G04 ================== begin FILE IDENTIFICATION RECORD ==================*
G04 Layout Name:  15126-1b.brd*
G04 Film Name:    DP_REF_L1*
G04 File Format:  Gerber RS274X*
G04 File Origin:  Cadence Allegro 16.6-2015-S079*
G04 Origin Date:  Fri Feb 10 17:23:32 2017*
G04 *
G04 Layer:  BOARD GEOMETRY/PANEL_OUTLINE*
G04 Layer:  BOARD GEOMETRY/DP_REF_L1_TBL*
G04 Layer:  BOARD GEOMETRY/DP_REF_L1_TOP*
G04 *
G04 Offset:    (0.00 0.00)*
G04 Mirror:    No*
G04 Mode:      Positive*
G04 Rotation:  0*
G04 FullContactRelief:  No*
G04 UndefLineWidth:     6.00*
G04 ================== end FILE IDENTIFICATION RECORD ====================*
%FSLAX35Y35*MOIN*%
%IR0*IPPOS*OFA0.00000B0.00000*MIA0B0*SFA1.00000B1.00000*%
%ADD10C,.02*%
%ADD11C,.006*%
%ADD12C,.0045*%
%ADD13C,.0046*%
%ADD14C,.0065*%
%ADD15C,.00395*%
G75*
%LPD*%
G75*
G54D10*
G01X2026678Y631398D02*
Y458148D01*
G01D02*
X2814178D01*
G01X2026678Y492798D02*
X2814178D01*
G01X2026678Y527448D02*
X2814178D01*
G01X2026678Y562098D02*
X2814178D01*
G01X2026678Y596748D02*
X2814178D01*
G01X2026678Y631398D02*
X2814178D01*
G01X2201678D02*
Y458148D01*
G01X2499178Y631398D02*
Y458148D01*
G01X2604178Y631398D02*
Y458148D01*
G01X2814178Y631398D02*
Y458148D01*
G54D11*
G01X-17372Y-95792D02*
Y-113292D01*
G01X-22394Y-95792D02*
X-12350D01*
G01X-3584Y-113292D02*
Y-95792D01*
G01Y-104250D02*
X-2492Y-102792D01*
X-1400Y-101917D01*
X346Y-101626D01*
X1656Y-101917D01*
X3185Y-103084D01*
X3840Y-104834D01*
Y-113292D01*
G01X17628Y-101626D02*
Y-113292D01*
G01Y-96959D02*
X17191Y-96667D01*
Y-96084D01*
X17628Y-95792D01*
X18065Y-96084D01*
Y-96667D01*
X17628Y-96959D01*
G01X31853Y-111251D02*
X32945Y-112417D01*
X34473Y-113292D01*
X35783D01*
X37093Y-112709D01*
X37966Y-111834D01*
X38403Y-110668D01*
X38185Y-108917D01*
X37311Y-108042D01*
X33381Y-106292D01*
X32508Y-104250D01*
X32945Y-102792D01*
X33818Y-101917D01*
X35128Y-101626D01*
X36438Y-101917D01*
X37748Y-102792D01*
G01X67071Y-117667D02*
X68600Y-118834D01*
X70346Y-119125D01*
X71874Y-118834D01*
X73185Y-117376D01*
X74058Y-115334D01*
Y-101626D01*
G01Y-103959D02*
X73185Y-102792D01*
X71874Y-101917D01*
X70346Y-101626D01*
X68600Y-102209D01*
X67508Y-103375D01*
X66634Y-105417D01*
X66198Y-107459D01*
X66416Y-109209D01*
X67290Y-111251D01*
X68600Y-112709D01*
X70346Y-113292D01*
X71656Y-113000D01*
X73185Y-111834D01*
X74058Y-110668D01*
G01X84353Y-105417D02*
X91340D01*
X90685Y-103375D01*
X89593Y-102209D01*
X88065Y-101626D01*
X86536Y-101917D01*
X85226Y-102792D01*
X84353Y-104834D01*
X83916Y-106584D01*
Y-108334D01*
X84353Y-110084D01*
X85445Y-111834D01*
X86755Y-113000D01*
X88283Y-113292D01*
X89811Y-112709D01*
X91340Y-110959D01*
G01X102071Y-113292D02*
Y-101626D01*
G01Y-103959D02*
X103163Y-102792D01*
X104255Y-101917D01*
X105783Y-101626D01*
X106874Y-101917D01*
X108185Y-102792D01*
G01X118698Y-113292D02*
Y-95792D01*
G01Y-104542D02*
X119790Y-102792D01*
X121100Y-101917D01*
X122410Y-101626D01*
X124374Y-102209D01*
X125685Y-103375D01*
X126558Y-105417D01*
Y-107750D01*
X126121Y-110084D01*
X125248Y-111834D01*
X123720Y-113000D01*
X122410Y-113292D01*
X121100Y-113000D01*
X119790Y-112126D01*
X118698Y-110668D01*
G01X136853Y-105417D02*
X143840D01*
X143185Y-103375D01*
X142093Y-102209D01*
X140565Y-101626D01*
X139036Y-101917D01*
X137726Y-102792D01*
X136853Y-104834D01*
X136416Y-106584D01*
Y-108334D01*
X136853Y-110084D01*
X137945Y-111834D01*
X139255Y-113000D01*
X140783Y-113292D01*
X142311Y-112709D01*
X143840Y-110959D01*
G01X154571Y-113292D02*
Y-101626D01*
G01Y-103959D02*
X155663Y-102792D01*
X156755Y-101917D01*
X158283Y-101626D01*
X159374Y-101917D01*
X160685Y-102792D01*
G01X192628Y-101626D02*
Y-113292D01*
G01Y-96959D02*
X192191Y-96667D01*
Y-96084D01*
X192628Y-95792D01*
X193065Y-96084D01*
Y-96667D01*
X192628Y-96959D01*
G01X206853Y-111251D02*
X207945Y-112417D01*
X209473Y-113292D01*
X210783D01*
X212093Y-112709D01*
X212966Y-111834D01*
X213403Y-110668D01*
X213185Y-108917D01*
X212311Y-108042D01*
X208381Y-106292D01*
X207508Y-104250D01*
X207945Y-102792D01*
X208818Y-101917D01*
X210128Y-101626D01*
X211438Y-101917D01*
X212748Y-102792D01*
G01X241634Y-117667D02*
X243163Y-118834D01*
X244473Y-119125D01*
X246220Y-118542D01*
X247530Y-117084D01*
X248185Y-114458D01*
Y-101626D01*
G01Y-96959D02*
X247748Y-96667D01*
Y-96084D01*
X248185Y-95792D01*
X248621Y-96084D01*
Y-96667D01*
X248185Y-96959D01*
G01X258916Y-101626D02*
Y-109792D01*
X259790Y-111834D01*
X261100Y-113000D01*
X262628Y-113292D01*
X264156Y-113000D01*
X265466Y-111834D01*
X266340Y-109792D01*
G01Y-113292D02*
Y-101626D01*
G01X276853Y-111251D02*
X277945Y-112417D01*
X279473Y-113292D01*
X280783D01*
X282093Y-112709D01*
X282966Y-111834D01*
X283403Y-110668D01*
X283185Y-108917D01*
X282311Y-108042D01*
X278381Y-106292D01*
X277508Y-104250D01*
X277945Y-102792D01*
X278818Y-101917D01*
X280128Y-101626D01*
X281438Y-101917D01*
X282748Y-102792D01*
G01X297628Y-95792D02*
Y-113292D01*
G01X294571Y-101626D02*
X300685D01*
G01X331318Y-113292D02*
Y-98417D01*
X331755Y-96959D01*
X332628Y-96084D01*
X333938Y-95792D01*
X335248Y-96375D01*
X335903Y-97834D01*
G01X333283Y-102792D02*
X328916D01*
G01X350128Y-113292D02*
X348818Y-113000D01*
X347508Y-111834D01*
X346634Y-109792D01*
X346198Y-107459D01*
X346634Y-105125D01*
X347508Y-103084D01*
X348818Y-101917D01*
X350128Y-101626D01*
X351438Y-101917D01*
X352748Y-103084D01*
X353621Y-105125D01*
X353840Y-107459D01*
X353621Y-109792D01*
X352748Y-111834D01*
X351438Y-113000D01*
X350128Y-113292D01*
G01X364571D02*
Y-101626D01*
G01Y-103959D02*
X365663Y-102792D01*
X366755Y-101917D01*
X368283Y-101626D01*
X369374Y-101917D01*
X370685Y-102792D01*
G01X398043Y-118542D02*
X399353Y-119125D01*
X401100Y-118542D01*
X402191Y-117376D01*
X403065Y-115917D01*
X404374Y-111251D01*
X407213Y-101626D01*
G01X400226D02*
X404374Y-111251D01*
G01X420128Y-113292D02*
X418818Y-113000D01*
X417508Y-111834D01*
X416634Y-109792D01*
X416198Y-107459D01*
X416634Y-105125D01*
X417508Y-103084D01*
X418818Y-101917D01*
X420128Y-101626D01*
X421438Y-101917D01*
X422748Y-103084D01*
X423621Y-105125D01*
X423840Y-107459D01*
X423621Y-109792D01*
X422748Y-111834D01*
X421438Y-113000D01*
X420128Y-113292D01*
G01X433916Y-101626D02*
Y-109792D01*
X434790Y-111834D01*
X436100Y-113000D01*
X437628Y-113292D01*
X439156Y-113000D01*
X440466Y-111834D01*
X441340Y-109792D01*
G01Y-113292D02*
Y-101626D01*
G01X452071Y-113292D02*
Y-101626D01*
G01Y-103959D02*
X453163Y-102792D01*
X454255Y-101917D01*
X455783Y-101626D01*
X456874Y-101917D01*
X458185Y-102792D01*
G01X487071Y-113292D02*
Y-101626D01*
G01Y-103959D02*
X488163Y-102792D01*
X489255Y-101917D01*
X490783Y-101626D01*
X491874Y-101917D01*
X493185Y-102792D01*
G01X504353Y-105417D02*
X511340D01*
X510685Y-103375D01*
X509593Y-102209D01*
X508065Y-101626D01*
X506536Y-101917D01*
X505226Y-102792D01*
X504353Y-104834D01*
X503916Y-106584D01*
Y-108334D01*
X504353Y-110084D01*
X505445Y-111834D01*
X506755Y-113000D01*
X508283Y-113292D01*
X509811Y-112709D01*
X511340Y-110959D01*
G01X523818Y-113292D02*
Y-98417D01*
X524255Y-96959D01*
X525128Y-96084D01*
X526438Y-95792D01*
X527748Y-96375D01*
X528403Y-97834D01*
G01X525783Y-102792D02*
X521416D01*
G01X539353Y-105417D02*
X546340D01*
X545685Y-103375D01*
X544593Y-102209D01*
X543065Y-101626D01*
X541536Y-101917D01*
X540226Y-102792D01*
X539353Y-104834D01*
X538916Y-106584D01*
Y-108334D01*
X539353Y-110084D01*
X540445Y-111834D01*
X541755Y-113000D01*
X543283Y-113292D01*
X544811Y-112709D01*
X546340Y-110959D01*
G01X557071Y-113292D02*
Y-101626D01*
G01Y-103959D02*
X558163Y-102792D01*
X559255Y-101917D01*
X560783Y-101626D01*
X561874Y-101917D01*
X563185Y-102792D01*
G01X574353Y-105417D02*
X581340D01*
X580685Y-103375D01*
X579593Y-102209D01*
X578065Y-101626D01*
X576536Y-101917D01*
X575226Y-102792D01*
X574353Y-104834D01*
X573916Y-106584D01*
Y-108334D01*
X574353Y-110084D01*
X575445Y-111834D01*
X576755Y-113000D01*
X578283Y-113292D01*
X579811Y-112709D01*
X581340Y-110959D01*
G01X591416Y-113292D02*
Y-101626D01*
G01Y-104542D02*
X592290Y-103084D01*
X593600Y-101917D01*
X595346Y-101626D01*
X596874Y-101917D01*
X598185Y-103084D01*
X598840Y-105125D01*
Y-113292D01*
G01X616121Y-103084D02*
X614593Y-101917D01*
X613283Y-101626D01*
X611536Y-102209D01*
X610226Y-103375D01*
X609353Y-105417D01*
X609134Y-107459D01*
X609353Y-109501D01*
X610226Y-111251D01*
X611536Y-112709D01*
X613283Y-113292D01*
X614811Y-112709D01*
X616121Y-111542D01*
G01X626853Y-105417D02*
X633840D01*
X633185Y-103375D01*
X632093Y-102209D01*
X630565Y-101626D01*
X629036Y-101917D01*
X627726Y-102792D01*
X626853Y-104834D01*
X626416Y-106584D01*
Y-108334D01*
X626853Y-110084D01*
X627945Y-111834D01*
X629255Y-113000D01*
X630783Y-113292D01*
X632311Y-112709D01*
X633840Y-110959D01*
G01X665128Y-95792D02*
Y-113292D01*
G01X662071Y-101626D02*
X668185D01*
G01X682628Y-113292D02*
X681318Y-113000D01*
X680008Y-111834D01*
X679134Y-109792D01*
X678698Y-107459D01*
X679134Y-105125D01*
X680008Y-103084D01*
X681318Y-101917D01*
X682628Y-101626D01*
X683938Y-101917D01*
X685248Y-103084D01*
X686121Y-105125D01*
X686340Y-107459D01*
X686121Y-109792D01*
X685248Y-111834D01*
X683938Y-113000D01*
X682628Y-113292D01*
G01X716318D02*
Y-98417D01*
X716755Y-96959D01*
X717628Y-96084D01*
X718938Y-95792D01*
X720248Y-96375D01*
X720903Y-97834D01*
G01X718283Y-102792D02*
X713916D01*
G01X735128Y-101626D02*
Y-113292D01*
G01Y-96959D02*
X734691Y-96667D01*
Y-96084D01*
X735128Y-95792D01*
X735565Y-96084D01*
Y-96667D01*
X735128Y-96959D01*
G01X748916Y-113292D02*
Y-101626D01*
G01Y-104542D02*
X749790Y-103084D01*
X751100Y-101917D01*
X752846Y-101626D01*
X754374Y-101917D01*
X755685Y-103084D01*
X756340Y-105125D01*
Y-113292D01*
G01X774058Y-95792D02*
Y-113292D01*
G01Y-110668D02*
X773185Y-112126D01*
X771874Y-113000D01*
X770346Y-113292D01*
X768600Y-112709D01*
X767290Y-111251D01*
X766416Y-109501D01*
X766198Y-107459D01*
X766416Y-105417D01*
X767290Y-103667D01*
X768600Y-102209D01*
X770346Y-101626D01*
X771874Y-101917D01*
X772966Y-102501D01*
X774058Y-103667D01*
G01X805128Y-95792D02*
Y-113292D01*
G01X802071Y-101626D02*
X808185D01*
G01X818916Y-113292D02*
Y-95792D01*
G01Y-104250D02*
X820008Y-102792D01*
X821100Y-101917D01*
X822846Y-101626D01*
X824156Y-101917D01*
X825685Y-103084D01*
X826340Y-104834D01*
Y-113292D01*
G01X836853Y-105417D02*
X843840D01*
X843185Y-103375D01*
X842093Y-102209D01*
X840565Y-101626D01*
X839036Y-101917D01*
X837726Y-102792D01*
X836853Y-104834D01*
X836416Y-106584D01*
Y-108334D01*
X836853Y-110084D01*
X837945Y-111834D01*
X839255Y-113000D01*
X840783Y-113292D01*
X842311Y-112709D01*
X843840Y-110959D01*
G01X870325Y-113292D02*
Y-95792D01*
X874691D01*
X876438Y-96667D01*
X877748Y-97834D01*
X878840Y-99583D01*
X879713Y-101626D01*
X879931Y-104542D01*
X879713Y-107459D01*
X878840Y-109501D01*
X877748Y-111251D01*
X876438Y-112417D01*
X874691Y-113292D01*
X870325D01*
G01X888261D02*
Y-95792D01*
X893501D01*
X895248Y-96667D01*
X896558Y-98709D01*
X896995Y-101042D01*
X896558Y-103375D01*
X895466Y-105125D01*
X893501Y-106001D01*
X888261D01*
G01X927628Y-101626D02*
Y-113292D01*
G01Y-96959D02*
X927191Y-96667D01*
Y-96084D01*
X927628Y-95792D01*
X928065Y-96084D01*
Y-96667D01*
X927628Y-96959D01*
G01X938578Y-113292D02*
Y-101626D01*
G01Y-104834D02*
X939233Y-103375D01*
X940325Y-102209D01*
X941853Y-101626D01*
X943381Y-102209D01*
X944473Y-103375D01*
X945128Y-104834D01*
Y-113292D01*
G01Y-104834D02*
X945783Y-103375D01*
X946874Y-102209D01*
X948403Y-101626D01*
X949931Y-102209D01*
X951023Y-103375D01*
X951678Y-105125D01*
Y-113292D01*
G01X958698Y-119125D02*
Y-101626D01*
G01Y-104250D02*
X959790Y-102792D01*
X960881Y-101917D01*
X962628Y-101626D01*
X964156Y-101917D01*
X965685Y-103375D01*
X966340Y-105417D01*
X966558Y-107459D01*
X966340Y-109501D01*
X965685Y-111542D01*
X964374Y-112709D01*
X962628Y-113292D01*
X961100Y-113000D01*
X959571Y-112126D01*
X958698Y-110959D01*
G01X976853Y-105417D02*
X983840D01*
X983185Y-103375D01*
X982093Y-102209D01*
X980565Y-101626D01*
X979036Y-101917D01*
X977726Y-102792D01*
X976853Y-104834D01*
X976416Y-106584D01*
Y-108334D01*
X976853Y-110084D01*
X977945Y-111834D01*
X979255Y-113000D01*
X980783Y-113292D01*
X982311Y-112709D01*
X983840Y-110959D01*
G01X1001558Y-95792D02*
Y-113292D01*
G01Y-110668D02*
X1000685Y-112126D01*
X999374Y-113000D01*
X997846Y-113292D01*
X996100Y-112709D01*
X994790Y-111251D01*
X993916Y-109501D01*
X993698Y-107459D01*
X993916Y-105417D01*
X994790Y-103667D01*
X996100Y-102209D01*
X997846Y-101626D01*
X999374Y-101917D01*
X1000466Y-102501D01*
X1001558Y-103667D01*
G01X1019058Y-113292D02*
Y-101626D01*
G01Y-103667D02*
X1018185Y-102501D01*
X1016874Y-101917D01*
X1015346Y-101626D01*
X1013818Y-102209D01*
X1012508Y-103375D01*
X1011634Y-105125D01*
X1011198Y-107459D01*
X1011634Y-109792D01*
X1012508Y-111542D01*
X1013818Y-112709D01*
X1015346Y-113292D01*
X1016874Y-113000D01*
X1018185Y-112126D01*
X1019058Y-110959D01*
G01X1028916Y-113292D02*
Y-101626D01*
G01Y-104542D02*
X1029790Y-103084D01*
X1031100Y-101917D01*
X1032846Y-101626D01*
X1034374Y-101917D01*
X1035685Y-103084D01*
X1036340Y-105125D01*
Y-113292D01*
G01X1053621Y-103084D02*
X1052093Y-101917D01*
X1050783Y-101626D01*
X1049036Y-102209D01*
X1047726Y-103375D01*
X1046853Y-105417D01*
X1046634Y-107459D01*
X1046853Y-109501D01*
X1047726Y-111251D01*
X1049036Y-112709D01*
X1050783Y-113292D01*
X1052311Y-112709D01*
X1053621Y-111542D01*
G01X1064353Y-105417D02*
X1071340D01*
X1070685Y-103375D01*
X1069593Y-102209D01*
X1068065Y-101626D01*
X1066536Y-101917D01*
X1065226Y-102792D01*
X1064353Y-104834D01*
X1063916Y-106584D01*
Y-108334D01*
X1064353Y-110084D01*
X1065445Y-111834D01*
X1066755Y-113000D01*
X1068283Y-113292D01*
X1069811Y-112709D01*
X1071340Y-110959D01*
G01X1102628Y-95792D02*
Y-113292D01*
G01X1099571Y-101626D02*
X1105685D01*
G01X1117071Y-113292D02*
Y-101626D01*
G01Y-103959D02*
X1118163Y-102792D01*
X1119255Y-101917D01*
X1120783Y-101626D01*
X1121874Y-101917D01*
X1123185Y-102792D01*
G01X1141558Y-113292D02*
Y-101626D01*
G01Y-103667D02*
X1140685Y-102501D01*
X1139374Y-101917D01*
X1137846Y-101626D01*
X1136318Y-102209D01*
X1135008Y-103375D01*
X1134134Y-105125D01*
X1133698Y-107459D01*
X1134134Y-109792D01*
X1135008Y-111542D01*
X1136318Y-112709D01*
X1137846Y-113292D01*
X1139374Y-113000D01*
X1140685Y-112126D01*
X1141558Y-110959D01*
G01X1158621Y-103084D02*
X1157093Y-101917D01*
X1155783Y-101626D01*
X1154036Y-102209D01*
X1152726Y-103375D01*
X1151853Y-105417D01*
X1151634Y-107459D01*
X1151853Y-109501D01*
X1152726Y-111251D01*
X1154036Y-112709D01*
X1155783Y-113292D01*
X1157311Y-112709D01*
X1158621Y-111542D01*
G01X1169353Y-105417D02*
X1176340D01*
X1175685Y-103375D01*
X1174593Y-102209D01*
X1173065Y-101626D01*
X1171536Y-101917D01*
X1170226Y-102792D01*
X1169353Y-104834D01*
X1168916Y-106584D01*
Y-108334D01*
X1169353Y-110084D01*
X1170445Y-111834D01*
X1171755Y-113000D01*
X1173283Y-113292D01*
X1174811Y-112709D01*
X1176340Y-110959D01*
G01X1186853Y-111251D02*
X1187945Y-112417D01*
X1189473Y-113292D01*
X1190783D01*
X1192093Y-112709D01*
X1192966Y-111834D01*
X1193403Y-110668D01*
X1193185Y-108917D01*
X1192311Y-108042D01*
X1188381Y-106292D01*
X1187508Y-104250D01*
X1187945Y-102792D01*
X1188818Y-101917D01*
X1190128Y-101626D01*
X1191438Y-101917D01*
X1192748Y-102792D01*
G01X1225128Y-101626D02*
Y-113292D01*
G01Y-96959D02*
X1224691Y-96667D01*
Y-96084D01*
X1225128Y-95792D01*
X1225565Y-96084D01*
Y-96667D01*
X1225128Y-96959D01*
G01X1238916Y-113292D02*
Y-101626D01*
G01Y-104542D02*
X1239790Y-103084D01*
X1241100Y-101917D01*
X1242846Y-101626D01*
X1244374Y-101917D01*
X1245685Y-103084D01*
X1246340Y-105125D01*
Y-113292D01*
G01X1277628D02*
Y-95792D01*
G01X1299058Y-113292D02*
Y-101626D01*
G01Y-103667D02*
X1298185Y-102501D01*
X1296874Y-101917D01*
X1295346Y-101626D01*
X1293818Y-102209D01*
X1292508Y-103375D01*
X1291634Y-105125D01*
X1291198Y-107459D01*
X1291634Y-109792D01*
X1292508Y-111542D01*
X1293818Y-112709D01*
X1295346Y-113292D01*
X1296874Y-113000D01*
X1298185Y-112126D01*
X1299058Y-110959D01*
G01X1308043Y-118542D02*
X1309353Y-119125D01*
X1311100Y-118542D01*
X1312191Y-117376D01*
X1313065Y-115917D01*
X1314374Y-111251D01*
X1317213Y-101626D01*
G01X1310226D02*
X1314374Y-111251D01*
G01X1326853Y-105417D02*
X1333840D01*
X1333185Y-103375D01*
X1332093Y-102209D01*
X1330565Y-101626D01*
X1329036Y-101917D01*
X1327726Y-102792D01*
X1326853Y-104834D01*
X1326416Y-106584D01*
Y-108334D01*
X1326853Y-110084D01*
X1327945Y-111834D01*
X1329255Y-113000D01*
X1330783Y-113292D01*
X1332311Y-112709D01*
X1333840Y-110959D01*
G01X1344571Y-113292D02*
Y-101626D01*
G01Y-103959D02*
X1345663Y-102792D01*
X1346755Y-101917D01*
X1348283Y-101626D01*
X1349374Y-101917D01*
X1350685Y-102792D01*
G01X1378261Y-95792D02*
Y-113292D01*
X1386995D01*
G01X1400128D02*
Y-95792D01*
X1397508Y-99292D01*
G01Y-113292D02*
X1402748D01*
G01X1417628Y-113875D02*
X1417191Y-113584D01*
Y-113000D01*
X1417628Y-112709D01*
X1418065Y-113000D01*
Y-113584D01*
X1417628Y-113875D01*
G01X2079178Y467898D02*
Y485398D01*
X2076558Y481898D01*
G01Y467898D02*
X2081798D01*
G01X2096678Y485398D02*
X2094931Y484815D01*
X2093621Y483356D01*
X2092748Y481607D01*
X2092093Y479273D01*
X2091875Y476648D01*
X2092093Y474023D01*
X2092748Y471689D01*
X2093621Y469939D01*
X2094931Y468481D01*
X2096678Y467898D01*
X2098424Y468481D01*
X2099735Y469939D01*
X2100608Y471689D01*
X2101263Y474023D01*
X2101481Y476648D01*
X2101263Y479273D01*
X2100608Y481607D01*
X2099735Y483356D01*
X2098424Y484815D01*
X2096678Y485398D01*
G01X2114178D02*
X2112431Y484815D01*
X2111121Y483356D01*
X2110248Y481607D01*
X2109593Y479273D01*
X2109375Y476648D01*
X2109593Y474023D01*
X2110248Y471689D01*
X2111121Y469939D01*
X2112431Y468481D01*
X2114178Y467898D01*
X2115924Y468481D01*
X2117235Y469939D01*
X2118108Y471689D01*
X2118763Y474023D01*
X2118981Y476648D01*
X2118763Y479273D01*
X2118108Y481607D01*
X2117235Y483356D01*
X2115924Y484815D01*
X2114178Y485398D01*
G01X2131678Y467315D02*
X2131241Y467606D01*
Y468190D01*
X2131678Y468481D01*
X2132115Y468190D01*
Y467606D01*
X2131678Y467315D01*
G01X2149178Y485398D02*
X2147431Y484815D01*
X2146121Y483356D01*
X2145248Y481607D01*
X2144593Y479273D01*
X2144375Y476648D01*
X2144593Y474023D01*
X2145248Y471689D01*
X2146121Y469939D01*
X2147431Y468481D01*
X2149178Y467898D01*
X2150924Y468481D01*
X2152235Y469939D01*
X2153108Y471689D01*
X2153763Y474023D01*
X2153981Y476648D01*
X2153763Y479273D01*
X2153108Y481607D01*
X2152235Y483356D01*
X2150924Y484815D01*
X2149178Y485398D01*
G01X2084216Y504589D02*
X2085745Y503131D01*
X2087491Y502548D01*
X2089238Y503131D01*
X2090766Y504881D01*
X2091858Y507506D01*
X2092295Y510131D01*
Y513339D01*
X2091858Y515964D01*
X2090766Y518298D01*
X2089456Y519465D01*
X2087928Y520048D01*
X2086181Y519465D01*
X2084871Y518298D01*
X2083998Y516548D01*
X2083561Y514214D01*
X2083998Y512173D01*
X2085090Y510131D01*
X2086400Y508964D01*
X2087928Y508673D01*
X2089674Y509256D01*
X2090985Y510715D01*
X2092295Y513339D01*
G01X2100625Y505172D02*
X2101934Y503714D01*
X2103463Y502840D01*
X2105428Y502548D01*
X2107393Y503131D01*
X2108921Y504298D01*
X2110013Y506339D01*
X2110231Y508673D01*
X2109795Y511006D01*
X2108703Y512465D01*
X2107174Y513631D01*
X2105646Y513923D01*
X2104118Y513631D01*
X2102153Y512465D01*
X2102808Y520048D01*
X2108703D01*
G01X2122928Y501965D02*
X2122491Y502256D01*
Y502840D01*
X2122928Y503131D01*
X2123365Y502840D01*
Y502256D01*
X2122928Y501965D01*
G01X2140428Y520048D02*
X2138681Y519465D01*
X2137371Y518006D01*
X2136498Y516257D01*
X2135843Y513923D01*
X2135625Y511298D01*
X2135843Y508673D01*
X2136498Y506339D01*
X2137371Y504589D01*
X2138681Y503131D01*
X2140428Y502548D01*
X2142174Y503131D01*
X2143485Y504589D01*
X2144358Y506339D01*
X2145013Y508673D01*
X2145231Y511298D01*
X2145013Y513923D01*
X2144358Y516257D01*
X2143485Y518006D01*
X2142174Y519465D01*
X2140428Y520048D01*
G01X2087928Y537198D02*
X2089456Y537490D01*
X2091203Y538364D01*
X2092295Y539822D01*
X2092731Y541865D01*
X2092295Y543906D01*
X2090985Y545656D01*
X2089020Y546531D01*
X2086836D01*
X2085526Y547115D01*
X2084434Y548573D01*
X2083998Y550614D01*
X2084653Y552656D01*
X2086181Y554115D01*
X2087928Y554698D01*
X2089674Y554115D01*
X2091203Y552656D01*
X2091858Y550614D01*
X2091421Y548573D01*
X2090330Y547115D01*
X2089020Y546531D01*
X2086836D01*
X2084871Y545656D01*
X2083561Y543906D01*
X2083125Y541865D01*
X2083561Y539822D01*
X2084653Y538364D01*
X2086400Y537490D01*
X2087928Y537198D01*
G01X2100625Y539822D02*
X2101934Y538364D01*
X2103463Y537490D01*
X2105428Y537198D01*
X2107393Y537781D01*
X2108921Y538948D01*
X2110013Y540989D01*
X2110231Y543323D01*
X2109795Y545656D01*
X2108703Y547115D01*
X2107174Y548281D01*
X2105646Y548573D01*
X2104118Y548281D01*
X2102153Y547115D01*
X2102808Y554698D01*
X2108703D01*
G01X2122928Y536615D02*
X2122491Y536906D01*
Y537490D01*
X2122928Y537781D01*
X2123365Y537490D01*
Y536906D01*
X2122928Y536615D01*
G01X2140428Y554698D02*
X2138681Y554115D01*
X2137371Y552656D01*
X2136498Y550907D01*
X2135843Y548573D01*
X2135625Y545948D01*
X2135843Y543323D01*
X2136498Y540989D01*
X2137371Y539239D01*
X2138681Y537781D01*
X2140428Y537198D01*
X2142174Y537781D01*
X2143485Y539239D01*
X2144358Y540989D01*
X2145013Y543323D01*
X2145231Y545948D01*
X2145013Y548573D01*
X2144358Y550907D01*
X2143485Y552656D01*
X2142174Y554115D01*
X2140428Y554698D01*
G01X2087491Y571848D02*
X2087928Y575639D01*
X2088583Y578848D01*
X2089456Y581765D01*
X2090548Y584973D01*
X2092295Y589348D01*
X2083561D01*
G01X2100625Y575348D02*
X2101934Y573306D01*
X2103681Y572140D01*
X2105646Y571848D01*
X2107393Y572140D01*
X2109140Y573598D01*
X2110231Y575348D01*
X2110450Y577098D01*
X2110013Y579139D01*
X2108485Y580598D01*
X2106956Y581181D01*
X2104991D01*
G01X2106956D02*
X2108266Y582056D01*
X2109358Y583514D01*
X2109795Y585264D01*
X2109358Y587015D01*
X2108266Y588473D01*
X2106301Y589348D01*
X2104336Y589056D01*
X2102371Y587889D01*
G01X2122928Y571265D02*
X2122491Y571556D01*
Y572140D01*
X2122928Y572431D01*
X2123365Y572140D01*
Y571556D01*
X2122928Y571265D01*
G01X2140428Y589348D02*
X2138681Y588765D01*
X2137371Y587306D01*
X2136498Y585557D01*
X2135843Y583223D01*
X2135625Y580598D01*
X2135843Y577973D01*
X2136498Y575639D01*
X2137371Y573889D01*
X2138681Y572431D01*
X2140428Y571848D01*
X2142174Y572431D01*
X2143485Y573889D01*
X2144358Y575639D01*
X2145013Y577973D01*
X2145231Y580598D01*
X2145013Y583223D01*
X2144358Y585557D01*
X2143485Y587306D01*
X2142174Y588765D01*
X2140428Y589348D01*
G01X2050308Y623998D02*
X2055548D01*
G01X2052928D02*
Y606498D01*
G01X2050308D02*
X2055548D01*
G01X2064751D02*
Y623998D01*
X2070428Y609415D01*
X2076105Y623998D01*
Y606498D01*
G01X2083561D02*
Y623998D01*
X2088801D01*
X2090548Y623123D01*
X2091858Y621081D01*
X2092295Y618748D01*
X2091858Y616415D01*
X2090766Y614665D01*
X2088801Y613789D01*
X2083561D01*
G01X2104336Y600665D02*
X2102153Y603581D01*
X2101061Y606498D01*
Y618164D01*
X2102153Y621081D01*
X2104336Y623998D01*
G01X2122928Y606498D02*
X2121181Y606790D01*
X2119653Y607956D01*
X2118343Y609706D01*
X2117469Y611748D01*
X2117033Y614081D01*
Y616415D01*
X2117469Y618748D01*
X2118343Y620790D01*
X2119653Y622539D01*
X2121181Y623706D01*
X2122928Y623998D01*
X2124674Y623706D01*
X2126203Y622539D01*
X2127513Y620790D01*
X2128387Y618748D01*
X2128823Y616415D01*
Y614081D01*
X2128387Y611748D01*
X2127513Y609706D01*
X2126203Y607956D01*
X2124674Y606790D01*
X2122928Y606498D01*
G01X2136716D02*
Y623998D01*
G01Y615540D02*
X2137808Y616998D01*
X2138900Y617873D01*
X2140646Y618164D01*
X2141956Y617873D01*
X2143485Y616706D01*
X2144140Y614956D01*
Y606498D01*
G01X2151378D02*
Y618164D01*
G01Y614956D02*
X2152033Y616415D01*
X2153125Y617581D01*
X2154653Y618164D01*
X2156181Y617581D01*
X2157273Y616415D01*
X2157928Y614956D01*
Y606498D01*
G01Y614956D02*
X2158583Y616415D01*
X2159674Y617581D01*
X2161203Y618164D01*
X2162731Y617581D01*
X2163823Y616415D01*
X2164478Y614665D01*
Y606498D01*
G01X2176520Y600665D02*
X2178703Y603581D01*
X2179795Y606498D01*
Y618164D01*
X2178703Y621081D01*
X2176520Y623998D01*
G01X2028425Y641148D02*
Y658648D01*
X2032791D01*
X2034538Y657773D01*
X2035848Y656606D01*
X2036940Y654857D01*
X2037813Y652814D01*
X2038031Y649898D01*
X2037813Y646981D01*
X2036940Y644939D01*
X2035848Y643189D01*
X2034538Y642023D01*
X2032791Y641148D01*
X2028425D01*
G01X2046361D02*
Y658648D01*
X2051601D01*
X2053348Y657773D01*
X2054658Y655731D01*
X2055095Y653398D01*
X2054658Y651065D01*
X2053566Y649315D01*
X2051601Y648439D01*
X2046361D01*
G01X2083108Y658648D02*
X2088348D01*
G01X2085728D02*
Y641148D01*
G01X2083108D02*
X2088348D01*
G01X2097551D02*
Y658648D01*
X2103228Y644065D01*
X2108905Y658648D01*
Y641148D01*
G01X2116361D02*
Y658648D01*
X2121601D01*
X2123348Y657773D01*
X2124658Y655731D01*
X2125095Y653398D01*
X2124658Y651065D01*
X2123566Y649315D01*
X2121601Y648439D01*
X2116361D01*
G01X2142595Y641148D02*
X2133861D01*
Y658648D01*
X2142595D01*
G01X2139101Y650190D02*
X2133861D01*
G01X2150925Y641148D02*
Y658648D01*
X2155291D01*
X2157038Y657773D01*
X2158348Y656606D01*
X2159440Y654857D01*
X2160313Y652814D01*
X2160531Y649898D01*
X2160313Y646981D01*
X2159440Y644939D01*
X2158348Y643189D01*
X2157038Y642023D01*
X2155291Y641148D01*
X2150925D01*
G01X2167769D02*
X2173228Y658648D01*
X2178687Y641148D01*
G01X2176721Y647273D02*
X2169734D01*
G01X2185706Y641148D02*
Y658648D01*
X2195750Y641148D01*
Y658648D01*
G01X2213031Y657189D02*
X2211721Y658065D01*
X2210193Y658648D01*
X2208446D01*
X2206481Y657773D01*
X2204953Y656315D01*
X2203861Y654564D01*
X2202988Y651648D01*
X2202769Y649023D01*
X2203206Y646398D01*
X2203861Y644648D01*
X2205171Y642898D01*
X2206700Y641731D01*
X2208228Y641148D01*
X2209756D01*
X2211285Y641731D01*
X2212595Y642606D01*
X2213687Y643772D01*
G01X2230095Y641148D02*
X2221361D01*
Y658648D01*
X2230095D01*
G01X2226601Y650190D02*
X2221361D01*
G01X2260728Y658648D02*
Y641148D01*
G01X2255706Y658648D02*
X2265750D01*
G01X2272769Y641148D02*
X2278228Y658648D01*
X2283687Y641148D01*
G01X2281721Y647273D02*
X2274734D01*
G01X2297474Y650481D02*
X2298348Y651356D01*
X2299003Y652814D01*
X2299440Y654857D01*
X2299003Y656606D01*
X2298130Y657773D01*
X2296601Y658648D01*
X2290706D01*
Y641148D01*
X2297911D01*
X2299440Y642314D01*
X2300313Y644065D01*
X2300750Y646106D01*
X2300313Y648148D01*
X2299003Y649898D01*
X2297474Y650481D01*
X2290706D01*
G01X2308861Y658648D02*
Y641148D01*
X2317595D01*
G01X2335095D02*
X2326361D01*
Y658648D01*
X2335095D01*
G01X2331601Y650190D02*
X2326361D01*
G01X2348228Y640565D02*
X2347791Y640856D01*
Y641440D01*
X2348228Y641731D01*
X2348665Y641440D01*
Y640856D01*
X2348228Y640565D01*
G01Y648439D02*
X2347791Y648731D01*
Y649315D01*
X2348228Y649606D01*
X2348665Y649315D01*
Y648731D01*
X2348228Y648439D01*
G01X2378861Y658648D02*
Y641148D01*
X2387595D01*
G01X2400728D02*
Y658648D01*
X2398108Y655148D01*
G01Y641148D02*
X2403348D01*
G01X2266875Y471398D02*
X2268184Y469356D01*
X2269931Y468190D01*
X2271896Y467898D01*
X2273643Y468190D01*
X2275390Y469648D01*
X2276481Y471398D01*
X2276700Y473148D01*
X2276263Y475189D01*
X2274735Y476648D01*
X2273206Y477231D01*
X2271241D01*
G01X2273206D02*
X2274516Y478106D01*
X2275608Y479564D01*
X2276045Y481314D01*
X2275608Y483065D01*
X2274516Y484523D01*
X2272551Y485398D01*
X2270586Y485106D01*
X2268621Y483939D01*
G01X2289178Y467315D02*
X2288741Y467606D01*
Y468190D01*
X2289178Y468481D01*
X2289615Y468190D01*
Y467606D01*
X2289178Y467315D01*
G01X2302966Y469939D02*
X2304495Y468481D01*
X2306241Y467898D01*
X2307988Y468481D01*
X2309516Y470231D01*
X2310608Y472856D01*
X2311045Y475481D01*
Y478689D01*
X2310608Y481314D01*
X2309516Y483648D01*
X2308206Y484815D01*
X2306678Y485398D01*
X2304931Y484815D01*
X2303621Y483648D01*
X2302748Y481898D01*
X2302311Y479564D01*
X2302748Y477523D01*
X2303840Y475481D01*
X2305150Y474314D01*
X2306678Y474023D01*
X2308424Y474606D01*
X2309735Y476065D01*
X2311045Y478689D01*
G01X2319375Y470522D02*
X2320684Y469064D01*
X2322213Y468190D01*
X2324178Y467898D01*
X2326143Y468481D01*
X2327671Y469648D01*
X2328763Y471689D01*
X2328981Y474023D01*
X2328545Y476356D01*
X2327453Y477815D01*
X2325924Y478981D01*
X2324396Y479273D01*
X2322868Y478981D01*
X2320903Y477815D01*
X2321558Y485398D01*
X2327453D01*
G01X2337748Y467315D02*
X2345608Y485398D01*
G01X2359178Y467898D02*
Y485398D01*
X2356558Y481898D01*
G01Y467898D02*
X2361798D01*
G01X2379298D02*
Y485398D01*
X2371219Y472856D01*
X2382137D01*
G01X2394178Y467315D02*
X2393741Y467606D01*
Y468190D01*
X2394178Y468481D01*
X2394615Y468190D01*
Y467606D01*
X2394178Y467315D01*
G01X2411678Y485398D02*
X2409931Y484815D01*
X2408621Y483356D01*
X2407748Y481607D01*
X2407093Y479273D01*
X2406875Y476648D01*
X2407093Y474023D01*
X2407748Y471689D01*
X2408621Y469939D01*
X2409931Y468481D01*
X2411678Y467898D01*
X2413424Y468481D01*
X2414735Y469939D01*
X2415608Y471689D01*
X2416263Y474023D01*
X2416481Y476648D01*
X2416263Y479273D01*
X2415608Y481607D01*
X2414735Y483356D01*
X2413424Y484815D01*
X2411678Y485398D01*
G01X2424375Y470522D02*
X2425684Y469064D01*
X2427213Y468190D01*
X2429178Y467898D01*
X2431143Y468481D01*
X2432671Y469648D01*
X2433763Y471689D01*
X2433981Y474023D01*
X2433545Y476356D01*
X2432453Y477815D01*
X2430924Y478981D01*
X2429396Y479273D01*
X2427868Y478981D01*
X2425903Y477815D01*
X2426558Y485398D01*
X2432453D01*
G01X2256378Y623998D02*
X2259434Y606498D01*
X2262928Y623998D01*
X2266421Y606498D01*
X2269478Y623998D01*
G01X2277808D02*
X2283048D01*
G01X2280428D02*
Y606498D01*
G01X2277808D02*
X2283048D01*
G01X2293125D02*
Y623998D01*
X2297491D01*
X2299238Y623123D01*
X2300548Y621956D01*
X2301640Y620207D01*
X2302513Y618164D01*
X2302731Y615248D01*
X2302513Y612331D01*
X2301640Y610289D01*
X2300548Y608539D01*
X2299238Y607373D01*
X2297491Y606498D01*
X2293125D01*
G01X2315428Y623998D02*
Y606498D01*
G01X2310406Y623998D02*
X2320450D01*
G01X2328343Y606498D02*
Y623998D01*
G01X2337513D02*
Y606498D01*
G01Y615248D02*
X2328343D01*
G01X2349336Y600665D02*
X2347153Y603581D01*
X2346061Y606498D01*
Y618164D01*
X2347153Y621081D01*
X2349336Y623998D01*
G01X2361378Y606498D02*
Y618164D01*
G01Y614956D02*
X2362033Y616415D01*
X2363125Y617581D01*
X2364653Y618164D01*
X2366181Y617581D01*
X2367273Y616415D01*
X2367928Y614956D01*
Y606498D01*
G01Y614956D02*
X2368583Y616415D01*
X2369674Y617581D01*
X2371203Y618164D01*
X2372731Y617581D01*
X2373823Y616415D01*
X2374478Y614665D01*
Y606498D01*
G01X2385428Y618164D02*
Y606498D01*
G01Y622831D02*
X2384991Y623123D01*
Y623706D01*
X2385428Y623998D01*
X2385865Y623706D01*
Y623123D01*
X2385428Y622831D01*
G01X2402928Y606498D02*
Y623998D01*
G01X2417153Y608539D02*
X2418245Y607373D01*
X2419773Y606498D01*
X2421083D01*
X2422393Y607081D01*
X2423266Y607956D01*
X2423703Y609122D01*
X2423485Y610873D01*
X2422611Y611748D01*
X2418681Y613498D01*
X2417808Y615540D01*
X2418245Y616998D01*
X2419118Y617873D01*
X2420428Y618164D01*
X2421738Y617873D01*
X2423048Y616998D01*
G01X2439020Y600665D02*
X2441203Y603581D01*
X2442295Y606498D01*
Y618164D01*
X2441203Y621081D01*
X2439020Y623998D01*
G01X2291798Y502548D02*
Y520048D01*
X2283719Y507506D01*
X2294637D01*
G01X2306678Y501965D02*
X2306241Y502256D01*
Y502840D01*
X2306678Y503131D01*
X2307115Y502840D01*
Y502256D01*
X2306678Y501965D01*
G01X2320030Y509839D02*
X2321558Y511881D01*
X2322868Y513048D01*
X2324615Y513631D01*
X2326143Y513048D01*
X2327235Y511881D01*
X2328108Y510131D01*
X2328326Y508090D01*
X2328108Y506339D01*
X2327235Y504589D01*
X2325924Y503131D01*
X2324396Y502548D01*
X2322650Y503131D01*
X2321121Y504881D01*
X2320248Y507506D01*
X2320030Y510423D01*
X2320466Y514214D01*
X2321121Y516257D01*
X2322213Y518298D01*
X2323741Y519756D01*
X2325270Y520048D01*
X2326798Y519465D01*
X2327890Y518006D01*
G01X2337748Y501965D02*
X2345608Y520048D01*
G01X2359178Y502548D02*
Y520048D01*
X2356558Y516548D01*
G01Y502548D02*
X2361798D01*
G01X2371875Y506048D02*
X2373184Y504006D01*
X2374931Y502840D01*
X2376896Y502548D01*
X2378643Y502840D01*
X2380390Y504298D01*
X2381481Y506048D01*
X2381700Y507798D01*
X2381263Y509839D01*
X2379735Y511298D01*
X2378206Y511881D01*
X2376241D01*
G01X2378206D02*
X2379516Y512756D01*
X2380608Y514214D01*
X2381045Y515964D01*
X2380608Y517715D01*
X2379516Y519173D01*
X2377551Y520048D01*
X2375586Y519756D01*
X2373621Y518589D01*
G01X2394178Y501965D02*
X2393741Y502256D01*
Y502840D01*
X2394178Y503131D01*
X2394615Y502840D01*
Y502256D01*
X2394178Y501965D01*
G01X2406875Y505172D02*
X2408184Y503714D01*
X2409713Y502840D01*
X2411678Y502548D01*
X2413643Y503131D01*
X2415171Y504298D01*
X2416263Y506339D01*
X2416481Y508673D01*
X2416045Y511006D01*
X2414953Y512465D01*
X2413424Y513631D01*
X2411896Y513923D01*
X2410368Y513631D01*
X2408403Y512465D01*
X2409058Y520048D01*
X2414953D01*
G01X2300548Y537198D02*
Y554698D01*
X2292469Y542156D01*
X2303387D01*
G01X2315428Y536615D02*
X2314991Y536906D01*
Y537490D01*
X2315428Y537781D01*
X2315865Y537490D01*
Y536906D01*
X2315428Y536615D01*
G01X2328125Y539822D02*
X2329434Y538364D01*
X2330963Y537490D01*
X2332928Y537198D01*
X2334893Y537781D01*
X2336421Y538948D01*
X2337513Y540989D01*
X2337731Y543323D01*
X2337295Y545656D01*
X2336203Y547115D01*
X2334674Y548281D01*
X2333146Y548573D01*
X2331618Y548281D01*
X2329653Y547115D01*
X2330308Y554698D01*
X2336203D01*
G01X2346498Y536615D02*
X2354358Y554698D01*
G01X2363125Y539822D02*
X2364434Y538364D01*
X2365963Y537490D01*
X2367928Y537198D01*
X2369893Y537781D01*
X2371421Y538948D01*
X2372513Y540989D01*
X2372731Y543323D01*
X2372295Y545656D01*
X2371203Y547115D01*
X2369674Y548281D01*
X2368146Y548573D01*
X2366618Y548281D01*
X2364653Y547115D01*
X2365308Y554698D01*
X2371203D01*
G01X2385428Y536615D02*
X2384991Y536906D01*
Y537490D01*
X2385428Y537781D01*
X2385865Y537490D01*
Y536906D01*
X2385428Y536615D01*
G01X2402928Y554698D02*
X2401181Y554115D01*
X2399871Y552656D01*
X2398998Y550907D01*
X2398343Y548573D01*
X2398125Y545948D01*
X2398343Y543323D01*
X2398998Y540989D01*
X2399871Y539239D01*
X2401181Y537781D01*
X2402928Y537198D01*
X2404674Y537781D01*
X2405985Y539239D01*
X2406858Y540989D01*
X2407513Y543323D01*
X2407731Y545948D01*
X2407513Y548573D01*
X2406858Y550907D01*
X2405985Y552656D01*
X2404674Y554115D01*
X2402928Y554698D01*
G01X2293780Y579139D02*
X2295308Y581181D01*
X2296618Y582348D01*
X2298365Y582931D01*
X2299893Y582348D01*
X2300985Y581181D01*
X2301858Y579431D01*
X2302076Y577390D01*
X2301858Y575639D01*
X2300985Y573889D01*
X2299674Y572431D01*
X2298146Y571848D01*
X2296400Y572431D01*
X2294871Y574181D01*
X2293998Y576806D01*
X2293780Y579723D01*
X2294216Y583514D01*
X2294871Y585557D01*
X2295963Y587598D01*
X2297491Y589056D01*
X2299020Y589348D01*
X2300548Y588765D01*
X2301640Y587306D01*
G01X2315428Y571265D02*
X2314991Y571556D01*
Y572140D01*
X2315428Y572431D01*
X2315865Y572140D01*
Y571556D01*
X2315428Y571265D01*
G01X2328125Y574472D02*
X2329434Y573014D01*
X2330963Y572140D01*
X2332928Y571848D01*
X2334893Y572431D01*
X2336421Y573598D01*
X2337513Y575639D01*
X2337731Y577973D01*
X2337295Y580306D01*
X2336203Y581765D01*
X2334674Y582931D01*
X2333146Y583223D01*
X2331618Y582931D01*
X2329653Y581765D01*
X2330308Y589348D01*
X2336203D01*
G01X2346498Y571265D02*
X2354358Y589348D01*
G01X2363125Y574472D02*
X2364434Y573014D01*
X2365963Y572140D01*
X2367928Y571848D01*
X2369893Y572431D01*
X2371421Y573598D01*
X2372513Y575639D01*
X2372731Y577973D01*
X2372295Y580306D01*
X2371203Y581765D01*
X2369674Y582931D01*
X2368146Y583223D01*
X2366618Y582931D01*
X2364653Y581765D01*
X2365308Y589348D01*
X2371203D01*
G01X2385428Y571265D02*
X2384991Y571556D01*
Y572140D01*
X2385428Y572431D01*
X2385865Y572140D01*
Y571556D01*
X2385428Y571265D01*
G01X2402928Y589348D02*
X2401181Y588765D01*
X2399871Y587306D01*
X2398998Y585557D01*
X2398343Y583223D01*
X2398125Y580598D01*
X2398343Y577973D01*
X2398998Y575639D01*
X2399871Y573889D01*
X2401181Y572431D01*
X2402928Y571848D01*
X2404674Y572431D01*
X2405985Y573889D01*
X2406858Y575639D01*
X2407513Y577973D01*
X2407731Y580598D01*
X2407513Y583223D01*
X2406858Y585557D01*
X2405985Y587306D01*
X2404674Y588765D01*
X2402928Y589348D01*
G01X2538125Y467898D02*
Y485398D01*
X2542491D01*
X2544238Y484523D01*
X2545548Y483356D01*
X2546640Y481607D01*
X2547513Y479564D01*
X2547731Y476648D01*
X2547513Y473731D01*
X2546640Y471689D01*
X2545548Y469939D01*
X2544238Y468773D01*
X2542491Y467898D01*
X2538125D01*
G01X2556061D02*
Y485398D01*
X2561301D01*
X2563048Y484523D01*
X2564358Y482481D01*
X2564795Y480148D01*
X2564358Y477815D01*
X2563266Y476065D01*
X2561301Y475189D01*
X2556061D01*
G01X2538125Y502548D02*
Y520048D01*
X2542491D01*
X2544238Y519173D01*
X2545548Y518006D01*
X2546640Y516257D01*
X2547513Y514214D01*
X2547731Y511298D01*
X2547513Y508381D01*
X2546640Y506339D01*
X2545548Y504589D01*
X2544238Y503423D01*
X2542491Y502548D01*
X2538125D01*
G01X2556061D02*
Y520048D01*
X2561301D01*
X2563048Y519173D01*
X2564358Y517131D01*
X2564795Y514798D01*
X2564358Y512465D01*
X2563266Y510715D01*
X2561301Y509839D01*
X2556061D01*
G01X2538125Y537198D02*
Y554698D01*
X2542491D01*
X2544238Y553823D01*
X2545548Y552656D01*
X2546640Y550907D01*
X2547513Y548864D01*
X2547731Y545948D01*
X2547513Y543031D01*
X2546640Y540989D01*
X2545548Y539239D01*
X2544238Y538073D01*
X2542491Y537198D01*
X2538125D01*
G01X2556061D02*
Y554698D01*
X2561301D01*
X2563048Y553823D01*
X2564358Y551781D01*
X2564795Y549448D01*
X2564358Y547115D01*
X2563266Y545365D01*
X2561301Y544489D01*
X2556061D01*
G01X2538125Y571848D02*
Y589348D01*
X2542491D01*
X2544238Y588473D01*
X2545548Y587306D01*
X2546640Y585557D01*
X2547513Y583514D01*
X2547731Y580598D01*
X2547513Y577681D01*
X2546640Y575639D01*
X2545548Y573889D01*
X2544238Y572723D01*
X2542491Y571848D01*
X2538125D01*
G01X2556061D02*
Y589348D01*
X2561301D01*
X2563048Y588473D01*
X2564358Y586431D01*
X2564795Y584098D01*
X2564358Y581765D01*
X2563266Y580015D01*
X2561301Y579139D01*
X2556061D01*
G01X2525428Y623998D02*
Y606498D01*
G01X2520406Y623998D02*
X2530450D01*
G01X2542928Y606498D02*
Y614373D01*
X2538561Y623998D01*
G01X2547295D02*
X2542928Y614373D01*
G01X2556061Y606498D02*
Y623998D01*
X2561301D01*
X2563048Y623123D01*
X2564358Y621081D01*
X2564795Y618748D01*
X2564358Y616415D01*
X2563266Y614665D01*
X2561301Y613789D01*
X2556061D01*
G01X2582295Y606498D02*
X2573561D01*
Y623998D01*
X2582295D01*
G01X2578801Y615540D02*
X2573561D01*
G01X2626061Y606498D02*
Y623998D01*
X2631520D01*
X2633266Y623123D01*
X2634358Y621956D01*
X2634795Y619623D01*
X2634358Y617289D01*
X2633048Y615831D01*
X2631520Y614956D01*
X2626061D01*
G01X2631520D02*
X2634795Y606498D01*
G01X2644653Y614373D02*
X2651640D01*
X2650985Y616415D01*
X2649893Y617581D01*
X2648365Y618164D01*
X2646836Y617873D01*
X2645526Y616998D01*
X2644653Y614956D01*
X2644216Y613206D01*
Y611456D01*
X2644653Y609706D01*
X2645745Y607956D01*
X2647055Y606790D01*
X2648583Y606498D01*
X2650111Y607081D01*
X2651640Y608831D01*
G01X2664118Y606498D02*
Y621373D01*
X2664555Y622831D01*
X2665428Y623706D01*
X2666738Y623998D01*
X2668048Y623415D01*
X2668703Y621956D01*
G01X2666083Y616998D02*
X2661716D01*
G01X2682928Y605915D02*
X2682491Y606206D01*
Y606790D01*
X2682928Y607081D01*
X2683365Y606790D01*
Y606206D01*
X2682928Y605915D01*
G01X2713561Y606498D02*
Y623998D01*
X2718801D01*
X2720548Y623123D01*
X2721858Y621081D01*
X2722295Y618748D01*
X2721858Y616415D01*
X2720766Y614665D01*
X2718801Y613789D01*
X2713561D01*
G01X2735428Y606498D02*
Y623998D01*
G01X2756858Y606498D02*
Y618164D01*
G01Y616123D02*
X2755985Y617289D01*
X2754674Y617873D01*
X2753146Y618164D01*
X2751618Y617581D01*
X2750308Y616415D01*
X2749434Y614665D01*
X2748998Y612331D01*
X2749434Y609998D01*
X2750308Y608248D01*
X2751618Y607081D01*
X2753146Y606498D01*
X2754674Y606790D01*
X2755985Y607664D01*
X2756858Y608831D01*
G01X2766716Y606498D02*
Y618164D01*
G01Y615248D02*
X2767590Y616706D01*
X2768900Y617873D01*
X2770646Y618164D01*
X2772174Y617873D01*
X2773485Y616706D01*
X2774140Y614665D01*
Y606498D01*
G01X2784653Y614373D02*
X2791640D01*
X2790985Y616415D01*
X2789893Y617581D01*
X2788365Y618164D01*
X2786836Y617873D01*
X2785526Y616998D01*
X2784653Y614956D01*
X2784216Y613206D01*
Y611456D01*
X2784653Y609706D01*
X2785745Y607956D01*
X2787055Y606790D01*
X2788583Y606498D01*
X2790111Y607081D01*
X2791640Y608831D01*
G01X2696061Y485398D02*
Y467898D01*
X2704795D01*
G01X2713780Y482481D02*
X2715090Y484231D01*
X2716618Y485106D01*
X2718365Y485398D01*
X2720548Y484815D01*
X2722076Y483356D01*
X2722513Y481607D01*
X2722295Y479856D01*
X2721421Y478398D01*
X2717055Y475481D01*
X2715090Y473440D01*
X2713780Y470522D01*
X2713343Y467898D01*
X2722513D01*
G01X2696061Y520048D02*
Y502548D01*
X2704795D01*
G01X2713780Y517131D02*
X2715090Y518881D01*
X2716618Y519756D01*
X2718365Y520048D01*
X2720548Y519465D01*
X2722076Y518006D01*
X2722513Y516257D01*
X2722295Y514506D01*
X2721421Y513048D01*
X2717055Y510131D01*
X2715090Y508090D01*
X2713780Y505172D01*
X2713343Y502548D01*
X2722513D01*
G01X2696061Y554698D02*
Y537198D01*
X2704795D01*
G01X2713780Y551781D02*
X2715090Y553531D01*
X2716618Y554406D01*
X2718365Y554698D01*
X2720548Y554115D01*
X2722076Y552656D01*
X2722513Y550907D01*
X2722295Y549156D01*
X2721421Y547698D01*
X2717055Y544781D01*
X2715090Y542740D01*
X2713780Y539822D01*
X2713343Y537198D01*
X2722513D01*
G01X2696061Y589348D02*
Y571848D01*
X2704795D01*
G01X2713780Y586431D02*
X2715090Y588181D01*
X2716618Y589056D01*
X2718365Y589348D01*
X2720548Y588765D01*
X2722076Y587306D01*
X2722513Y585557D01*
X2722295Y583806D01*
X2721421Y582348D01*
X2717055Y579431D01*
X2715090Y577390D01*
X2713780Y574472D01*
X2713343Y571848D01*
X2722513D01*
G01X2905728Y548864D02*
Y537198D01*
G01Y553531D02*
X2905291Y553823D01*
Y554406D01*
X2905728Y554698D01*
X2906165Y554406D01*
Y553823D01*
X2905728Y553531D01*
G01X2919516Y537198D02*
Y548864D01*
G01Y545948D02*
X2920390Y547406D01*
X2921700Y548573D01*
X2923446Y548864D01*
X2924974Y548573D01*
X2926285Y547406D01*
X2926940Y545365D01*
Y537198D01*
G01X2937453Y539239D02*
X2938545Y538073D01*
X2940073Y537198D01*
X2941383D01*
X2942693Y537781D01*
X2943566Y538656D01*
X2944003Y539822D01*
X2943785Y541573D01*
X2942911Y542448D01*
X2938981Y544198D01*
X2938108Y546240D01*
X2938545Y547698D01*
X2939418Y548573D01*
X2940728Y548864D01*
X2942038Y548573D01*
X2943348Y547698D01*
G01X2958228Y548864D02*
Y537198D01*
G01Y553531D02*
X2957791Y553823D01*
Y554406D01*
X2958228Y554698D01*
X2958665Y554406D01*
Y553823D01*
X2958228Y553531D01*
G01X2979658Y554698D02*
Y537198D01*
G01Y539822D02*
X2978785Y538364D01*
X2977474Y537490D01*
X2975946Y537198D01*
X2974200Y537781D01*
X2972890Y539239D01*
X2972016Y540989D01*
X2971798Y543031D01*
X2972016Y545073D01*
X2972890Y546823D01*
X2974200Y548281D01*
X2975946Y548864D01*
X2977474Y548573D01*
X2978566Y547989D01*
X2979658Y546823D01*
G01X2989953Y545073D02*
X2996940D01*
X2996285Y547115D01*
X2995193Y548281D01*
X2993665Y548864D01*
X2992136Y548573D01*
X2990826Y547698D01*
X2989953Y545656D01*
X2989516Y543906D01*
Y542156D01*
X2989953Y540406D01*
X2991045Y538656D01*
X2992355Y537490D01*
X2993883Y537198D01*
X2995411Y537781D01*
X2996940Y539531D01*
G01X3024298Y537198D02*
Y554698D01*
G01Y545948D02*
X3025390Y547698D01*
X3026700Y548573D01*
X3028010Y548864D01*
X3029974Y548281D01*
X3031285Y547115D01*
X3032158Y545073D01*
Y542740D01*
X3031721Y540406D01*
X3030848Y538656D01*
X3029320Y537490D01*
X3028010Y537198D01*
X3026700Y537490D01*
X3025390Y538364D01*
X3024298Y539822D01*
G01X3045728Y537198D02*
X3044418Y537490D01*
X3043108Y538656D01*
X3042234Y540698D01*
X3041798Y543031D01*
X3042234Y545365D01*
X3043108Y547406D01*
X3044418Y548573D01*
X3045728Y548864D01*
X3047038Y548573D01*
X3048348Y547406D01*
X3049221Y545365D01*
X3049440Y543031D01*
X3049221Y540698D01*
X3048348Y538656D01*
X3047038Y537490D01*
X3045728Y537198D01*
G01X3067158D02*
Y548864D01*
G01Y546823D02*
X3066285Y547989D01*
X3064974Y548573D01*
X3063446Y548864D01*
X3061918Y548281D01*
X3060608Y547115D01*
X3059734Y545365D01*
X3059298Y543031D01*
X3059734Y540698D01*
X3060608Y538948D01*
X3061918Y537781D01*
X3063446Y537198D01*
X3064974Y537490D01*
X3066285Y538364D01*
X3067158Y539531D01*
G01X3077671Y537198D02*
Y548864D01*
G01Y546531D02*
X3078763Y547698D01*
X3079855Y548573D01*
X3081383Y548864D01*
X3082474Y548573D01*
X3083785Y547698D01*
G01X3102158Y554698D02*
Y537198D01*
G01Y539822D02*
X3101285Y538364D01*
X3099974Y537490D01*
X3098446Y537198D01*
X3096700Y537781D01*
X3095390Y539239D01*
X3094516Y540989D01*
X3094298Y543031D01*
X3094516Y545073D01*
X3095390Y546823D01*
X3096700Y548281D01*
X3098446Y548864D01*
X3099974Y548573D01*
X3101066Y547989D01*
X3102158Y546823D01*
G01X3133228Y537198D02*
X3131918Y537490D01*
X3130608Y538656D01*
X3129734Y540698D01*
X3129298Y543031D01*
X3129734Y545365D01*
X3130608Y547406D01*
X3131918Y548573D01*
X3133228Y548864D01*
X3134538Y548573D01*
X3135848Y547406D01*
X3136721Y545365D01*
X3136940Y543031D01*
X3136721Y540698D01*
X3135848Y538656D01*
X3134538Y537490D01*
X3133228Y537198D01*
G01X3147016Y548864D02*
Y540698D01*
X3147890Y538656D01*
X3149200Y537490D01*
X3150728Y537198D01*
X3152256Y537490D01*
X3153566Y538656D01*
X3154440Y540698D01*
G01Y537198D02*
Y548864D01*
G01X3168228Y554698D02*
Y537198D01*
G01X3165171Y548864D02*
X3171285D01*
G01X3185728Y537198D02*
Y554698D01*
G01X3203228Y548864D02*
Y537198D01*
G01Y553531D02*
X3202791Y553823D01*
Y554406D01*
X3203228Y554698D01*
X3203665Y554406D01*
Y553823D01*
X3203228Y553531D01*
G01X3217016Y537198D02*
Y548864D01*
G01Y545948D02*
X3217890Y547406D01*
X3219200Y548573D01*
X3220946Y548864D01*
X3222474Y548573D01*
X3223785Y547406D01*
X3224440Y545365D01*
Y537198D01*
G01X3234953Y545073D02*
X3241940D01*
X3241285Y547115D01*
X3240193Y548281D01*
X3238665Y548864D01*
X3237136Y548573D01*
X3235826Y547698D01*
X3234953Y545656D01*
X3234516Y543906D01*
Y542156D01*
X3234953Y540406D01*
X3236045Y538656D01*
X3237355Y537490D01*
X3238883Y537198D01*
X3240411Y537781D01*
X3241940Y539531D01*
G01X3255728Y536615D02*
X3255291Y536906D01*
Y537490D01*
X3255728Y537781D01*
X3256165Y537490D01*
Y536906D01*
X3255728Y536615D01*
G01X2905728Y583514D02*
Y571848D01*
G01Y588181D02*
X2905291Y588473D01*
Y589056D01*
X2905728Y589348D01*
X2906165Y589056D01*
Y588473D01*
X2905728Y588181D01*
G01X2919953Y573889D02*
X2921045Y572723D01*
X2922573Y571848D01*
X2923883D01*
X2925193Y572431D01*
X2926066Y573306D01*
X2926503Y574472D01*
X2926285Y576223D01*
X2925411Y577098D01*
X2921481Y578848D01*
X2920608Y580890D01*
X2921045Y582348D01*
X2921918Y583223D01*
X2923228Y583514D01*
X2924538Y583223D01*
X2925848Y582348D01*
G01X2953206Y571848D02*
Y589348D01*
X2963250Y571848D01*
Y589348D01*
G01X2975728Y571848D02*
X2973981Y572140D01*
X2972453Y573306D01*
X2971143Y575056D01*
X2970269Y577098D01*
X2969833Y579431D01*
Y581765D01*
X2970269Y584098D01*
X2971143Y586140D01*
X2972453Y587889D01*
X2973981Y589056D01*
X2975728Y589348D01*
X2977474Y589056D01*
X2979003Y587889D01*
X2980313Y586140D01*
X2981187Y584098D01*
X2981623Y581765D01*
Y579431D01*
X2981187Y577098D01*
X2980313Y575056D01*
X2979003Y573306D01*
X2977474Y572140D01*
X2975728Y571848D01*
G01X2993228Y589348D02*
Y571848D01*
G01X2988206Y589348D02*
X2998250D01*
G01X3024516Y583514D02*
Y575348D01*
X3025390Y573306D01*
X3026700Y572140D01*
X3028228Y571848D01*
X3029756Y572140D01*
X3031066Y573306D01*
X3031940Y575348D01*
G01Y571848D02*
Y583514D01*
G01X3042453Y573889D02*
X3043545Y572723D01*
X3045073Y571848D01*
X3046383D01*
X3047693Y572431D01*
X3048566Y573306D01*
X3049003Y574472D01*
X3048785Y576223D01*
X3047911Y577098D01*
X3043981Y578848D01*
X3043108Y580890D01*
X3043545Y582348D01*
X3044418Y583223D01*
X3045728Y583514D01*
X3047038Y583223D01*
X3048348Y582348D01*
G01X3059953Y579723D02*
X3066940D01*
X3066285Y581765D01*
X3065193Y582931D01*
X3063665Y583514D01*
X3062136Y583223D01*
X3060826Y582348D01*
X3059953Y580306D01*
X3059516Y578556D01*
Y576806D01*
X3059953Y575056D01*
X3061045Y573306D01*
X3062355Y572140D01*
X3063883Y571848D01*
X3065411Y572431D01*
X3066940Y574181D01*
G01X3084658Y589348D02*
Y571848D01*
G01Y574472D02*
X3083785Y573014D01*
X3082474Y572140D01*
X3080946Y571848D01*
X3079200Y572431D01*
X3077890Y573889D01*
X3077016Y575639D01*
X3076798Y577681D01*
X3077016Y579723D01*
X3077890Y581473D01*
X3079200Y582931D01*
X3080946Y583514D01*
X3082474Y583223D01*
X3083566Y582639D01*
X3084658Y581473D01*
G01X3115728Y583514D02*
Y571848D01*
G01Y588181D02*
X3115291Y588473D01*
Y589056D01*
X3115728Y589348D01*
X3116165Y589056D01*
Y588473D01*
X3115728Y588181D01*
G01X3129516Y571848D02*
Y583514D01*
G01Y580598D02*
X3130390Y582056D01*
X3131700Y583223D01*
X3133446Y583514D01*
X3134974Y583223D01*
X3136285Y582056D01*
X3136940Y580015D01*
Y571848D01*
G01X3168228Y589348D02*
Y571848D01*
G01X3165171Y583514D02*
X3171285D01*
G01X3182016Y571848D02*
Y589348D01*
G01Y580890D02*
X3183108Y582348D01*
X3184200Y583223D01*
X3185946Y583514D01*
X3187256Y583223D01*
X3188785Y582056D01*
X3189440Y580306D01*
Y571848D01*
G01X3203228Y583514D02*
Y571848D01*
G01Y588181D02*
X3202791Y588473D01*
Y589056D01*
X3203228Y589348D01*
X3203665Y589056D01*
Y588473D01*
X3203228Y588181D01*
G01X3217453Y573889D02*
X3218545Y572723D01*
X3220073Y571848D01*
X3221383D01*
X3222693Y572431D01*
X3223566Y573306D01*
X3224003Y574472D01*
X3223785Y576223D01*
X3222911Y577098D01*
X3218981Y578848D01*
X3218108Y580890D01*
X3218545Y582348D01*
X3219418Y583223D01*
X3220728Y583514D01*
X3222038Y583223D01*
X3223348Y582348D01*
G01X3255728Y571848D02*
Y589348D01*
G01X3277158Y571848D02*
Y583514D01*
G01Y581473D02*
X3276285Y582639D01*
X3274974Y583223D01*
X3273446Y583514D01*
X3271918Y582931D01*
X3270608Y581765D01*
X3269734Y580015D01*
X3269298Y577681D01*
X3269734Y575348D01*
X3270608Y573598D01*
X3271918Y572431D01*
X3273446Y571848D01*
X3274974Y572140D01*
X3276285Y573014D01*
X3277158Y574181D01*
G01X3286143Y566598D02*
X3287453Y566015D01*
X3289200Y566598D01*
X3290291Y567764D01*
X3291165Y569223D01*
X3292474Y573889D01*
X3295313Y583514D01*
G01X3288326D02*
X3292474Y573889D01*
G01X3304953Y579723D02*
X3311940D01*
X3311285Y581765D01*
X3310193Y582931D01*
X3308665Y583514D01*
X3307136Y583223D01*
X3305826Y582348D01*
X3304953Y580306D01*
X3304516Y578556D01*
Y576806D01*
X3304953Y575056D01*
X3306045Y573306D01*
X3307355Y572140D01*
X3308883Y571848D01*
X3310411Y572431D01*
X3311940Y574181D01*
G01X3322671Y571848D02*
Y583514D01*
G01Y581181D02*
X3323763Y582348D01*
X3324855Y583223D01*
X3326383Y583514D01*
X3327474Y583223D01*
X3328785Y582348D01*
G01X2830925Y605915D02*
X2840531Y618748D01*
G01X2835728Y621081D02*
Y603581D01*
G01X2840531Y605915D02*
X2830925Y618748D01*
G01X2829178Y612331D02*
X2842278D01*
G01X2867890D02*
X2873566D01*
G01X2900925Y606498D02*
Y623998D01*
X2905291D01*
X2907038Y623123D01*
X2908348Y621956D01*
X2909440Y620207D01*
X2910313Y618164D01*
X2910531Y615248D01*
X2910313Y612331D01*
X2909440Y610289D01*
X2908348Y608539D01*
X2907038Y607373D01*
X2905291Y606498D01*
X2900925D01*
G01X2919953Y614373D02*
X2926940D01*
X2926285Y616415D01*
X2925193Y617581D01*
X2923665Y618164D01*
X2922136Y617873D01*
X2920826Y616998D01*
X2919953Y614956D01*
X2919516Y613206D01*
Y611456D01*
X2919953Y609706D01*
X2921045Y607956D01*
X2922355Y606790D01*
X2923883Y606498D01*
X2925411Y607081D01*
X2926940Y608831D01*
G01X2937016Y606498D02*
Y618164D01*
G01Y615248D02*
X2937890Y616706D01*
X2939200Y617873D01*
X2940946Y618164D01*
X2942474Y617873D01*
X2943785Y616706D01*
X2944440Y614665D01*
Y606498D01*
G01X2958228D02*
X2956918Y606790D01*
X2955608Y607956D01*
X2954734Y609998D01*
X2954298Y612331D01*
X2954734Y614665D01*
X2955608Y616706D01*
X2956918Y617873D01*
X2958228Y618164D01*
X2959538Y617873D01*
X2960848Y616706D01*
X2961721Y614665D01*
X2961940Y612331D01*
X2961721Y609998D01*
X2960848Y607956D01*
X2959538Y606790D01*
X2958228Y606498D01*
G01X2975728Y623998D02*
Y606498D01*
G01X2972671Y618164D02*
X2978785D01*
G01X2989953Y614373D02*
X2996940D01*
X2996285Y616415D01*
X2995193Y617581D01*
X2993665Y618164D01*
X2992136Y617873D01*
X2990826Y616998D01*
X2989953Y614956D01*
X2989516Y613206D01*
Y611456D01*
X2989953Y609706D01*
X2991045Y607956D01*
X2992355Y606790D01*
X2993883Y606498D01*
X2995411Y607081D01*
X2996940Y608831D01*
G01X3007453Y608539D02*
X3008545Y607373D01*
X3010073Y606498D01*
X3011383D01*
X3012693Y607081D01*
X3013566Y607956D01*
X3014003Y609122D01*
X3013785Y610873D01*
X3012911Y611748D01*
X3008981Y613498D01*
X3008108Y615540D01*
X3008545Y616998D01*
X3009418Y617873D01*
X3010728Y618164D01*
X3012038Y617873D01*
X3013348Y616998D01*
G01X3045728Y623998D02*
Y606498D01*
G01X3042671Y618164D02*
X3048785D01*
G01X3059516Y606498D02*
Y623998D01*
G01Y615540D02*
X3060608Y616998D01*
X3061700Y617873D01*
X3063446Y618164D01*
X3064756Y617873D01*
X3066285Y616706D01*
X3066940Y614956D01*
Y606498D01*
G01X3084658D02*
Y618164D01*
G01Y616123D02*
X3083785Y617289D01*
X3082474Y617873D01*
X3080946Y618164D01*
X3079418Y617581D01*
X3078108Y616415D01*
X3077234Y614665D01*
X3076798Y612331D01*
X3077234Y609998D01*
X3078108Y608248D01*
X3079418Y607081D01*
X3080946Y606498D01*
X3082474Y606790D01*
X3083785Y607664D01*
X3084658Y608831D01*
G01X3098228Y623998D02*
Y606498D01*
G01X3095171Y618164D02*
X3101285D01*
G01X3126678Y623998D02*
X3129734Y606498D01*
X3133228Y623998D01*
X3136721Y606498D01*
X3139778Y623998D01*
G01X3148108D02*
X3153348D01*
G01X3150728D02*
Y606498D01*
G01X3148108D02*
X3153348D01*
G01X3163425D02*
Y623998D01*
X3167791D01*
X3169538Y623123D01*
X3170848Y621956D01*
X3171940Y620207D01*
X3172813Y618164D01*
X3173031Y615248D01*
X3172813Y612331D01*
X3171940Y610289D01*
X3170848Y608539D01*
X3169538Y607373D01*
X3167791Y606498D01*
X3163425D01*
G01X3185728Y623998D02*
Y606498D01*
G01X3180706Y623998D02*
X3190750D01*
G01X3198643Y606498D02*
Y623998D01*
G01X3207813D02*
Y606498D01*
G01Y615248D02*
X3198643D01*
G01X-7874Y-31496D02*
X-19685D01*
G01X-7874D02*
X-19685D01*
G01D02*
G03X-23622Y-35433I0J-3937D01*
G01D02*
Y-59055D01*
G01Y-35433D02*
Y-59055D01*
G01X-19685Y-31496D02*
G03X-23622Y-35433I0J-3937D01*
G01Y-59055D02*
G03X-19685Y-62992I3937J0D01*
G01D02*
X1972441D01*
G01X-19685D02*
X1972441D01*
G01X-23622Y-59055D02*
G03X-19685Y-62992I3937J0D01*
G01Y-23622D02*
X1972441D01*
G01X-19685D02*
X1972441D01*
G01X-19685D02*
X1972441D01*
G01X-19685D02*
X1972441D01*
G01X-23622Y622441D02*
Y-19685D01*
G01Y622441D02*
Y-19685D01*
G01Y622441D02*
Y-19685D01*
G01Y622441D02*
Y-19685D01*
G01D02*
G03X-19685Y-23622I3937J0D01*
G01X-23622Y-19685D02*
G03X-19685Y-23622I3937J0D01*
G01X-23622Y-19685D02*
G03X-19685Y-23622I3937J0D01*
G01X-23622Y-19685D02*
G03X-19685Y-23622I3937J0D01*
G01X1972441Y626378D02*
X-19685D01*
G01X1972441D02*
X-19685D01*
G01X1972441D02*
X-19685D01*
G01X1972441D02*
X-19685D01*
G01D02*
G03X-23622Y622441I0J-3937D01*
G01X-19685Y626378D02*
G03X-23622Y622441I0J-3937D01*
G01X-19685Y626378D02*
G03X-23622Y622441I0J-3937D01*
G01X-19685Y626378D02*
G03X-23622Y622441I0J-3937D01*
G01X-19685Y634252D02*
X-7874D01*
G01X-19685D02*
X-7874D01*
G01X-23622Y661811D02*
Y638189D01*
G01Y661811D02*
Y638189D01*
G01D02*
G03X-19685Y634252I3937J0D01*
G01X-23622Y638189D02*
G03X-19685Y634252I3937J0D01*
G01X1972441Y665748D02*
X-19685D01*
G01X1972441D02*
X-19685D01*
G01D02*
G03X-23622Y661811I0J-3937D01*
G01X-19685Y665748D02*
G03X-23622Y661811I0J-3937D01*
G01X-7874Y-31496D02*
G03Y-23622I0J3937D01*
G01Y-31496D02*
G03Y-23622I0J3937D01*
G01X22835D02*
G03Y-31496I0J-3937D01*
G01X137795D02*
X22835D01*
G01X137795D02*
X22835D01*
G01Y-23622D02*
G03Y-31496I0J-3937D01*
G01X0Y616535D02*
G03Y604724I0J-5905D01*
G01Y616535D02*
G03Y604724I0J-5905D01*
G01Y616535D02*
X2646D01*
G01X2644D02*
X0D01*
G01Y604724D02*
X2644D01*
G01X2646D02*
X0D01*
G01X2646D02*
X0D01*
G01D02*
X2644D01*
G01Y616535D02*
X0D01*
G01D02*
X2646D01*
G01X0D02*
G03Y604724I0J-5905D01*
G01Y616535D02*
G03Y604724I0J-5905D01*
G01X2646Y616535D02*
G03X7595Y618285I0J7874D01*
G01X2644Y616535D02*
G03X7593Y618285I0J7874D01*
G01X2644Y616535D02*
G03X7593Y618285I0J7874D01*
G01X7595Y602975D02*
G03X2646Y604724I-4948J-6125D01*
G01X7593Y602975D02*
G03X2644Y604724I-4948J-6125D01*
G01X7593Y602975D02*
G03X2644Y604724I-4948J-6125D01*
G01X7593Y602975D02*
G03X2644Y604724I-4948J-6125D01*
G01X7593Y602975D02*
G03X2644Y604724I-4948J-6125D01*
G01X7595Y602975D02*
G03X2646Y604724I-4948J-6125D01*
G01X2644Y616535D02*
G03X7593Y618285I0J7874D01*
G01X2644Y616535D02*
G03X7593Y618285I0J7874D01*
G01X2646Y616535D02*
G03X7595Y618285I0J7874D01*
G01Y602975D02*
G03Y618285I6186J7655D01*
G01X7593Y602975D02*
G03Y618285I6187J7655D01*
G01Y602975D02*
G03Y618285I6187J7655D01*
G01Y602975D02*
G03Y618285I6187J7655D01*
G01Y602975D02*
G03Y618285I6187J7655D01*
G01X7595Y602975D02*
G03Y618285I6186J7655D01*
G01X-7874Y626378D02*
G03Y634252I0J3937D01*
G01Y626378D02*
G03Y634252I0J3937D01*
G01X22835D02*
G03Y626378I0J-3937D01*
G01Y634252D02*
X137795D01*
G01X22835D02*
X137795D01*
G01X22835D02*
G03Y626378I0J-3937D01*
G01X168504Y-23622D02*
G03Y-31496I0J-3937D01*
G01X137795D02*
G03Y-23622I0J3937D01*
G01X341732Y-31496D02*
X168504D01*
G01X341732D02*
X168504D01*
G01X137795D02*
G03Y-23622I0J3937D01*
G01X168504D02*
G03Y-31496I0J-3937D01*
G01Y634252D02*
G03Y626378I0J-3937D01*
G01X137795D02*
G03Y634252I0J3937D01*
G01X168504D02*
X341732D01*
G01X168504D02*
X341732D01*
G01X137795Y626378D02*
G03Y634252I0J3937D01*
G01X168504D02*
G03Y626378I0J-3937D01*
G01X341732Y-31496D02*
G03Y-23622I0J3937D01*
G01Y-31496D02*
G03Y-23622I0J3937D01*
G01Y626378D02*
G03Y634252I0J3937D01*
G01Y626378D02*
G03Y634252I0J3937D01*
G01X372441Y-23622D02*
G03Y-31496I0J-3937D01*
G01X529921D02*
X372441D01*
G01X529921D02*
X372441D01*
G01Y-23622D02*
G03Y-31496I0J-3937D01*
G01Y634252D02*
G03Y626378I0J-3937D01*
G01Y634252D02*
X529921D01*
G01X372441D02*
X529921D01*
G01X372441D02*
G03Y626378I0J-3937D01*
G01X529921Y-31496D02*
G03Y-23622I0J3937D01*
G01Y-31496D02*
G03Y-23622I0J3937D01*
G01Y626378D02*
G03Y634252I0J3937D01*
G01Y626378D02*
G03Y634252I0J3937D01*
G01X560630Y-23622D02*
G03Y-31496I0J-3937D01*
G01X788976D02*
X560630D01*
G01X788976D02*
X560630D01*
G01Y-23622D02*
G03Y-31496I0J-3937D01*
G01Y634252D02*
G03Y626378I0J-3937D01*
G01Y634252D02*
X788976D01*
G01X560630D02*
X788976D01*
G01X560630D02*
G03Y626378I0J-3937D01*
G01X684760Y-15529D02*
G03Y-219I6187J7655D01*
G01X684759Y-15529D02*
G03X679809Y-13780I-4948J-6125D01*
G01X679811Y-1969D02*
G03X684760Y-219I0J7874D01*
G01X677165Y-1969D02*
X679811D01*
G01X677165D02*
G03Y-13780I0J-5906D01*
G01D02*
X679809D01*
G01X684760Y602975D02*
G03Y618285I6187J7655D01*
G01X684759Y602975D02*
G03Y618285I6186J7655D01*
G01Y602975D02*
G03Y618285I6186J7655D01*
G01Y602975D02*
G03Y618285I6186J7655D01*
G01Y602975D02*
G03Y618285I6186J7655D01*
G01X684760Y602975D02*
G03Y618285I6187J7655D01*
G01X679811Y616535D02*
G03X684760Y618285I0J7874D01*
G01X679809Y616535D02*
G03X684759Y618285I0J7874D01*
G01X679809Y616535D02*
G03X684759Y618285I0J7874D01*
G01X684760Y602975D02*
G03X679811Y604724I-4948J-6125D01*
G01X684759Y602975D02*
G03X679809Y604724I-4948J-6125D01*
G01X684759Y602975D02*
G03X679809Y604724I-4948J-6125D01*
G01X684759Y602975D02*
G03X679809Y604724I-4948J-6125D01*
G01X684759Y602975D02*
G03X679809Y604724I-4948J-6125D01*
G01X684760Y602975D02*
G03X679811Y604724I-4948J-6125D01*
G01X679809Y616535D02*
G03X684759Y618285I0J7874D01*
G01X679809Y616535D02*
G03X684759Y618285I0J7874D01*
G01X679811Y616535D02*
G03X684760Y618285I0J7874D01*
G01X677165Y616535D02*
X679811D01*
G01X677165D02*
G03Y604724I0J-5905D01*
G01D02*
X679809D01*
G01X788976Y-31496D02*
G03Y-23622I0J3937D01*
G01Y-31496D02*
G03Y-23622I0J3937D01*
G01X819685D02*
G03Y-31496I0J-3937D01*
G01X975591D02*
X819685D01*
G01X975591D02*
X819685D01*
G01Y-23622D02*
G03Y-31496I0J-3937D01*
G01X788976Y626378D02*
G03Y634252I0J3937D01*
G01Y626378D02*
G03Y634252I0J3937D01*
G01X819685D02*
G03Y626378I0J-3937D01*
G01Y634252D02*
X975591D01*
G01X819685D02*
X975591D01*
G01X819685D02*
G03Y626378I0J-3937D01*
G01X975591Y-31496D02*
G03Y-23622I0J3937D01*
G01Y-31496D02*
G03Y-23622I0J3937D01*
G01X1006299D02*
G03Y-31496I0J-3937D01*
G01X1162205D02*
X1006299D01*
G01X1162205D02*
X1006299D01*
G01Y-23622D02*
G03Y-31496I0J-3937D01*
G01Y634252D02*
X1162205D01*
G01X1006299D02*
X1162205D01*
G01X975591Y626378D02*
G03Y634252I0J3937D01*
G01Y626378D02*
G03Y634252I0J3937D01*
G01X1006299D02*
G03Y626378I0J-3937D01*
G01Y634252D02*
G03Y626378I0J-3937D01*
G01X1162205Y-31496D02*
G03Y-23622I0J3937D01*
G01Y-31496D02*
G03Y-23622I0J3937D01*
G01X1192913D02*
G03Y-31496I0J-3937D01*
G01X1398425D02*
X1192913D01*
G01X1398425D02*
X1192913D01*
G01Y-23622D02*
G03Y-31496I0J-3937D01*
G01Y634252D02*
X1394488D01*
G01X1192913D02*
X1394488D01*
G01X1162205Y626378D02*
G03Y634252I0J3937D01*
G01Y626378D02*
G03Y634252I0J3937D01*
G01X1192913D02*
G03Y626378I0J-3937D01*
G01Y634252D02*
G03Y626378I0J-3937D01*
G01X1398425Y-31496D02*
G03Y-23622I0J3937D01*
G01Y-31496D02*
G03Y-23622I0J3937D01*
G01X1405512Y-1968D02*
G03Y-13779I0J-5906D01*
G01Y-1968D02*
G03Y-13779I0J-5906D01*
G01Y-1968D02*
G03Y-13779I0J-5906D01*
G01Y-1968D02*
G03Y-13779I0J-5906D01*
G01X1394488Y626378D02*
G03Y634252I0J3937D01*
G01Y626378D02*
G03Y634252I0J3937D01*
G01X1405512Y616535D02*
G03Y604724I0J-5905D01*
G01Y616535D02*
G03Y604724I0J-5905D01*
G01Y616535D02*
G03Y604724I0J-5905D01*
G01Y616535D02*
G03Y604724I0J-5905D01*
G01X1429134Y-23622D02*
G03Y-31496I0J-3937D01*
G01X1851181D02*
X1429134D01*
G01X1851181D02*
X1429134D01*
G01Y-23622D02*
G03Y-31496I0J-3937D01*
G01X1413107Y-15529D02*
G03Y-218I6186J7655D01*
G01X1413105Y-15529D02*
G03Y-218I6186J7655D01*
G01Y-15529D02*
G03Y-218I6186J7655D01*
G01Y-15529D02*
G03Y-218I6186J7655D01*
G01Y-15529D02*
G03Y-218I6186J7655D01*
G01X1413107Y-15529D02*
G03Y-218I6186J7655D01*
G01X1408157Y-1968D02*
G03X1413107Y-218I1J7874D01*
G01X1408156Y-1968D02*
G03X1413105Y-218I0J7874D01*
G01X1408156Y-1968D02*
G03X1413105Y-218I0J7874D01*
G01X1408156Y-1968D02*
G03X1413105Y-218I0J7874D01*
G01X1408156Y-1968D02*
G03X1413105Y-218I0J7874D01*
G01X1408157Y-1968D02*
G03X1413107Y-218I1J7874D01*
G01Y-15529D02*
G03X1408157Y-13779I-4949J-6124D01*
G01X1413105Y-15529D02*
G03X1408156Y-13779I-4949J-6124D01*
G01X1413105Y-15529D02*
G03X1408156Y-13779I-4949J-6124D01*
G01X1413105Y-15529D02*
G03X1408156Y-13779I-4949J-6124D01*
G01X1413105Y-15529D02*
G03X1408156Y-13779I-4949J-6124D01*
G01X1413107Y-15529D02*
G03X1408157Y-13779I-4949J-6124D01*
G01X1405512D02*
X1408156D01*
G01X1408157D02*
X1405512D01*
G01X1408157D02*
X1405512D01*
G01D02*
X1408156D01*
G01X1405512Y-1968D02*
X1408157D01*
G01X1408156D02*
X1405512D01*
G01X1408156D02*
X1405512D01*
G01D02*
X1408157D01*
G01X1425197Y634252D02*
X1851181D01*
G01X1425197D02*
X1851181D01*
G01X1425197D02*
G03Y626378I0J-3937D01*
G01Y634252D02*
G03Y626378I0J-3937D01*
G01X1408157Y616535D02*
G03X1413107Y618285I1J7874D01*
G01X1408156Y616535D02*
G03X1413105Y618285I0J7874D01*
G01X1408156Y616535D02*
G03X1413105Y618285I0J7874D01*
G01X1413107Y602975D02*
G03Y618285I6186J7655D01*
G01X1413105Y602975D02*
G03Y618285I6187J7655D01*
G01Y602975D02*
G03Y618285I6187J7655D01*
G01X1413107Y602975D02*
G03X1408157Y604724I-4948J-6125D01*
G01X1413105Y602975D02*
G03X1408156Y604724I-4948J-6125D01*
G01X1413105Y602975D02*
G03X1408156Y604724I-4948J-6125D01*
G01X1413105Y602975D02*
G03X1408156Y604724I-4948J-6125D01*
G01X1413105Y602975D02*
G03X1408156Y604724I-4948J-6125D01*
G01X1413107Y602975D02*
G03X1408157Y604724I-4948J-6125D01*
G01X1413105Y602975D02*
G03Y618285I6187J7655D01*
G01Y602975D02*
G03Y618285I6187J7655D01*
G01X1413107Y602975D02*
G03Y618285I6186J7655D01*
G01X1408156Y616535D02*
G03X1413105Y618285I0J7874D01*
G01X1408156Y616535D02*
G03X1413105Y618285I0J7874D01*
G01X1408157Y616535D02*
G03X1413107Y618285I1J7874D01*
G01X1405512Y616535D02*
X1408157D01*
G01X1408156D02*
X1405512D01*
G01Y604724D02*
X1408156D01*
G01X1408157D02*
X1405512D01*
G01X1408157D02*
X1405512D01*
G01D02*
X1408156D01*
G01Y616535D02*
X1405512D01*
G01D02*
X1408157D01*
G01X1685866Y267244D02*
X1883780D01*
G01X1685866D02*
X1883780D01*
G01X1685866D02*
X1883780D01*
G01X1685866D02*
X1883780D01*
G01X1681929Y271181D02*
G03X1685866Y267244I3937J0D01*
G01X1681929Y271181D02*
G03X1685866Y267244I3937J0D01*
G01X1681929Y271181D02*
G03X1685866Y267244I3937J0D01*
G01X1681929Y271181D02*
G03X1685866Y267244I3937J0D01*
G01X1681929Y428661D02*
Y271181D01*
G01Y428661D02*
Y271181D01*
G01Y428661D02*
Y271181D01*
G01Y428661D02*
Y271181D01*
G01X1685866Y432598D02*
G03X1681929Y428661I0J-3937D01*
G01X1685866Y432598D02*
G03X1681929Y428661I0J-3937D01*
G01X1972441Y432598D02*
X1685866D01*
G01X1972441D02*
X1685866D01*
G01X1972441D02*
X1685866D01*
G01X1972441D02*
X1685866D01*
G01D02*
G03X1681929Y428661I0J-3937D01*
G01X1685866Y432598D02*
G03X1681929Y428661I0J-3937D01*
G01X1851181Y-31496D02*
G03Y-23622I0J3937D01*
G01Y-31496D02*
G03Y-23622I0J3937D01*
G01X1881890D02*
G03Y-31496I0J-3937D01*
G01X1972441D02*
X1881890D01*
G01X1972441D02*
X1881890D01*
G01Y-23622D02*
G03Y-31496I0J-3937D01*
G01X1861926Y-15529D02*
G03X1856976Y-13780I-4948J-6125D01*
G01X1861924Y-15529D02*
G03X1856975Y-13780I-4948J-6125D01*
G01X1861924Y-15529D02*
G03X1856975Y-13780I-4948J-6125D01*
G01X1861924Y-15529D02*
G03X1856975Y-13780I-4948J-6125D01*
G01X1861924Y-15529D02*
G03X1856975Y-13780I-4948J-6125D01*
G01X1861926Y-15529D02*
G03X1856976Y-13780I-4948J-6125D01*
G01Y-1969D02*
G03X1861926Y-219I0J7874D01*
G01X1856975Y-1969D02*
G03X1861924Y-219I0J7874D01*
G01X1856975Y-1969D02*
G03X1861924Y-219I0J7874D01*
G01X1861926Y-15529D02*
G03Y-219I6186J7655D01*
G01X1861924Y-15529D02*
G03Y-219I6186J7655D01*
G01Y-15529D02*
G03Y-219I6186J7655D01*
G01Y-15529D02*
G03Y-219I6186J7655D01*
G01Y-15529D02*
G03Y-219I6186J7655D01*
G01X1861926Y-15529D02*
G03Y-219I6186J7655D01*
G01X1856975Y-1969D02*
G03X1861924Y-219I0J7874D01*
G01X1856975Y-1969D02*
G03X1861924Y-219I0J7874D01*
G01X1856976Y-1969D02*
G03X1861926Y-219I0J7874D01*
G01X1854331Y-1969D02*
G03Y-13780I0J-5906D01*
G01Y-1969D02*
G03Y-13780I0J-5906D01*
G01D02*
X1856975D01*
G01X1856976D02*
X1854331D01*
G01X1856976D02*
X1854331D01*
G01D02*
X1856975D01*
G01X1854331Y-1969D02*
G03Y-13780I0J-5906D01*
G01Y-1969D02*
G03Y-13780I0J-5906D01*
G01Y-1969D02*
X1856976D01*
G01X1856975D02*
X1854331D01*
G01X1856975D02*
X1854331D01*
G01D02*
X1856976D01*
G01X1891654Y246772D02*
X1972441D01*
G01X1891654D02*
X1972441D01*
G01X1891654D02*
X1972441D01*
G01X1891654D02*
X1972441D01*
G01X1887717Y250709D02*
G03X1891654Y246772I3937J0D01*
G01X1887717Y250709D02*
G03X1891654Y246772I3937J0D01*
G01X1887717Y263307D02*
Y250709D01*
G01Y263307D02*
Y250709D01*
G01Y263307D02*
Y250709D01*
G01Y263307D02*
Y250709D01*
G01D02*
G03X1891654Y246772I3937J0D01*
G01X1887717Y250709D02*
G03X1891654Y246772I3937J0D01*
G01X1887717Y263307D02*
G03X1883780Y267244I-3937J0D01*
G01X1887717Y263307D02*
G03X1883780Y267244I-3937J0D01*
G01X1887717Y263307D02*
G03X1883780Y267244I-3937J0D01*
G01X1887717Y263307D02*
G03X1883780Y267244I-3937J0D01*
G01X1881890Y634252D02*
G03Y626378I0J-3937D01*
G01Y634252D02*
X1972441D01*
G01X1881890D02*
X1972441D01*
G01X1881890D02*
G03Y626378I0J-3937D01*
G01X1851181D02*
G03Y634252I0J3937D01*
G01Y626378D02*
G03Y634252I0J3937D01*
G01X1856976Y616535D02*
G03X1861926Y618285I0J7874D01*
G01X1856975Y616535D02*
G03X1861924Y618285I0J7874D01*
G01X1856975Y616535D02*
G03X1861924Y618285I0J7874D01*
G01X1861926Y602975D02*
G03Y618285I6186J7655D01*
G01X1861924Y602975D02*
G03Y618285I6186J7655D01*
G01Y602975D02*
G03Y618285I6186J7655D01*
G01Y602975D02*
G03Y618285I6186J7655D01*
G01Y602975D02*
G03Y618285I6186J7655D01*
G01X1861926Y602975D02*
G03Y618285I6186J7655D01*
G01X1856975Y616535D02*
G03X1861924Y618285I0J7874D01*
G01X1856975Y616535D02*
G03X1861924Y618285I0J7874D01*
G01X1856976Y616535D02*
G03X1861926Y618285I0J7874D01*
G01Y602975D02*
G03X1856976Y604724I-4948J-6125D01*
G01X1861924Y602975D02*
G03X1856975Y604724I-4948J-6125D01*
G01X1861924Y602975D02*
G03X1856975Y604724I-4948J-6125D01*
G01X1861924Y602975D02*
G03X1856975Y604724I-4948J-6125D01*
G01X1861924Y602975D02*
G03X1856975Y604724I-4948J-6125D01*
G01X1861926Y602975D02*
G03X1856976Y604724I-4948J-6125D01*
G01X1854331Y616535D02*
G03Y604724I0J-5905D01*
G01Y616535D02*
G03Y604724I0J-5905D01*
G01D02*
X1856975D01*
G01X1856976D02*
X1854331D01*
G01X1856976D02*
X1854331D01*
G01D02*
X1856975D01*
G01X1854331Y616535D02*
G03Y604724I0J-5905D01*
G01Y616535D02*
G03Y604724I0J-5905D01*
G01Y616535D02*
X1856976D01*
G01X1856975D02*
X1854331D01*
G01X1856975D02*
X1854331D01*
G01D02*
X1856976D01*
G01X1972441Y-11811D02*
X1906890D01*
G01X1904921Y-9843D02*
G03X1906890Y-11811I1969J1D01*
G01X1904921Y53150D02*
Y-9843D01*
G01X1972441Y-11811D02*
X1906890D01*
G01X1904921Y-9843D02*
G03X1906890Y-11811I1969J1D01*
G01X1904921Y53150D02*
Y-9843D01*
G01X1923071Y53150D02*
Y-9843D01*
G01X1940787Y-3937D02*
X1972441D01*
G01X1940787D02*
G03X1938819Y-5906I0J-1968D01*
G01Y-9843D02*
Y-5906D01*
G01Y-9843D02*
G03X1940787Y-11811I1968J0D01*
G01X1921102D02*
G03X1923071Y-9843I0J1969D01*
G01X1906890Y55118D02*
G03X1904921Y53150I0J-1969D01*
G01X1972441Y55118D02*
X1906890D01*
G01X1972441D02*
X1906890D01*
G01X1972441D02*
X1906890D01*
G01X1972441D02*
X1906890D01*
G01D02*
G03X1904921Y53150I0J-1969D01*
G01X1923071D02*
G03X1921102Y55118I-1969J-1D01*
G01X1940787D02*
G03X1938819Y53150I0J-1968D01*
G01Y49213D02*
Y53150D01*
G01Y49213D02*
G03X1940787Y47244I1968J-1D01*
G01X1972441D02*
X1940787D01*
G01X1976378Y-35433D02*
G03X1972441Y-31496I-3937J0D01*
G01X1976378Y-59055D02*
Y-35433D01*
G01Y-59055D02*
Y-35433D01*
G01D02*
G03X1972441Y-31496I-3937J0D01*
G01Y-62992D02*
G03X1976378Y-59055I0J3937D01*
G01X1972441Y-62992D02*
G03X1976378Y-59055I0J3937D01*
G01X1972441Y-23622D02*
G03X1976378Y-19685I0J3937D01*
G01X1972441Y-23622D02*
G03X1976378Y-19685I0J3937D01*
G01X1972441Y-23622D02*
G03X1976378Y-19685I0J3937D01*
G01X1972441Y-23622D02*
G03X1976378Y-19685I0J3937D01*
G01D02*
Y-15748D01*
G01Y-19685D02*
Y-15748D01*
G01Y-19685D02*
Y-15748D01*
G01Y-19685D02*
Y-15748D01*
G01D02*
G03X1972441Y-11811I-3937J0D01*
G01X1976378Y-15748D02*
G03X1972441Y-11811I-3937J0D01*
G01X1976378Y-15748D02*
G03X1972441Y-11811I-3937J0D01*
G01X1976378Y-15748D02*
G03X1972441Y-11811I-3937J0D01*
G01X1976378Y0D02*
Y43307D01*
G01X1972441Y-3937D02*
G03X1976378Y0I0J3937D01*
G01X1972441Y55118D02*
G03X1976378Y59055I0J3937D01*
G01X1972441Y55118D02*
G03X1976378Y59055I0J3937D01*
G01X1972441Y55118D02*
G03X1976378Y59055I0J3937D01*
G01X1972441Y55118D02*
G03X1976378Y59055I0J3937D01*
G01D02*
Y242835D01*
G01Y59055D02*
Y242835D01*
G01Y59055D02*
Y242835D01*
G01Y59055D02*
Y242835D01*
G01Y43307D02*
G03X1972441Y47244I-3937J0D01*
G01X1976378Y242835D02*
G03X1972441Y246772I-3937J0D01*
G01X1976378Y242835D02*
G03X1972441Y246772I-3937J0D01*
G01X1976378Y242835D02*
G03X1972441Y246772I-3937J0D01*
G01X1976378Y242835D02*
G03X1972441Y246772I-3937J0D01*
G01Y432598D02*
G03X1976378Y436535I0J3937D01*
G01X1972441Y432598D02*
G03X1976378Y436535I0J3937D01*
G01X1972441Y432598D02*
G03X1976378Y436535I0J3937D01*
G01X1972441Y432598D02*
G03X1976378Y436535I0J3937D01*
G01D02*
Y622441D01*
G01Y436535D02*
Y622441D01*
G01Y436535D02*
Y622441D01*
G01Y436535D02*
Y622441D01*
G01D02*
G03X1972441Y626378I-3937J0D01*
G01X1976378Y622441D02*
G03X1972441Y626378I-3937J0D01*
G01X1976378Y622441D02*
G03X1972441Y626378I-3937J0D01*
G01X1976378Y622441D02*
G03X1972441Y626378I-3937J0D01*
G01Y634252D02*
G03X1976378Y638189I0J3937D01*
G01X1972441Y634252D02*
G03X1976378Y638189I0J3937D01*
G01D02*
Y661811D01*
G01Y638189D02*
Y661811D01*
G01D02*
G03X1972441Y665748I-3937J0D01*
G01X1976378Y661811D02*
G03X1972441Y665748I-3937J0D01*
G54D12*
G01X58925Y94275D02*
X65488D01*
G01X58885Y93325D02*
X65094D01*
G01X65488Y94275D02*
X66950Y92813D01*
G01X65094Y93325D02*
X66000Y92419D01*
G01X66950Y92813D02*
Y91350D01*
G01X66000Y92419D02*
Y91350D01*
G01X58885Y93325D02*
X65094D01*
G01X58925Y94275D02*
X65488D01*
G01X65094Y93325D02*
X66000Y92419D01*
G01X65488Y94275D02*
X66950Y92813D01*
G01X66000Y92419D02*
Y91350D01*
G01X66950Y92813D02*
Y91350D01*
G01X58885Y93325D02*
X65094D01*
G01X58925Y94275D02*
X65488D01*
G01X65094Y93325D02*
X66000Y92419D01*
G01X65488Y94275D02*
X66950Y92813D01*
G01X66000Y92419D02*
Y91350D01*
G01X66950Y92813D02*
Y91350D01*
G01X58925Y94275D02*
X65488D01*
G01X58885Y93325D02*
X65094D01*
G01X65488Y94275D02*
X66950Y92813D01*
G01X65094Y93325D02*
X66000Y92419D01*
G01X66950Y92813D02*
Y91350D01*
G01X66000Y92419D02*
Y91350D01*
G01X53425Y99775D02*
X47350D01*
G01X53425Y100725D02*
X47350D01*
G01X53425Y114725D02*
X47350D01*
G01X53425Y113775D02*
X47350D01*
G01X53425Y120775D02*
X52019D01*
G01X53425Y121725D02*
X52019D01*
G01X53425Y128725D02*
X47350D01*
G01X53425Y127775D02*
X47350D01*
G01X53425Y134775D02*
X52019D01*
G01X53425Y135725D02*
X52019D01*
G01X53425Y142725D02*
X47350D01*
G01X53425Y141775D02*
X47350D01*
G01X53425Y100725D02*
X47350D01*
G01X53425Y99775D02*
X47350D01*
G01X53425Y113775D02*
X47350D01*
G01X53425Y114725D02*
X47350D01*
G01X53425Y121725D02*
X52019D01*
G01X53425Y120775D02*
X52019D01*
G01X53425Y127775D02*
X47350D01*
G01X53425Y128725D02*
X47350D01*
G01X53425Y135725D02*
X52019D01*
G01X53425Y134775D02*
X52019D01*
G01X53425Y141775D02*
X47350D01*
G01X53425Y142725D02*
X47350D01*
G01X64326Y107725D02*
X59475D01*
G01Y106775D02*
X64934D01*
G01X59488Y114712D02*
X60237D01*
G01X59462Y113762D02*
X60263D01*
G01X59470Y120770D02*
X64940D01*
G01X59480Y121720D02*
X64970D01*
G01X59475Y134775D02*
X65237D01*
G01X59475Y135725D02*
X65237D01*
G01X59475Y142725D02*
X60381D01*
G01X59475Y141775D02*
X60381D01*
G01X59475Y106775D02*
X64934D01*
G01X64326Y107725D02*
X59475D01*
G01X59462Y113762D02*
X60263D01*
G01X59488Y114712D02*
X60237D01*
G01X59480Y121720D02*
X64970D01*
G01X59470Y120770D02*
X64940D01*
G01X59475Y135725D02*
X65237D01*
G01X59475Y134775D02*
X65237D01*
G01X59475Y141775D02*
X60381D01*
G01X59475Y142725D02*
X60381D01*
G01X64326Y107725D02*
X59475D01*
G01Y106775D02*
X64934D01*
G01X59488Y114712D02*
X60237D01*
G01X59462Y113762D02*
X60263D01*
G01X59470Y120770D02*
X64940D01*
G01X59480Y121720D02*
X64970D01*
G01X59475Y134775D02*
X65237D01*
G01X59475Y135725D02*
X65237D01*
G01X59475Y142725D02*
X60381D01*
G01X59475Y141775D02*
X60381D01*
G01X59475Y106775D02*
X64934D01*
G01X64326Y107725D02*
X59475D01*
G01X59462Y113762D02*
X60263D01*
G01X59488Y114712D02*
X60237D01*
G01X59480Y121720D02*
X64970D01*
G01X59470Y120770D02*
X64940D01*
G01X59475Y135725D02*
X65237D01*
G01X59475Y134775D02*
X65237D01*
G01X59475Y141775D02*
X60381D01*
G01X59475Y142725D02*
X60381D01*
G01X108370Y644149D02*
X107553Y645315D01*
G01D02*
X109058Y653856D01*
G01X106755Y654261D02*
X105046Y644559D01*
G01X105887Y654814D02*
X104178Y645113D01*
G01X105046Y644559D02*
X103877Y643744D01*
G01X104178Y645113D02*
X103655Y644748D01*
G01X105046Y644559D02*
X103877Y643744D01*
G01D02*
X101685Y644129D01*
G01X103655Y644748D02*
X102237Y644997D01*
G01X101685Y644129D02*
X100868Y645295D01*
G01X102237Y644997D02*
X101872Y645518D01*
G01X100868Y645295D02*
X102365Y653790D01*
G01X101872Y645518D02*
X103369Y654013D01*
G01X100061Y654194D02*
X98367Y644574D01*
G01X99193Y654747D02*
X97499Y645127D01*
G01X98367Y644574D02*
X97199Y643757D01*
G01X97499Y645127D02*
X96976Y644761D01*
G01X98367Y644574D02*
X97199Y643757D01*
G01D02*
X95005Y644142D01*
G01X96976Y644761D02*
X95559Y645010D01*
G01X95005Y644142D02*
X94190Y645311D01*
G01X95559Y645010D02*
X95194Y645533D01*
G01X94190Y645311D02*
X95684Y653794D01*
G01X95194Y645533D02*
X96689Y654017D01*
G01X93382Y654200D02*
X91684Y644553D01*
G01X92514Y654753D02*
X90816Y645107D01*
G01X91684Y644553D02*
X90516Y643738D01*
G01X90816Y645107D02*
X90293Y644742D01*
G01X91684Y644553D02*
X90516Y643738D01*
G01D02*
X88320Y644122D01*
G01X90293Y644742D02*
X88873Y644990D01*
G01X88320Y644122D02*
X87505Y645289D01*
G01X88873Y644990D02*
X88509Y645511D01*
G01X87505Y645289D02*
X89002Y653783D01*
G01X88509Y645511D02*
X90006Y654006D01*
G01X86698Y654188D02*
X84986Y644471D01*
G01X85830Y654741D02*
X84118Y645024D01*
G01X84986Y644471D02*
X83818Y643654D01*
G01X84118Y645024D02*
X83595Y644658D01*
G01X84986Y644471D02*
X83818Y643654D01*
G01D02*
X81624Y644039D01*
G01X83595Y644658D02*
X82178Y644907D01*
G01X81624Y644039D02*
X80809Y645208D01*
G01X82178Y644907D02*
X81813Y645430D01*
G01X80809Y645208D02*
X82319Y653779D01*
G01X81813Y645430D02*
X83324Y654002D01*
G01X80017Y654186D02*
X78308Y644485D01*
G01X79149Y654739D02*
X77440Y645038D01*
G01X78308Y644485D02*
X77140Y643668D01*
G01X77440Y645038D02*
X76917Y644672D01*
G01X78308Y644485D02*
X77140Y643668D01*
G01D02*
X74946Y644053D01*
G01X76917Y644672D02*
X75498Y644921D01*
G01X74946Y644053D02*
X74129Y645219D01*
G01X75498Y644921D02*
X75133Y645442D01*
G01X74129Y645219D02*
X75655Y653874D01*
G01X75133Y645442D02*
X76659Y654097D01*
G01X73014Y652372D02*
X70871Y649736D01*
G01D02*
X65542Y648844D01*
G01X70360Y650614D02*
X65500Y649801D01*
G01X65542Y648844D02*
X61193Y649181D01*
G01X65500Y649801D02*
X61230Y650131D01*
G01X61193Y649181D02*
X59179D01*
G01X108370Y644149D02*
X107553Y645315D01*
G01D02*
X109058Y653856D01*
G01X105887Y654814D02*
X104178Y645113D01*
G01X106755Y654261D02*
X105046Y644559D01*
G01X104178Y645113D02*
X103655Y644748D01*
G01D02*
X102237Y644997D01*
G01X105046Y644559D02*
X103877Y643744D01*
G01X103655Y644748D02*
X102237Y644997D01*
G01X103877Y643744D02*
X101685Y644129D01*
G01X102237Y644997D02*
X101872Y645518D01*
G01X101685Y644129D02*
X100868Y645295D01*
G01X101872Y645518D02*
X103369Y654013D01*
G01X100868Y645295D02*
X102365Y653790D01*
G01X99193Y654747D02*
X97499Y645127D01*
G01X100061Y654194D02*
X98367Y644574D01*
G01X97499Y645127D02*
X96976Y644761D01*
G01D02*
X95559Y645010D01*
G01X98367Y644574D02*
X97199Y643757D01*
G01X96976Y644761D02*
X95559Y645010D01*
G01X97199Y643757D02*
X95005Y644142D01*
G01X95559Y645010D02*
X95194Y645533D01*
G01X95005Y644142D02*
X94190Y645311D01*
G01X95194Y645533D02*
X96689Y654017D01*
G01X94190Y645311D02*
X95684Y653794D01*
G01X92514Y654753D02*
X90816Y645107D01*
G01X93382Y654200D02*
X91684Y644553D01*
G01X90816Y645107D02*
X90293Y644742D01*
G01D02*
X88873Y644990D01*
G01X91684Y644553D02*
X90516Y643738D01*
G01X90293Y644742D02*
X88873Y644990D01*
G01X90516Y643738D02*
X88320Y644122D01*
G01X88873Y644990D02*
X88509Y645511D01*
G01X88320Y644122D02*
X87505Y645289D01*
G01X88509Y645511D02*
X90006Y654006D01*
G01X87505Y645289D02*
X89002Y653783D01*
G01X85830Y654741D02*
X84118Y645024D01*
G01X86698Y654188D02*
X84986Y644471D01*
G01X84118Y645024D02*
X83595Y644658D01*
G01D02*
X82178Y644907D01*
G01X84986Y644471D02*
X83818Y643654D01*
G01X83595Y644658D02*
X82178Y644907D01*
G01X83818Y643654D02*
X81624Y644039D01*
G01X82178Y644907D02*
X81813Y645430D01*
G01X81624Y644039D02*
X80809Y645208D01*
G01X81813Y645430D02*
X83324Y654002D01*
G01X80809Y645208D02*
X82319Y653779D01*
G01X79149Y654739D02*
X77440Y645038D01*
G01X80017Y654186D02*
X78308Y644485D01*
G01X77440Y645038D02*
X76917Y644672D01*
G01D02*
X75498Y644921D01*
G01X78308Y644485D02*
X77140Y643668D01*
G01X76917Y644672D02*
X75498Y644921D01*
G01X77140Y643668D02*
X74946Y644053D01*
G01X75498Y644921D02*
X75133Y645442D01*
G01X74946Y644053D02*
X74129Y645219D01*
G01X75133Y645442D02*
X76659Y654097D01*
G01X74129Y645219D02*
X75655Y653874D01*
G01X73014Y652372D02*
X70871Y649736D01*
G01X70360Y650614D02*
X65500Y649801D01*
G01X70871Y649736D02*
X65542Y648844D01*
G01X65500Y649801D02*
X61230Y650131D01*
G01X65542Y648844D02*
X61193Y649181D01*
G01D02*
X59179D01*
G01X108694Y654376D02*
X107274Y654624D01*
G01X109246Y655244D02*
X107052Y655629D01*
G01X108694Y654376D02*
X107274Y654624D01*
G01D02*
X106755Y654261D01*
G01X107052Y655629D02*
X105887Y654814D01*
G01X102365Y653790D02*
X102001Y654310D01*
G01X103369Y654013D02*
X102553Y655178D01*
G01X102001Y654310D02*
X100581Y654558D01*
G01X102553Y655178D02*
X100359Y655563D01*
G01X102001Y654310D02*
X100581Y654558D01*
G01D02*
X100061Y654194D01*
G01X100359Y655563D02*
X99193Y654747D01*
G01X95684Y653794D02*
X95320Y654315D01*
G01X96689Y654017D02*
X95873Y655183D01*
G01X95320Y654315D02*
X93902Y654565D01*
G01X95873Y655183D02*
X93679Y655569D01*
G01X95320Y654315D02*
X93902Y654565D01*
G01D02*
X93382Y654200D01*
G01X93679Y655569D02*
X92514Y654753D01*
G01X89002Y653783D02*
X88637Y654302D01*
G01X90006Y654006D02*
X89190Y655170D01*
G01X88637Y654302D02*
X87218Y654552D01*
G01X89190Y655170D02*
X86996Y655557D01*
G01X88637Y654302D02*
X87218Y654552D01*
G01D02*
X86698Y654188D01*
G01X86996Y655557D02*
X85830Y654741D01*
G01X82319Y653779D02*
X81955Y654300D01*
G01X83324Y654002D02*
X82508Y655168D01*
G01X81955Y654300D02*
X80537Y654550D01*
G01X82508Y655168D02*
X80314Y655555D01*
G01X81955Y654300D02*
X80537Y654550D01*
G01D02*
X80017Y654186D01*
G01X80314Y655555D02*
X79149Y654739D01*
G01X75655Y653874D02*
X75290Y654394D01*
G01X76659Y654097D02*
X75843Y655262D01*
G01X75290Y654394D02*
X73871Y654644D01*
G01X75843Y655262D02*
X73649Y655648D01*
G01X75290Y654394D02*
X73871Y654644D01*
G01D02*
X73351Y654281D01*
G01X73649Y655648D02*
X72483Y654835D01*
G01X73351Y654281D02*
X73014Y652372D01*
G01X72483Y654835D02*
X72121Y652780D01*
G01D02*
X70360Y650614D01*
G01X61230Y650131D02*
X59179D01*
G01X109246Y655244D02*
X107052Y655629D01*
G01D02*
X105887Y654814D01*
G01X108694Y654376D02*
X107274Y654624D01*
G01X107052Y655629D02*
X105887Y654814D01*
G01X107274Y654624D02*
X106755Y654261D01*
G01X103369Y654013D02*
X102553Y655178D01*
G01X102365Y653790D02*
X102001Y654310D01*
G01X102553Y655178D02*
X100359Y655563D01*
G01D02*
X99193Y654747D01*
G01X102001Y654310D02*
X100581Y654558D01*
G01X100359Y655563D02*
X99193Y654747D01*
G01X100581Y654558D02*
X100061Y654194D01*
G01X96689Y654017D02*
X95873Y655183D01*
G01X95684Y653794D02*
X95320Y654315D01*
G01X95873Y655183D02*
X93679Y655569D01*
G01D02*
X92514Y654753D01*
G01X95320Y654315D02*
X93902Y654565D01*
G01X93679Y655569D02*
X92514Y654753D01*
G01X93902Y654565D02*
X93382Y654200D01*
G01X90006Y654006D02*
X89190Y655170D01*
G01X89002Y653783D02*
X88637Y654302D01*
G01X89190Y655170D02*
X86996Y655557D01*
G01D02*
X85830Y654741D01*
G01X88637Y654302D02*
X87218Y654552D01*
G01X86996Y655557D02*
X85830Y654741D01*
G01X87218Y654552D02*
X86698Y654188D01*
G01X83324Y654002D02*
X82508Y655168D01*
G01X82319Y653779D02*
X81955Y654300D01*
G01X82508Y655168D02*
X80314Y655555D01*
G01D02*
X79149Y654739D01*
G01X81955Y654300D02*
X80537Y654550D01*
G01X80314Y655555D02*
X79149Y654739D01*
G01X80537Y654550D02*
X80017Y654186D01*
G01X76659Y654097D02*
X75843Y655262D01*
G01X75655Y653874D02*
X75290Y654394D01*
G01X75843Y655262D02*
X73649Y655648D01*
G01D02*
X72483Y654835D01*
G01X75290Y654394D02*
X73871Y654644D01*
G01X73649Y655648D02*
X72483Y654835D01*
G01X73871Y654644D02*
X73351Y654281D01*
G01X72483Y654835D02*
X72121Y652780D01*
G01X73351Y654281D02*
X73014Y652372D01*
G01X72121Y652780D02*
X70360Y650614D01*
G01X61230Y650131D02*
X59179D01*
G01X170690Y643698D02*
X168496Y644084D01*
G01X170467Y644702D02*
X169049Y644952D01*
G01X168496Y644084D02*
X167680Y645250D01*
G01X169049Y644952D02*
X168685Y645473D01*
G01X167680Y645250D02*
X169175Y653734D01*
G01X168685Y645473D02*
X170179Y653956D01*
G01X166870Y654140D02*
X165176Y644520D01*
G01X166002Y654693D02*
X164308Y645073D01*
G01X165176Y644520D02*
X164010Y643704D01*
G01X164308Y645073D02*
X163788Y644709D01*
G01X165176Y644520D02*
X164010Y643704D01*
G01D02*
X161816Y644089D01*
G01X163788Y644709D02*
X162368Y644957D01*
G01X161816Y644089D02*
X161000Y645254D01*
G01X162368Y644957D02*
X162004Y645477D01*
G01X161000Y645254D02*
X162497Y653749D01*
G01X162004Y645477D02*
X163501Y653972D01*
G01X160191Y654154D02*
X158482Y644453D01*
G01X159323Y654708D02*
X157614Y645006D01*
G01X158482Y644453D02*
X157317Y643638D01*
G01X157614Y645006D02*
X157095Y644643D01*
G01X158482Y644453D02*
X157317Y643638D01*
G01D02*
X155123Y644023D01*
G01X157095Y644643D02*
X155675Y644891D01*
G01X155123Y644023D02*
X154307Y645188D01*
G01X155675Y644891D02*
X155311Y645411D01*
G01X154307Y645188D02*
X155812Y653729D01*
G01X155311Y645411D02*
X156816Y653952D01*
G01X153506Y654133D02*
X151802Y644461D01*
G01X152638Y654686D02*
X150934Y645014D01*
G01X151802Y644461D02*
X150624Y643636D01*
G01X150934Y645014D02*
X150401Y644641D01*
G01X151802Y644461D02*
X150624Y643636D01*
G01D02*
X148453Y644019D01*
G01X150401Y644641D02*
X149005Y644887D01*
G01X148453Y644019D02*
X147624Y645198D01*
G01X149005Y644887D02*
X148629Y645422D01*
G01X147624Y645198D02*
X149132Y653752D01*
G01X148629Y645422D02*
X150136Y653974D01*
G01X146827Y654156D02*
X145119Y644447D01*
G01X145959Y654709D02*
X144251Y645000D01*
G01X145119Y644447D02*
X143954Y643632D01*
G01X144251Y645000D02*
X143731Y644636D01*
G01X145119Y644447D02*
X143954Y643632D01*
G01D02*
X141756Y644018D01*
G01X143731Y644636D02*
X142310Y644886D01*
G01X141756Y644018D02*
X140943Y645184D01*
G01X142310Y644886D02*
X141947Y645406D01*
G01X140943Y645184D02*
X142451Y653750D01*
G01X141947Y645406D02*
X143455Y653973D01*
G01X140146Y654153D02*
X138442Y644480D01*
G01X139278Y654706D02*
X137574Y645033D01*
G01X138442Y644480D02*
X137277Y643665D01*
G01X137574Y645033D02*
X137054Y644669D01*
G01X138442Y644480D02*
X137277Y643665D01*
G01D02*
X135082Y644050D01*
G01X137054Y644669D02*
X135634Y644918D01*
G01X135082Y644050D02*
X134265Y645217D01*
G01X135634Y644918D02*
X135269Y645440D01*
G01X134265Y645217D02*
X135767Y653735D01*
G01X135269Y645440D02*
X136771Y653957D01*
G01X132759Y650154D02*
X131774Y644573D01*
G01X131815Y650276D02*
X130906Y645126D01*
G01X131774Y644573D02*
X130606Y643756D01*
G01X130906Y645126D02*
X130383Y644760D01*
G01X131774Y644573D02*
X130606Y643756D01*
G01D02*
X128413Y644141D01*
G01X130383Y644760D02*
X128967Y645009D01*
G01X128413Y644141D02*
X127598Y645310D01*
G01X128967Y645009D02*
X128602Y645532D01*
G01X127598Y645310D02*
X129100Y653827D01*
G01X128602Y645532D02*
X130104Y654050D01*
G01X126795Y654234D02*
X125091Y644561D01*
G01X125927Y654787D02*
X124223Y645114D01*
G01X125091Y644561D02*
X123922Y643744D01*
G01X124223Y645114D02*
X123699Y644748D01*
G01X125091Y644561D02*
X123922Y643744D01*
G01D02*
X121731Y644128D01*
G01X123699Y644748D02*
X122283Y644996D01*
G01X121731Y644128D02*
X120914Y645294D01*
G01X122283Y644996D02*
X121918Y645517D01*
G01X120914Y645294D02*
X122422Y653861D01*
G01X121918Y645517D02*
X123426Y654083D01*
G01X120118Y654267D02*
X118410Y644558D01*
G01X119250Y654820D02*
X117542Y645111D01*
G01X118410Y644558D02*
X117241Y643741D01*
G01X117542Y645111D02*
X117019Y644745D01*
G01X118410Y644558D02*
X117241Y643741D01*
G01D02*
X115049Y644126D01*
G01X117019Y644745D02*
X115602Y644994D01*
G01X115049Y644126D02*
X114233Y645293D01*
G01X115602Y644994D02*
X115237Y645515D01*
G01X114233Y645293D02*
X115740Y653845D01*
G01X115237Y645515D02*
X116745Y654069D01*
G01X113435Y654253D02*
X111731Y644581D01*
G01X112567Y654806D02*
X110863Y645134D01*
G01X111731Y644581D02*
X110563Y643764D01*
G01X110863Y645134D02*
X110340Y644768D01*
G01X111731Y644581D02*
X110563Y643764D01*
G01D02*
X108370Y644149D01*
G01X110340Y644768D02*
X108922Y645017D01*
G01D02*
X108557Y645538D01*
G01D02*
X110062Y654079D01*
G01X170467Y644702D02*
X169049Y644952D01*
G01X170467Y644702D02*
X169049Y644952D01*
G01X170690Y643698D02*
X168496Y644084D01*
G01X169049Y644952D02*
X168685Y645473D01*
G01X168496Y644084D02*
X167680Y645250D01*
G01X168685Y645473D02*
X170179Y653956D01*
G01X167680Y645250D02*
X169175Y653734D01*
G01X166002Y654693D02*
X164308Y645073D01*
G01X166870Y654140D02*
X165176Y644520D01*
G01X164308Y645073D02*
X163788Y644709D01*
G01D02*
X162368Y644957D01*
G01X165176Y644520D02*
X164010Y643704D01*
G01X163788Y644709D02*
X162368Y644957D01*
G01X164010Y643704D02*
X161816Y644089D01*
G01X162368Y644957D02*
X162004Y645477D01*
G01X161816Y644089D02*
X161000Y645254D01*
G01X162004Y645477D02*
X163501Y653972D01*
G01X161000Y645254D02*
X162497Y653749D01*
G01X159323Y654708D02*
X157614Y645006D01*
G01X160191Y654154D02*
X158482Y644453D01*
G01X157614Y645006D02*
X157095Y644643D01*
G01D02*
X155675Y644891D01*
G01X158482Y644453D02*
X157317Y643638D01*
G01X157095Y644643D02*
X155675Y644891D01*
G01X157317Y643638D02*
X155123Y644023D01*
G01X155675Y644891D02*
X155311Y645411D01*
G01X155123Y644023D02*
X154307Y645188D01*
G01X155311Y645411D02*
X156816Y653952D01*
G01X154307Y645188D02*
X155812Y653729D01*
G01X152638Y654686D02*
X150934Y645014D01*
G01X153506Y654133D02*
X151802Y644461D01*
G01X150934Y645014D02*
X150401Y644641D01*
G01D02*
X149005Y644887D01*
G01X151802Y644461D02*
X150624Y643636D01*
G01X150401Y644641D02*
X149005Y644887D01*
G01X150624Y643636D02*
X148453Y644019D01*
G01X149005Y644887D02*
X148629Y645422D01*
G01X148453Y644019D02*
X147624Y645198D01*
G01X148629Y645422D02*
X150136Y653974D01*
G01X147624Y645198D02*
X149132Y653752D01*
G01X145959Y654709D02*
X144251Y645000D01*
G01X146827Y654156D02*
X145119Y644447D01*
G01X144251Y645000D02*
X143731Y644636D01*
G01D02*
X142310Y644886D01*
G01X145119Y644447D02*
X143954Y643632D01*
G01X143731Y644636D02*
X142310Y644886D01*
G01X143954Y643632D02*
X141756Y644018D01*
G01X142310Y644886D02*
X141947Y645406D01*
G01X141756Y644018D02*
X140943Y645184D01*
G01X141947Y645406D02*
X143455Y653973D01*
G01X140943Y645184D02*
X142451Y653750D01*
G01X139278Y654706D02*
X137574Y645033D01*
G01X140146Y654153D02*
X138442Y644480D01*
G01X137574Y645033D02*
X137054Y644669D01*
G01D02*
X135634Y644918D01*
G01X138442Y644480D02*
X137277Y643665D01*
G01X137054Y644669D02*
X135634Y644918D01*
G01X137277Y643665D02*
X135082Y644050D01*
G01X135634Y644918D02*
X135269Y645440D01*
G01X135082Y644050D02*
X134265Y645217D01*
G01X135269Y645440D02*
X136771Y653957D01*
G01X134265Y645217D02*
X135767Y653735D01*
G01X131815Y650276D02*
X130906Y645126D01*
G01X132759Y650154D02*
X131774Y644573D01*
G01X130906Y645126D02*
X130383Y644760D01*
G01D02*
X128967Y645009D01*
G01X131774Y644573D02*
X130606Y643756D01*
G01X130383Y644760D02*
X128967Y645009D01*
G01X130606Y643756D02*
X128413Y644141D01*
G01X128967Y645009D02*
X128602Y645532D01*
G01X128413Y644141D02*
X127598Y645310D01*
G01X128602Y645532D02*
X130104Y654050D01*
G01X127598Y645310D02*
X129100Y653827D01*
G01X125927Y654787D02*
X124223Y645114D01*
G01X126795Y654234D02*
X125091Y644561D01*
G01X124223Y645114D02*
X123699Y644748D01*
G01D02*
X122283Y644996D01*
G01X125091Y644561D02*
X123922Y643744D01*
G01X123699Y644748D02*
X122283Y644996D01*
G01X123922Y643744D02*
X121731Y644128D01*
G01X122283Y644996D02*
X121918Y645517D01*
G01X121731Y644128D02*
X120914Y645294D01*
G01X121918Y645517D02*
X123426Y654083D01*
G01X120914Y645294D02*
X122422Y653861D01*
G01X119250Y654820D02*
X117542Y645111D01*
G01X120118Y654267D02*
X118410Y644558D01*
G01X117542Y645111D02*
X117019Y644745D01*
G01D02*
X115602Y644994D01*
G01X118410Y644558D02*
X117241Y643741D01*
G01X117019Y644745D02*
X115602Y644994D01*
G01X117241Y643741D02*
X115049Y644126D01*
G01X115602Y644994D02*
X115237Y645515D01*
G01X115049Y644126D02*
X114233Y645293D01*
G01X115237Y645515D02*
X116745Y654069D01*
G01X114233Y645293D02*
X115740Y653845D01*
G01X112567Y654806D02*
X110863Y645134D01*
G01X113435Y654253D02*
X111731Y644581D01*
G01X110863Y645134D02*
X110340Y644768D01*
G01D02*
X108922Y645017D01*
G01X111731Y644581D02*
X110563Y643764D01*
G01X110340Y644768D02*
X108922Y645017D01*
G01X110563Y643764D02*
X108370Y644149D01*
G01X108922Y645017D02*
X108557Y645538D01*
G01D02*
X110062Y654079D01*
G01X169175Y653734D02*
X168810Y654257D01*
G01X170179Y653956D02*
X169364Y655125D01*
G01X168810Y654257D02*
X167393Y654506D01*
G01X169364Y655125D02*
X167170Y655510D01*
G01X168810Y654257D02*
X167393Y654506D01*
G01D02*
X166870Y654140D01*
G01X167170Y655510D02*
X166002Y654693D01*
G01X162497Y653749D02*
X162132Y654270D01*
G01X163501Y653972D02*
X162684Y655138D01*
G01X162132Y654270D02*
X160714Y654519D01*
G01X162684Y655138D02*
X160492Y655523D01*
G01X162132Y654270D02*
X160714Y654519D01*
G01D02*
X160191Y654154D01*
G01X160492Y655523D02*
X159323Y654708D01*
G01X155812Y653729D02*
X155447Y654250D01*
G01X156816Y653952D02*
X155999Y655118D01*
G01X155447Y654250D02*
X154029Y654499D01*
G01X155999Y655118D02*
X153806Y655503D01*
G01X155447Y654250D02*
X154029Y654499D01*
G01D02*
X153506Y654133D01*
G01X153806Y655503D02*
X152638Y654686D01*
G01X149132Y653752D02*
X148767Y654273D01*
G01X150136Y653974D02*
X149320Y655141D01*
G01X148767Y654273D02*
X147350Y654522D01*
G01X149320Y655141D02*
X147128Y655526D01*
G01X148767Y654273D02*
X147350Y654522D01*
G01D02*
X146827Y654156D01*
G01X147128Y655526D02*
X145959Y654709D01*
G01X142451Y653750D02*
X142086Y654271D01*
G01X143455Y653973D02*
X142638Y655139D01*
G01X142086Y654271D02*
X140670Y654519D01*
G01X142638Y655139D02*
X140447Y655523D01*
G01X142086Y654271D02*
X140670Y654519D01*
G01D02*
X140146Y654153D01*
G01X140447Y655523D02*
X139278Y654706D01*
G01X135767Y653735D02*
X135402Y654258D01*
G01X136771Y653957D02*
X135956Y655126D01*
G01X135402Y654258D02*
X133986Y654507D01*
G01X135956Y655126D02*
X133763Y655511D01*
G01X135402Y654258D02*
X133986Y654507D01*
G01D02*
X133463Y654141D01*
G01X133763Y655511D02*
X132595Y654694D01*
G01X133463Y654141D02*
X132759Y650154D01*
G01X132595Y654694D02*
X131815Y650276D01*
G01X129100Y653827D02*
X128735Y654349D01*
G01X130104Y654050D02*
X129287Y655217D01*
G01X128735Y654349D02*
X127315Y654598D01*
G01X129287Y655217D02*
X127092Y655602D01*
G01X128735Y654349D02*
X127315Y654598D01*
G01D02*
X126795Y654234D01*
G01X127092Y655602D02*
X125927Y654787D01*
G01X122422Y653861D02*
X122059Y654381D01*
G01X123426Y654083D02*
X122613Y655249D01*
G01X122059Y654381D02*
X120638Y654631D01*
G01X122613Y655249D02*
X120415Y655635D01*
G01X122059Y654381D02*
X120638Y654631D01*
G01D02*
X120118Y654267D01*
G01X120415Y655635D02*
X119250Y654820D01*
G01X115740Y653845D02*
X115364Y654380D01*
G01X116745Y654069D02*
X115916Y655248D01*
G01X115364Y654380D02*
X113968Y654626D01*
G01X115916Y655248D02*
X113745Y655631D01*
G01X115364Y654380D02*
X113968Y654626D01*
G01D02*
X113435Y654253D01*
G01X113745Y655631D02*
X112567Y654806D01*
G01X109058Y653856D02*
X108694Y654376D01*
G01X110062Y654079D02*
X109246Y655244D01*
G01X170179Y653956D02*
X169364Y655125D01*
G01X169175Y653734D02*
X168810Y654257D01*
G01X169364Y655125D02*
X167170Y655510D01*
G01D02*
X166002Y654693D01*
G01X168810Y654257D02*
X167393Y654506D01*
G01X167170Y655510D02*
X166002Y654693D01*
G01X167393Y654506D02*
X166870Y654140D01*
G01X163501Y653972D02*
X162684Y655138D01*
G01X162497Y653749D02*
X162132Y654270D01*
G01X162684Y655138D02*
X160492Y655523D01*
G01D02*
X159323Y654708D01*
G01X162132Y654270D02*
X160714Y654519D01*
G01X160492Y655523D02*
X159323Y654708D01*
G01X160714Y654519D02*
X160191Y654154D01*
G01X156816Y653952D02*
X155999Y655118D01*
G01X155812Y653729D02*
X155447Y654250D01*
G01X155999Y655118D02*
X153806Y655503D01*
G01D02*
X152638Y654686D01*
G01X155447Y654250D02*
X154029Y654499D01*
G01X153806Y655503D02*
X152638Y654686D01*
G01X154029Y654499D02*
X153506Y654133D01*
G01X150136Y653974D02*
X149320Y655141D01*
G01X149132Y653752D02*
X148767Y654273D01*
G01X149320Y655141D02*
X147128Y655526D01*
G01D02*
X145959Y654709D01*
G01X148767Y654273D02*
X147350Y654522D01*
G01X147128Y655526D02*
X145959Y654709D01*
G01X147350Y654522D02*
X146827Y654156D01*
G01X143455Y653973D02*
X142638Y655139D01*
G01X142451Y653750D02*
X142086Y654271D01*
G01X142638Y655139D02*
X140447Y655523D01*
G01D02*
X139278Y654706D01*
G01X142086Y654271D02*
X140670Y654519D01*
G01X140447Y655523D02*
X139278Y654706D01*
G01X140670Y654519D02*
X140146Y654153D01*
G01X136771Y653957D02*
X135956Y655126D01*
G01X135767Y653735D02*
X135402Y654258D01*
G01X135956Y655126D02*
X133763Y655511D01*
G01D02*
X132595Y654694D01*
G01X135402Y654258D02*
X133986Y654507D01*
G01X133763Y655511D02*
X132595Y654694D01*
G01X133986Y654507D02*
X133463Y654141D01*
G01X132595Y654694D02*
X131815Y650276D01*
G01X133463Y654141D02*
X132759Y650154D01*
G01X130104Y654050D02*
X129287Y655217D01*
G01X129100Y653827D02*
X128735Y654349D01*
G01X129287Y655217D02*
X127092Y655602D01*
G01D02*
X125927Y654787D01*
G01X128735Y654349D02*
X127315Y654598D01*
G01X127092Y655602D02*
X125927Y654787D01*
G01X127315Y654598D02*
X126795Y654234D01*
G01X123426Y654083D02*
X122613Y655249D01*
G01X122422Y653861D02*
X122059Y654381D01*
G01X122613Y655249D02*
X120415Y655635D01*
G01D02*
X119250Y654820D01*
G01X122059Y654381D02*
X120638Y654631D01*
G01X120415Y655635D02*
X119250Y654820D01*
G01X120638Y654631D02*
X120118Y654267D01*
G01X116745Y654069D02*
X115916Y655248D01*
G01X115740Y653845D02*
X115364Y654380D01*
G01X115916Y655248D02*
X113745Y655631D01*
G01D02*
X112567Y654806D01*
G01X115364Y654380D02*
X113968Y654626D01*
G01X113745Y655631D02*
X112567Y654806D01*
G01X113968Y654626D02*
X113435Y654253D01*
G01X110062Y654079D02*
X109246Y655244D01*
G01X109058Y653856D02*
X108694Y654376D01*
G01X205190Y649136D02*
X203139D01*
G01D02*
X198869Y649466D01*
G01D02*
X194009Y648653D01*
G01X198827Y650423D02*
X193498Y649531D01*
G01X194009Y648653D02*
X192248Y646487D01*
G01X193498Y649531D02*
X191355Y646895D01*
G01X192248Y646487D02*
X191886Y644432D01*
G01X191355Y646895D02*
X191018Y644986D01*
G01X191886Y644432D02*
X190720Y643619D01*
G01X191018Y644986D02*
X190498Y644623D01*
G01X191886Y644432D02*
X190720Y643619D01*
G01D02*
X188526Y644005D01*
G01X190498Y644623D02*
X189079Y644873D01*
G01X188526Y644005D02*
X187710Y645170D01*
G01X189079Y644873D02*
X188714Y645393D01*
G01X187710Y645170D02*
X189236Y653825D01*
G01X188714Y645393D02*
X190240Y654048D01*
G01X186929Y654229D02*
X185220Y644528D01*
G01X186061Y654782D02*
X184352Y645081D01*
G01X185220Y644528D02*
X184055Y643712D01*
G01X184352Y645081D02*
X183832Y644717D01*
G01X185220Y644528D02*
X184055Y643712D01*
G01D02*
X181861Y644099D01*
G01X183832Y644717D02*
X182414Y644967D01*
G01X181861Y644099D02*
X181045Y645265D01*
G01X182414Y644967D02*
X182050Y645488D01*
G01X181045Y645265D02*
X182556Y653837D01*
G01X182050Y645488D02*
X183560Y654059D01*
G01X180251Y654243D02*
X178539Y644526D01*
G01X179383Y654796D02*
X177671Y645079D01*
G01X178539Y644526D02*
X177373Y643710D01*
G01X177671Y645079D02*
X177151Y644715D01*
G01X178539Y644526D02*
X177373Y643710D01*
G01D02*
X175179Y644097D01*
G01X177151Y644715D02*
X175732Y644965D01*
G01X175179Y644097D02*
X174363Y645261D01*
G01X175732Y644965D02*
X175367Y645484D01*
G01X174363Y645261D02*
X175860Y653756D01*
G01X175367Y645484D02*
X176864Y653978D01*
G01X173553Y654160D02*
X171855Y644514D01*
G01X172685Y654714D02*
X170987Y645067D01*
G01X171855Y644514D02*
X170690Y643698D01*
G01X170987Y645067D02*
X170467Y644702D01*
G01X171855Y644514D02*
X170690Y643698D01*
G01X205190Y649136D02*
X203139D01*
G01D02*
X198869Y649466D01*
G01X198827Y650423D02*
X193498Y649531D01*
G01X198869Y649466D02*
X194009Y648653D01*
G01X193498Y649531D02*
X191355Y646895D01*
G01X194009Y648653D02*
X192248Y646487D01*
G01X191355Y646895D02*
X191018Y644986D01*
G01X192248Y646487D02*
X191886Y644432D01*
G01X191018Y644986D02*
X190498Y644623D01*
G01D02*
X189079Y644873D01*
G01X191886Y644432D02*
X190720Y643619D01*
G01X190498Y644623D02*
X189079Y644873D01*
G01X190720Y643619D02*
X188526Y644005D01*
G01X189079Y644873D02*
X188714Y645393D01*
G01X188526Y644005D02*
X187710Y645170D01*
G01X188714Y645393D02*
X190240Y654048D01*
G01X187710Y645170D02*
X189236Y653825D01*
G01X186061Y654782D02*
X184352Y645081D01*
G01X186929Y654229D02*
X185220Y644528D01*
G01X184352Y645081D02*
X183832Y644717D01*
G01D02*
X182414Y644967D01*
G01X185220Y644528D02*
X184055Y643712D01*
G01X183832Y644717D02*
X182414Y644967D01*
G01X184055Y643712D02*
X181861Y644099D01*
G01X182414Y644967D02*
X182050Y645488D01*
G01X181861Y644099D02*
X181045Y645265D01*
G01X182050Y645488D02*
X183560Y654059D01*
G01X181045Y645265D02*
X182556Y653837D01*
G01X179383Y654796D02*
X177671Y645079D01*
G01X180251Y654243D02*
X178539Y644526D01*
G01X177671Y645079D02*
X177151Y644715D01*
G01D02*
X175732Y644965D01*
G01X178539Y644526D02*
X177373Y643710D01*
G01X177151Y644715D02*
X175732Y644965D01*
G01X177373Y643710D02*
X175179Y644097D01*
G01X175732Y644965D02*
X175367Y645484D01*
G01X175179Y644097D02*
X174363Y645261D01*
G01X175367Y645484D02*
X176864Y653978D01*
G01X174363Y645261D02*
X175860Y653756D01*
G01X172685Y654714D02*
X170987Y645067D01*
G01X173553Y654160D02*
X171855Y644514D01*
G01X170987Y645067D02*
X170467Y644702D01*
G01X171855Y644514D02*
X170690Y643698D01*
G01X205190Y650086D02*
X203176D01*
G01D02*
X198827Y650423D01*
G01X189236Y653825D02*
X188871Y654346D01*
G01X190240Y654048D02*
X189423Y655214D01*
G01X188871Y654346D02*
X187452Y654595D01*
G01X189423Y655214D02*
X187229Y655599D01*
G01X188871Y654346D02*
X187452Y654595D01*
G01D02*
X186929Y654229D01*
G01X187229Y655599D02*
X186061Y654782D01*
G01X182556Y653837D02*
X182191Y654360D01*
G01X183560Y654059D02*
X182745Y655228D01*
G01X182191Y654360D02*
X180774Y654609D01*
G01X182745Y655228D02*
X180551Y655613D01*
G01X182191Y654360D02*
X180774Y654609D01*
G01D02*
X180251Y654243D01*
G01X180551Y655613D02*
X179383Y654796D01*
G01X175860Y653756D02*
X175496Y654277D01*
G01X176864Y653978D02*
X176049Y655145D01*
G01X175496Y654277D02*
X174076Y654525D01*
G01X176049Y655145D02*
X173853Y655529D01*
G01X175496Y654277D02*
X174076Y654525D01*
G01D02*
X173553Y654160D01*
G01X173853Y655529D02*
X172685Y654714D01*
G01X205190Y650086D02*
X203176D01*
G01D02*
X198827Y650423D01*
G01X190240Y654048D02*
X189423Y655214D01*
G01X189236Y653825D02*
X188871Y654346D01*
G01X189423Y655214D02*
X187229Y655599D01*
G01D02*
X186061Y654782D01*
G01X188871Y654346D02*
X187452Y654595D01*
G01X187229Y655599D02*
X186061Y654782D01*
G01X187452Y654595D02*
X186929Y654229D01*
G01X183560Y654059D02*
X182745Y655228D01*
G01X182556Y653837D02*
X182191Y654360D01*
G01X182745Y655228D02*
X180551Y655613D01*
G01D02*
X179383Y654796D01*
G01X182191Y654360D02*
X180774Y654609D01*
G01X180551Y655613D02*
X179383Y654796D01*
G01X180774Y654609D02*
X180251Y654243D01*
G01X176864Y653978D02*
X176049Y655145D01*
G01X175860Y653756D02*
X175496Y654277D01*
G01X176049Y655145D02*
X173853Y655529D01*
G01D02*
X172685Y654714D01*
G01X175496Y654277D02*
X174076Y654525D01*
G01X173853Y655529D02*
X172685Y654714D01*
G01X174076Y654525D02*
X173553Y654160D01*
G01X564693Y234170D02*
X565847D01*
G01X564774Y233220D02*
X565453D01*
G01X565847Y234170D02*
X569173Y230844D01*
G01D02*
X569829D01*
G01X565453Y233220D02*
X568779Y229894D01*
G01X569173Y230844D02*
X569829D01*
G01X568779Y229894D02*
X569525D01*
G01X565176Y237208D02*
X570772D01*
G01X565176Y238158D02*
X571166D01*
G01X570772Y237208D02*
X576011Y231969D01*
G01X571166Y238158D02*
X576405Y232919D01*
G01X576011Y231969D02*
X576999D01*
G01X576405Y232919D02*
X577022D01*
G01X564774Y233220D02*
X565453D01*
G01X564693Y234170D02*
X565847D01*
G01X565453Y233220D02*
X568779Y229894D01*
G01X565847Y234170D02*
X569173Y230844D01*
G01X565453Y233220D02*
X568779Y229894D01*
G01D02*
X569525D01*
G01X569173Y230844D02*
X569829D01*
G01X565176Y238158D02*
X571166D01*
G01X565176Y237208D02*
X570772D01*
G01X571166Y238158D02*
X576405Y232919D01*
G01X570772Y237208D02*
X576011Y231969D01*
G01X576405Y232919D02*
X577022D01*
G01X576011Y231969D02*
X576999D01*
G01X564693Y234170D02*
X565847D01*
G01X564774Y233220D02*
X565453D01*
G01X565847Y234170D02*
X569173Y230844D01*
G01D02*
X569829D01*
G01X565453Y233220D02*
X568779Y229894D01*
G01X569173Y230844D02*
X569829D01*
G01X568779Y229894D02*
X569525D01*
G01X565176Y237208D02*
X570772D01*
G01X565176Y238158D02*
X571166D01*
G01X570772Y237208D02*
X576011Y231969D01*
G01X571166Y238158D02*
X576405Y232919D01*
G01X576011Y231969D02*
X576999D01*
G01X576405Y232919D02*
X577022D01*
G01X565176Y238158D02*
X571166D01*
G01X565176Y237208D02*
X570772D01*
G01X571166Y238158D02*
X576405Y232919D01*
G01X570772Y237208D02*
X576011Y231969D01*
G01X576405Y232919D02*
X577022D01*
G01X576011Y231969D02*
X576999D01*
G01X564774Y233220D02*
X565453D01*
G01X564693Y234170D02*
X565847D01*
G01X565453Y233220D02*
X568779Y229894D01*
G01X565847Y234170D02*
X569173Y230844D01*
G01X565453Y233220D02*
X568779Y229894D01*
G01D02*
X569525D01*
G01X569173Y230844D02*
X569829D01*
G01X554756Y287871D02*
X556952D01*
G01X554100Y288821D02*
X556558D01*
G01X556952Y287871D02*
X557493Y288412D01*
G01X556558Y288821D02*
X557099Y289362D01*
G01X557493Y288412D02*
X558868D01*
G01X557099Y289362D02*
X559950D01*
G01X554100Y288821D02*
X556558D01*
G01X554756Y287871D02*
X556952D01*
G01X556558Y288821D02*
X557099Y289362D01*
G01X556952Y287871D02*
X557493Y288412D01*
G01X557099Y289362D02*
X559950D01*
G01X557493Y288412D02*
X558868D01*
G01X554756Y287871D02*
X556952D01*
G01X554100Y288821D02*
X556558D01*
G01X556952Y287871D02*
X557493Y288412D01*
G01X556558Y288821D02*
X557099Y289362D01*
G01X557493Y288412D02*
X558868D01*
G01X557099Y289362D02*
X559950D01*
G01X554100Y288821D02*
X556558D01*
G01X554756Y287871D02*
X556952D01*
G01X556558Y288821D02*
X557099Y289362D01*
G01X556952Y287871D02*
X557493Y288412D01*
G01X557099Y289362D02*
X559950D01*
G01X557493Y288412D02*
X558868D01*
G01X638099Y305000D02*
X638500D01*
G01X638026Y304050D02*
X638450D01*
G01X638026D02*
X638450D01*
G01X638099Y305000D02*
X638500D01*
G01X662430Y337816D02*
Y338625D01*
G01X663380Y339019D02*
X662099Y340300D01*
G01X662430Y338625D02*
X661149Y339906D01*
G01X662099Y340300D02*
Y341530D01*
G01X661149Y339906D02*
Y341350D01*
G01X662430Y337816D02*
Y338625D01*
G01D02*
X661149Y339906D01*
G01X663380Y339019D02*
X662099Y340300D01*
G01X661149Y339906D02*
Y341350D01*
G01X662099Y340300D02*
Y341530D01*
G01X655508Y337892D02*
Y338756D01*
G01X654558Y337558D02*
Y338362D01*
G01X655508Y338756D02*
X654364Y339900D01*
G01X654558Y338362D02*
X653970Y338950D01*
G01X654364Y339900D02*
X652544D01*
G01X653970Y338950D02*
X652150D01*
G01X652544Y339900D02*
X651946Y340498D01*
G01X652150Y338950D02*
X650996Y340104D01*
G01X651946Y340498D02*
Y341390D01*
G01X650996Y340104D02*
Y341404D01*
G01X654558Y337558D02*
Y338362D01*
G01X655508Y337892D02*
Y338756D01*
G01X654558Y338362D02*
X653970Y338950D01*
G01X655508Y338756D02*
X654364Y339900D01*
G01X653970Y338950D02*
X652150D01*
G01X654364Y339900D02*
X652544D01*
G01X652150Y338950D02*
X650996Y340104D01*
G01X652544Y339900D02*
X651946Y340498D01*
G01X650996Y340104D02*
Y341404D01*
G01X651946Y340498D02*
Y341390D01*
G01X649378Y331106D02*
X647822D01*
G01X649241Y330156D02*
X647428D01*
G01X647822Y331106D02*
X646984Y331944D01*
G01X647428Y330156D02*
X646034Y331550D01*
G01X646984Y331944D02*
Y333941D01*
G01X646034Y331550D02*
Y333547D01*
G01X646984Y333941D02*
X645867Y335058D01*
G01X646034Y333547D02*
X645473Y334108D01*
G01X645867Y335058D02*
X644557D01*
G01X645473Y334108D02*
X644521D01*
G01X649241Y330156D02*
X647428D01*
G01X649378Y331106D02*
X647822D01*
G01X647428Y330156D02*
X646034Y331550D01*
G01X647822Y331106D02*
X646984Y331944D01*
G01X646034Y331550D02*
Y333547D01*
G01X646984Y331944D02*
Y333941D01*
G01X646034Y333547D02*
X645473Y334108D01*
G01X646984Y333941D02*
X645867Y335058D01*
G01X645473Y334108D02*
X644521D01*
G01X645867Y335058D02*
X644557D01*
G01X647018Y305244D02*
X644450D01*
G01X647412Y304294D02*
X644928D01*
G01X647412D02*
X644928D01*
G01X647018Y305244D02*
X644450D01*
G01X638099Y305000D02*
X638500D01*
G01X638026Y304050D02*
X638450D01*
G01X638026D02*
X638450D01*
G01X638099Y305000D02*
X638500D01*
G01X652074Y350464D02*
Y346158D01*
G01X651124Y350464D02*
Y346261D01*
G01Y350464D02*
Y346261D01*
G01X652074Y350464D02*
Y346158D01*
G01X662120Y350150D02*
Y346700D01*
G01X661170Y350310D02*
Y346700D01*
G01Y350310D02*
Y346700D01*
G01X662120Y350150D02*
Y346700D01*
G01Y350150D02*
Y346700D01*
G01X661170Y350310D02*
Y346700D01*
G01Y350310D02*
Y346700D01*
G01X662120Y350150D02*
Y346700D01*
G01X652074Y350464D02*
Y346158D01*
G01X651124Y350464D02*
Y346261D01*
G01Y350464D02*
Y346261D01*
G01X652074Y350464D02*
Y346158D01*
G01X663799Y653755D02*
X662105Y644135D01*
G01X662931Y654308D02*
X661237Y644688D01*
G01X662105Y644135D02*
X660937Y643318D01*
G01X661237Y644688D02*
X660714Y644322D01*
G01X662105Y644135D02*
X660937Y643318D01*
G01D02*
X658743Y643703D01*
G01X660714Y644322D02*
X659297Y644571D01*
G01X658743Y643703D02*
X657928Y644872D01*
G01X659297Y644571D02*
X658932Y645094D01*
G01X657928Y644872D02*
X659422Y653355D01*
G01X658932Y645094D02*
X660427Y653578D01*
G01X657120Y653761D02*
X655422Y644114D01*
G01X656252Y654314D02*
X654554Y644668D01*
G01X655422Y644114D02*
X654254Y643299D01*
G01X654554Y644668D02*
X654031Y644303D01*
G01X655422Y644114D02*
X654254Y643299D01*
G01D02*
X652058Y643683D01*
G01X654031Y644303D02*
X652611Y644551D01*
G01X652058Y643683D02*
X651243Y644850D01*
G01X652611Y644551D02*
X652247Y645072D01*
G01X651243Y644850D02*
X652740Y653344D01*
G01X652247Y645072D02*
X653744Y653567D01*
G01X650436Y653749D02*
X648724Y644032D01*
G01X649568Y654302D02*
X647856Y644585D01*
G01X648724Y644032D02*
X647556Y643215D01*
G01X647856Y644585D02*
X647333Y644219D01*
G01X648724Y644032D02*
X647556Y643215D01*
G01D02*
X645362Y643600D01*
G01X647333Y644219D02*
X645916Y644468D01*
G01X645362Y643600D02*
X644547Y644769D01*
G01X645916Y644468D02*
X645551Y644991D01*
G01X644547Y644769D02*
X646057Y653340D01*
G01X645551Y644991D02*
X647062Y653563D01*
G01X643755Y653747D02*
X642046Y644046D01*
G01X642887Y654300D02*
X641178Y644599D01*
G01X642046Y644046D02*
X640878Y643229D01*
G01X641178Y644599D02*
X640655Y644233D01*
G01X642046Y644046D02*
X640878Y643229D01*
G01D02*
X638684Y643614D01*
G01X640655Y644233D02*
X639236Y644482D01*
G01X638684Y643614D02*
X637867Y644780D01*
G01X639236Y644482D02*
X638871Y645003D01*
G01X637867Y644780D02*
X639393Y653435D01*
G01X638871Y645003D02*
X640397Y653658D01*
G01X636752Y651933D02*
X634609Y649297D01*
G01D02*
X629280Y648405D01*
G01X634098Y650175D02*
X629238Y649362D01*
G01X629280Y648405D02*
X624931Y648742D01*
G01X629238Y649362D02*
X624968Y649692D01*
G01X624931Y648742D02*
X622917D01*
G01X624968Y649692D02*
X622917D01*
G01X662931Y654308D02*
X661237Y644688D01*
G01X663799Y653755D02*
X662105Y644135D01*
G01X661237Y644688D02*
X660714Y644322D01*
G01D02*
X659297Y644571D01*
G01X662105Y644135D02*
X660937Y643318D01*
G01X660714Y644322D02*
X659297Y644571D01*
G01X660937Y643318D02*
X658743Y643703D01*
G01X659297Y644571D02*
X658932Y645094D01*
G01X658743Y643703D02*
X657928Y644872D01*
G01X658932Y645094D02*
X660427Y653578D01*
G01X657928Y644872D02*
X659422Y653355D01*
G01X656252Y654314D02*
X654554Y644668D01*
G01X657120Y653761D02*
X655422Y644114D01*
G01X654554Y644668D02*
X654031Y644303D01*
G01D02*
X652611Y644551D01*
G01X655422Y644114D02*
X654254Y643299D01*
G01X654031Y644303D02*
X652611Y644551D01*
G01X654254Y643299D02*
X652058Y643683D01*
G01X652611Y644551D02*
X652247Y645072D01*
G01X652058Y643683D02*
X651243Y644850D01*
G01X652247Y645072D02*
X653744Y653567D01*
G01X651243Y644850D02*
X652740Y653344D01*
G01X649568Y654302D02*
X647856Y644585D01*
G01X650436Y653749D02*
X648724Y644032D01*
G01X647856Y644585D02*
X647333Y644219D01*
G01D02*
X645916Y644468D01*
G01X648724Y644032D02*
X647556Y643215D01*
G01X647333Y644219D02*
X645916Y644468D01*
G01X647556Y643215D02*
X645362Y643600D01*
G01X645916Y644468D02*
X645551Y644991D01*
G01X645362Y643600D02*
X644547Y644769D01*
G01X645551Y644991D02*
X647062Y653563D01*
G01X644547Y644769D02*
X646057Y653340D01*
G01X642887Y654300D02*
X641178Y644599D01*
G01X643755Y653747D02*
X642046Y644046D01*
G01X641178Y644599D02*
X640655Y644233D01*
G01D02*
X639236Y644482D01*
G01X642046Y644046D02*
X640878Y643229D01*
G01X640655Y644233D02*
X639236Y644482D01*
G01X640878Y643229D02*
X638684Y643614D01*
G01X639236Y644482D02*
X638871Y645003D01*
G01X638684Y643614D02*
X637867Y644780D01*
G01X638871Y645003D02*
X640397Y653658D01*
G01X637867Y644780D02*
X639393Y653435D01*
G01X636752Y651933D02*
X634609Y649297D01*
G01X634098Y650175D02*
X629238Y649362D01*
G01X634609Y649297D02*
X629280Y648405D01*
G01X629238Y649362D02*
X624968Y649692D01*
G01X629280Y648405D02*
X624931Y648742D01*
G01X624968Y649692D02*
X622917D01*
G01X624931Y648742D02*
X622917D01*
G01X664097Y655124D02*
X662931Y654308D01*
G01X659422Y653355D02*
X659058Y653876D01*
G01X660427Y653578D02*
X659611Y654744D01*
G01X659058Y653876D02*
X657640Y654126D01*
G01X659611Y654744D02*
X657417Y655130D01*
G01X659058Y653876D02*
X657640Y654126D01*
G01D02*
X657120Y653761D01*
G01X657417Y655130D02*
X656252Y654314D01*
G01X652740Y653344D02*
X652375Y653863D01*
G01X653744Y653567D02*
X652928Y654731D01*
G01X652375Y653863D02*
X650956Y654113D01*
G01X652928Y654731D02*
X650734Y655118D01*
G01X652375Y653863D02*
X650956Y654113D01*
G01D02*
X650436Y653749D01*
G01X650734Y655118D02*
X649568Y654302D01*
G01X646057Y653340D02*
X645693Y653861D01*
G01X647062Y653563D02*
X646246Y654729D01*
G01X645693Y653861D02*
X644275Y654111D01*
G01X646246Y654729D02*
X644052Y655116D01*
G01X645693Y653861D02*
X644275Y654111D01*
G01D02*
X643755Y653747D01*
G01X644052Y655116D02*
X642887Y654300D01*
G01X639393Y653435D02*
X639028Y653955D01*
G01X640397Y653658D02*
X639581Y654823D01*
G01X639028Y653955D02*
X637609Y654205D01*
G01X639581Y654823D02*
X637387Y655209D01*
G01X639028Y653955D02*
X637609Y654205D01*
G01D02*
X637089Y653842D01*
G01X637387Y655209D02*
X636221Y654396D01*
G01X637089Y653842D02*
X636752Y651933D01*
G01X636221Y654396D02*
X635859Y652341D01*
G01D02*
X634098Y650175D01*
G01X664097Y655124D02*
X662931Y654308D01*
G01X664097Y655124D02*
X662931Y654308D01*
G01X660427Y653578D02*
X659611Y654744D01*
G01X659422Y653355D02*
X659058Y653876D01*
G01X659611Y654744D02*
X657417Y655130D01*
G01D02*
X656252Y654314D01*
G01X659058Y653876D02*
X657640Y654126D01*
G01X657417Y655130D02*
X656252Y654314D01*
G01X657640Y654126D02*
X657120Y653761D01*
G01X653744Y653567D02*
X652928Y654731D01*
G01X652740Y653344D02*
X652375Y653863D01*
G01X652928Y654731D02*
X650734Y655118D01*
G01D02*
X649568Y654302D01*
G01X652375Y653863D02*
X650956Y654113D01*
G01X650734Y655118D02*
X649568Y654302D01*
G01X650956Y654113D02*
X650436Y653749D01*
G01X647062Y653563D02*
X646246Y654729D01*
G01X646057Y653340D02*
X645693Y653861D01*
G01X646246Y654729D02*
X644052Y655116D01*
G01D02*
X642887Y654300D01*
G01X645693Y653861D02*
X644275Y654111D01*
G01X644052Y655116D02*
X642887Y654300D01*
G01X644275Y654111D02*
X643755Y653747D01*
G01X640397Y653658D02*
X639581Y654823D01*
G01X639393Y653435D02*
X639028Y653955D01*
G01X639581Y654823D02*
X637387Y655209D01*
G01D02*
X636221Y654396D01*
G01X639028Y653955D02*
X637609Y654205D01*
G01X637387Y655209D02*
X636221Y654396D01*
G01X637609Y654205D02*
X637089Y653842D01*
G01X636221Y654396D02*
X635859Y652341D01*
G01X637089Y653842D02*
X636752Y651933D01*
G01X635859Y652341D02*
X634098Y650175D01*
G01X663380Y338200D02*
Y339019D01*
G01Y338200D02*
Y339019D01*
G01X695899Y302450D02*
X694519D01*
G01X695799Y303400D02*
X694488D01*
G01X695799D02*
X694488D01*
G01X695899Y302450D02*
X694519D01*
G01X703938Y312700D02*
X703050D01*
G01X702850Y313650D02*
X703838D01*
G01X703938Y312700D02*
X703050D01*
G01X702850Y313650D02*
X703838D01*
G01X702850D02*
X703838D01*
G01X703938Y312700D02*
X703050D01*
G01X702850Y313650D02*
X703838D01*
G01X703938Y312700D02*
X703050D01*
G01X694483Y322525D02*
X697131D01*
G01X694413Y323475D02*
X697131D01*
G01X694413D02*
X697131D01*
G01X694483Y322525D02*
X697131D01*
G01X686011Y304488D02*
X686587D01*
G01X685981Y305438D02*
X686981D01*
G01X686587Y304488D02*
X688556Y302519D01*
G01X686981Y305438D02*
X688950Y303469D01*
G01X686587Y304488D02*
X688556Y302519D01*
G01D02*
X689973D01*
G01X688950Y303469D02*
X689977D01*
G01X685981Y305438D02*
X686981D01*
G01X686011Y304488D02*
X686587D01*
G01X686981Y305438D02*
X688950Y303469D01*
G01D02*
X689977D01*
G01X686587Y304488D02*
X688556Y302519D01*
G01X688950Y303469D02*
X689977D01*
G01X688556Y302519D02*
X689973D01*
G01X689000Y312366D02*
X695634D01*
G01X693962Y313316D02*
X695316D01*
G01X689000Y312366D02*
X695634D01*
G01X686823D02*
X689000D01*
G01X686823Y313316D02*
X693962D01*
G01X689000Y312366D02*
X695634D01*
G01X693962Y313316D02*
X695316D01*
G01X689000Y312366D02*
X695634D01*
G01X686823D02*
X689000D01*
G01X686823Y313316D02*
X693962D01*
G01D02*
X695316D01*
G01X686823D02*
X693962D01*
G01X689000Y312366D02*
X695634D01*
G01X686823Y313316D02*
X693962D01*
G01X686823Y312366D02*
X689000D01*
G01X693962Y313316D02*
X695316D01*
G01X686823D02*
X693962D01*
G01X689000Y312366D02*
X695634D01*
G01X686823Y313316D02*
X693962D01*
G01X686823Y312366D02*
X689000D01*
G01X686670Y322468D02*
X689372D01*
G01X686670Y323418D02*
X689790D01*
G01X686670D02*
X689790D01*
G01X686670Y322468D02*
X689372D01*
G01X671464Y338408D02*
Y338999D01*
G01X670514Y338449D02*
Y339393D01*
G01X671464Y338999D02*
X671984Y339519D01*
G01X670514Y339393D02*
X671034Y339913D01*
G01X671984Y339519D02*
Y340937D01*
G01X671034Y339913D02*
Y340937D01*
G01X670514Y338449D02*
Y339393D01*
G01X671464Y338408D02*
Y338999D01*
G01X670514Y339393D02*
X671034Y339913D01*
G01X671464Y338999D02*
X671984Y339519D01*
G01X671034Y339913D02*
Y340937D01*
G01X671984Y339519D02*
Y340937D01*
G01X695899Y302450D02*
X694519D01*
G01X695799Y303400D02*
X694488D01*
G01X695799D02*
X694488D01*
G01X695899Y302450D02*
X694519D01*
G01X703938Y312700D02*
X703050D01*
G01X702850Y313650D02*
X703838D01*
G01X702850D02*
X703838D01*
G01X703938Y312700D02*
X703050D01*
G01X694483Y322525D02*
X697131D01*
G01X694413Y323475D02*
X697131D01*
G01X694413D02*
X697131D01*
G01X694483Y322525D02*
X697131D01*
G01X672109Y350191D02*
Y346141D01*
G01X671159Y350089D02*
Y346296D01*
G01Y350089D02*
Y346296D01*
G01X672109Y350191D02*
Y346141D01*
G01Y350191D02*
Y346141D01*
G01X671159Y350089D02*
Y346296D01*
G01Y350089D02*
Y346296D01*
G01X672109Y350191D02*
Y346141D01*
G01X725565Y643713D02*
X724749Y644878D01*
G01D02*
X726246Y653373D01*
G01X723940Y653778D02*
X722231Y644077D01*
G01X723072Y654332D02*
X721363Y644630D01*
G01X722231Y644077D02*
X721066Y643262D01*
G01X721363Y644630D02*
X720844Y644267D01*
G01X722231Y644077D02*
X721066Y643262D01*
G01D02*
X718872Y643647D01*
G01X720844Y644267D02*
X719424Y644515D01*
G01X718872Y643647D02*
X718056Y644812D01*
G01X719424Y644515D02*
X719060Y645035D01*
G01X718056Y644812D02*
X719561Y653353D01*
G01X719060Y645035D02*
X720565Y653576D01*
G01X717255Y653757D02*
X715551Y644085D01*
G01X716387Y654310D02*
X714683Y644638D01*
G01X715551Y644085D02*
X714373Y643260D01*
G01X714683Y644638D02*
X714150Y644265D01*
G01X715551Y644085D02*
X714373Y643260D01*
G01D02*
X712202Y643643D01*
G01X714150Y644265D02*
X712754Y644511D01*
G01X712202Y643643D02*
X711373Y644822D01*
G01X712754Y644511D02*
X712378Y645046D01*
G01X711373Y644822D02*
X712881Y653376D01*
G01X712378Y645046D02*
X713885Y653598D01*
G01X710576Y653780D02*
X708868Y644071D01*
G01X709708Y654333D02*
X708000Y644624D01*
G01X708868Y644071D02*
X707703Y643256D01*
G01X708000Y644624D02*
X707480Y644260D01*
G01X708868Y644071D02*
X707703Y643256D01*
G01D02*
X705505Y643642D01*
G01X707480Y644260D02*
X706059Y644510D01*
G01X705505Y643642D02*
X704692Y644808D01*
G01X706059Y644510D02*
X705696Y645030D01*
G01X704692Y644808D02*
X706200Y653374D01*
G01X705696Y645030D02*
X707204Y653597D01*
G01X703895Y653777D02*
X702191Y644104D01*
G01X703027Y654330D02*
X701323Y644657D01*
G01X702191Y644104D02*
X701026Y643289D01*
G01X701323Y644657D02*
X700803Y644293D01*
G01X702191Y644104D02*
X701026Y643289D01*
G01D02*
X698831Y643674D01*
G01X700803Y644293D02*
X699383Y644542D01*
G01X698831Y643674D02*
X698014Y644841D01*
G01X699383Y644542D02*
X699018Y645064D01*
G01X698014Y644841D02*
X699516Y653359D01*
G01X699018Y645064D02*
X700520Y653581D01*
G01X697212Y653765D02*
X695512Y644134D01*
G01X697212Y653765D02*
X695512Y644134D01*
G01X695564Y649900D02*
X694644Y644687D01*
G01X695512Y644134D02*
X694344Y643317D01*
G01X694644Y644687D02*
X694121Y644321D01*
G01X695512Y644134D02*
X694344Y643317D01*
G01D02*
X692151Y643702D01*
G01X694121Y644321D02*
X692705Y644570D01*
G01X692151Y643702D02*
X691336Y644871D01*
G01X692705Y644570D02*
X692340Y645093D01*
G01X691336Y644871D02*
X692838Y653388D01*
G01X692340Y645093D02*
X693842Y653611D01*
G01X690533Y653795D02*
X688829Y644122D01*
G01X689665Y654348D02*
X687961Y644675D01*
G01X688829Y644122D02*
X687660Y643305D01*
G01X687961Y644675D02*
X687437Y644309D01*
G01X688829Y644122D02*
X687660Y643305D01*
G01D02*
X685469Y643689D01*
G01X687437Y644309D02*
X686021Y644557D01*
G01X685469Y643689D02*
X684652Y644855D01*
G01X686021Y644557D02*
X685656Y645078D01*
G01X684652Y644855D02*
X686160Y653422D01*
G01X685656Y645078D02*
X687164Y653644D01*
G01X683856Y653828D02*
X682148Y644119D01*
G01X682988Y654381D02*
X681280Y644672D01*
G01X682148Y644119D02*
X680979Y643302D01*
G01X681280Y644672D02*
X680757Y644306D01*
G01X682148Y644119D02*
X680979Y643302D01*
G01D02*
X678787Y643687D01*
G01X680757Y644306D02*
X679340Y644555D01*
G01X678787Y643687D02*
X677971Y644854D01*
G01X679340Y644555D02*
X678975Y645076D01*
G01X677971Y644854D02*
X679478Y653406D01*
G01X678975Y645076D02*
X680483Y653630D01*
G01X677173Y653814D02*
X675469Y644142D01*
G01X676305Y654367D02*
X674601Y644695D01*
G01X675469Y644142D02*
X674301Y643325D01*
G01X674601Y644695D02*
X674078Y644329D01*
G01X675469Y644142D02*
X674301Y643325D01*
G01D02*
X672108Y643710D01*
G01X674078Y644329D02*
X672660Y644578D01*
G01X672108Y643710D02*
X671291Y644876D01*
G01X672660Y644578D02*
X672295Y645099D01*
G01X671291Y644876D02*
X672796Y653417D01*
G01X672295Y645099D02*
X673800Y653640D01*
G01X670493Y653822D02*
X668784Y644120D01*
G01X669625Y654375D02*
X667916Y644674D01*
G01X668784Y644120D02*
X667615Y643305D01*
G01X667916Y644674D02*
X667393Y644309D01*
G01X668784Y644120D02*
X667615Y643305D01*
G01D02*
X665423Y643690D01*
G01X667393Y644309D02*
X665975Y644558D01*
G01X665423Y643690D02*
X664606Y644856D01*
G01X665975Y644558D02*
X665610Y645079D01*
G01X664606Y644856D02*
X666103Y653351D01*
G01X665610Y645079D02*
X667107Y653574D01*
G01X725565Y643713D02*
X724749Y644878D01*
G01D02*
X726246Y653373D01*
G01X723072Y654332D02*
X721363Y644630D01*
G01X723940Y653778D02*
X722231Y644077D01*
G01X721363Y644630D02*
X720844Y644267D01*
G01D02*
X719424Y644515D01*
G01X722231Y644077D02*
X721066Y643262D01*
G01X720844Y644267D02*
X719424Y644515D01*
G01X721066Y643262D02*
X718872Y643647D01*
G01X719424Y644515D02*
X719060Y645035D01*
G01X718872Y643647D02*
X718056Y644812D01*
G01X719060Y645035D02*
X720565Y653576D01*
G01X718056Y644812D02*
X719561Y653353D01*
G01X716387Y654310D02*
X714683Y644638D01*
G01X717255Y653757D02*
X715551Y644085D01*
G01X714683Y644638D02*
X714150Y644265D01*
G01D02*
X712754Y644511D01*
G01X715551Y644085D02*
X714373Y643260D01*
G01X714150Y644265D02*
X712754Y644511D01*
G01X714373Y643260D02*
X712202Y643643D01*
G01X712754Y644511D02*
X712378Y645046D01*
G01X712202Y643643D02*
X711373Y644822D01*
G01X712378Y645046D02*
X713885Y653598D01*
G01X711373Y644822D02*
X712881Y653376D01*
G01X709708Y654333D02*
X708000Y644624D01*
G01X710576Y653780D02*
X708868Y644071D01*
G01X708000Y644624D02*
X707480Y644260D01*
G01D02*
X706059Y644510D01*
G01X708868Y644071D02*
X707703Y643256D01*
G01X707480Y644260D02*
X706059Y644510D01*
G01X707703Y643256D02*
X705505Y643642D01*
G01X706059Y644510D02*
X705696Y645030D01*
G01X705505Y643642D02*
X704692Y644808D01*
G01X705696Y645030D02*
X707204Y653597D01*
G01X704692Y644808D02*
X706200Y653374D01*
G01X703027Y654330D02*
X701323Y644657D01*
G01X703895Y653777D02*
X702191Y644104D01*
G01X701323Y644657D02*
X700803Y644293D01*
G01D02*
X699383Y644542D01*
G01X702191Y644104D02*
X701026Y643289D01*
G01X700803Y644293D02*
X699383Y644542D01*
G01X701026Y643289D02*
X698831Y643674D01*
G01X699383Y644542D02*
X699018Y645064D01*
G01X698831Y643674D02*
X698014Y644841D01*
G01X699018Y645064D02*
X700520Y653581D01*
G01X698014Y644841D02*
X699516Y653359D01*
G01X695564Y649900D02*
X694644Y644687D01*
G01X697212Y653765D02*
X695512Y644134D01*
G01X694644Y644687D02*
X694121Y644321D01*
G01D02*
X692705Y644570D01*
G01X695512Y644134D02*
X694344Y643317D01*
G01X694121Y644321D02*
X692705Y644570D01*
G01X694344Y643317D02*
X692151Y643702D01*
G01X692705Y644570D02*
X692340Y645093D01*
G01X692151Y643702D02*
X691336Y644871D01*
G01X692340Y645093D02*
X693842Y653611D01*
G01X691336Y644871D02*
X692838Y653388D01*
G01X689665Y654348D02*
X687961Y644675D01*
G01X690533Y653795D02*
X688829Y644122D01*
G01X687961Y644675D02*
X687437Y644309D01*
G01D02*
X686021Y644557D01*
G01X688829Y644122D02*
X687660Y643305D01*
G01X687437Y644309D02*
X686021Y644557D01*
G01X687660Y643305D02*
X685469Y643689D01*
G01X686021Y644557D02*
X685656Y645078D01*
G01X685469Y643689D02*
X684652Y644855D01*
G01X685656Y645078D02*
X687164Y653644D01*
G01X684652Y644855D02*
X686160Y653422D01*
G01X682988Y654381D02*
X681280Y644672D01*
G01X683856Y653828D02*
X682148Y644119D01*
G01X681280Y644672D02*
X680757Y644306D01*
G01D02*
X679340Y644555D01*
G01X682148Y644119D02*
X680979Y643302D01*
G01X680757Y644306D02*
X679340Y644555D01*
G01X680979Y643302D02*
X678787Y643687D01*
G01X679340Y644555D02*
X678975Y645076D01*
G01X678787Y643687D02*
X677971Y644854D01*
G01X678975Y645076D02*
X680483Y653630D01*
G01X677971Y644854D02*
X679478Y653406D01*
G01X676305Y654367D02*
X674601Y644695D01*
G01X677173Y653814D02*
X675469Y644142D01*
G01X674601Y644695D02*
X674078Y644329D01*
G01D02*
X672660Y644578D01*
G01X675469Y644142D02*
X674301Y643325D01*
G01X674078Y644329D02*
X672660Y644578D01*
G01X674301Y643325D02*
X672108Y643710D01*
G01X672660Y644578D02*
X672295Y645099D01*
G01X672108Y643710D02*
X671291Y644876D01*
G01X672295Y645099D02*
X673800Y653640D01*
G01X671291Y644876D02*
X672796Y653417D01*
G01X669625Y654375D02*
X667916Y644674D01*
G01X670493Y653822D02*
X668784Y644120D01*
G01X667916Y644674D02*
X667393Y644309D01*
G01D02*
X665975Y644558D01*
G01X668784Y644120D02*
X667615Y643305D01*
G01X667393Y644309D02*
X665975Y644558D01*
G01X667615Y643305D02*
X665423Y643690D01*
G01X665975Y644558D02*
X665610Y645079D01*
G01X665423Y643690D02*
X664606Y644856D01*
G01X665610Y645079D02*
X667107Y653574D01*
G01X664606Y644856D02*
X666103Y653351D01*
G01X725881Y653894D02*
X724463Y654143D01*
G01X726433Y654762D02*
X724241Y655147D01*
G01X725881Y653894D02*
X724463Y654143D01*
G01D02*
X723940Y653778D01*
G01X724241Y655147D02*
X723072Y654332D01*
G01X719561Y653353D02*
X719196Y653874D01*
G01X720565Y653576D02*
X719748Y654742D01*
G01X719196Y653874D02*
X717778Y654123D01*
G01X719748Y654742D02*
X717555Y655127D01*
G01X719196Y653874D02*
X717778Y654123D01*
G01D02*
X717255Y653757D01*
G01X717555Y655127D02*
X716387Y654310D01*
G01X712881Y653376D02*
X712516Y653897D01*
G01X713885Y653598D02*
X713069Y654765D01*
G01X712516Y653897D02*
X711099Y654146D01*
G01X713069Y654765D02*
X710877Y655150D01*
G01X712516Y653897D02*
X711099Y654146D01*
G01D02*
X710576Y653780D01*
G01X710877Y655150D02*
X709708Y654333D01*
G01X706200Y653374D02*
X705835Y653895D01*
G01X707204Y653597D02*
X706387Y654763D01*
G01X705835Y653895D02*
X704419Y654143D01*
G01X706387Y654763D02*
X704196Y655147D01*
G01X705835Y653895D02*
X704419Y654143D01*
G01D02*
X703895Y653777D01*
G01X704196Y655147D02*
X703027Y654330D01*
G01X699516Y653359D02*
X699151Y653882D01*
G01X700520Y653581D02*
X699705Y654750D01*
G01X699151Y653882D02*
X697735Y654131D01*
G01X699705Y654750D02*
X697512Y655135D01*
G01X699151Y653882D02*
X697735Y654131D01*
G01D02*
X697212Y653765D01*
G01X697512Y655135D02*
X696344Y654318D01*
G01D02*
X695564Y649900D01*
G01X692838Y653388D02*
X692473Y653910D01*
G01X693842Y653611D02*
X693025Y654778D01*
G01X692473Y653910D02*
X691053Y654159D01*
G01X693025Y654778D02*
X690830Y655163D01*
G01X692473Y653910D02*
X691053Y654159D01*
G01D02*
X690533Y653795D01*
G01X690830Y655163D02*
X689665Y654348D01*
G01X686160Y653422D02*
X685797Y653942D01*
G01X687164Y653644D02*
X686351Y654810D01*
G01X685797Y653942D02*
X684376Y654192D01*
G01X686351Y654810D02*
X684153Y655196D01*
G01X685797Y653942D02*
X684376Y654192D01*
G01D02*
X683856Y653828D01*
G01X684153Y655196D02*
X682988Y654381D01*
G01X679478Y653406D02*
X679102Y653941D01*
G01X680483Y653630D02*
X679654Y654809D01*
G01X679102Y653941D02*
X677706Y654187D01*
G01X679654Y654809D02*
X677483Y655192D01*
G01X679102Y653941D02*
X677706Y654187D01*
G01D02*
X677173Y653814D01*
G01X677483Y655192D02*
X676305Y654367D01*
G01X672796Y653417D02*
X672432Y653937D01*
G01X673800Y653640D02*
X672984Y654805D01*
G01X672432Y653937D02*
X671012Y654185D01*
G01X672984Y654805D02*
X670790Y655190D01*
G01X672432Y653937D02*
X671012Y654185D01*
G01D02*
X670493Y653822D01*
G01X670790Y655190D02*
X669625Y654375D01*
G01X666103Y653351D02*
X665739Y653871D01*
G01X667107Y653574D02*
X666291Y654739D01*
G01X665739Y653871D02*
X664319Y654119D01*
G01X666291Y654739D02*
X664097Y655124D01*
G01X665739Y653871D02*
X664319Y654119D01*
G01D02*
X663799Y653755D01*
G01X726433Y654762D02*
X724241Y655147D01*
G01D02*
X723072Y654332D01*
G01X725881Y653894D02*
X724463Y654143D01*
G01X724241Y655147D02*
X723072Y654332D01*
G01X724463Y654143D02*
X723940Y653778D01*
G01X720565Y653576D02*
X719748Y654742D01*
G01X719561Y653353D02*
X719196Y653874D01*
G01X719748Y654742D02*
X717555Y655127D01*
G01D02*
X716387Y654310D01*
G01X719196Y653874D02*
X717778Y654123D01*
G01X717555Y655127D02*
X716387Y654310D01*
G01X717778Y654123D02*
X717255Y653757D01*
G01X713885Y653598D02*
X713069Y654765D01*
G01X712881Y653376D02*
X712516Y653897D01*
G01X713069Y654765D02*
X710877Y655150D01*
G01D02*
X709708Y654333D01*
G01X712516Y653897D02*
X711099Y654146D01*
G01X710877Y655150D02*
X709708Y654333D01*
G01X711099Y654146D02*
X710576Y653780D01*
G01X707204Y653597D02*
X706387Y654763D01*
G01X706200Y653374D02*
X705835Y653895D01*
G01X706387Y654763D02*
X704196Y655147D01*
G01D02*
X703027Y654330D01*
G01X705835Y653895D02*
X704419Y654143D01*
G01X704196Y655147D02*
X703027Y654330D01*
G01X704419Y654143D02*
X703895Y653777D01*
G01X700520Y653581D02*
X699705Y654750D01*
G01X699516Y653359D02*
X699151Y653882D01*
G01X699705Y654750D02*
X697512Y655135D01*
G01D02*
X696344Y654318D01*
G01X699151Y653882D02*
X697735Y654131D01*
G01X697512Y655135D02*
X696344Y654318D01*
G01X697735Y654131D02*
X697212Y653765D01*
G01X696344Y654318D02*
X695564Y649900D01*
G01X693842Y653611D02*
X693025Y654778D01*
G01X692838Y653388D02*
X692473Y653910D01*
G01X693025Y654778D02*
X690830Y655163D01*
G01D02*
X689665Y654348D01*
G01X692473Y653910D02*
X691053Y654159D01*
G01X690830Y655163D02*
X689665Y654348D01*
G01X691053Y654159D02*
X690533Y653795D01*
G01X687164Y653644D02*
X686351Y654810D01*
G01X686160Y653422D02*
X685797Y653942D01*
G01X686351Y654810D02*
X684153Y655196D01*
G01D02*
X682988Y654381D01*
G01X685797Y653942D02*
X684376Y654192D01*
G01X684153Y655196D02*
X682988Y654381D01*
G01X684376Y654192D02*
X683856Y653828D01*
G01X680483Y653630D02*
X679654Y654809D01*
G01X679478Y653406D02*
X679102Y653941D01*
G01X679654Y654809D02*
X677483Y655192D01*
G01D02*
X676305Y654367D01*
G01X679102Y653941D02*
X677706Y654187D01*
G01X677483Y655192D02*
X676305Y654367D01*
G01X677706Y654187D02*
X677173Y653814D01*
G01X673800Y653640D02*
X672984Y654805D01*
G01X672796Y653417D02*
X672432Y653937D01*
G01X672984Y654805D02*
X670790Y655190D01*
G01D02*
X669625Y654375D01*
G01X672432Y653937D02*
X671012Y654185D01*
G01X670790Y655190D02*
X669625Y654375D01*
G01X671012Y654185D02*
X670493Y653822D01*
G01X667107Y653574D02*
X666291Y654739D01*
G01X666103Y653351D02*
X665739Y653871D01*
G01X666291Y654739D02*
X664097Y655124D01*
G01X665739Y653871D02*
X664319Y654119D01*
G01D02*
X663799Y653755D01*
G01X787873Y643239D02*
X785680Y643624D01*
G01X787650Y644243D02*
X786232Y644492D01*
G01X785680Y643624D02*
X784863Y644790D01*
G01X786232Y644492D02*
X785867Y645013D01*
G01X784863Y644790D02*
X786385Y653428D01*
G01X785867Y645013D02*
X787389Y653651D01*
G01X784082Y653833D02*
X782356Y644034D01*
G01X783214Y654386D02*
X781488Y644588D01*
G01X782356Y644034D02*
X781187Y643219D01*
G01X781488Y644588D02*
X780965Y644223D01*
G01X782356Y644034D02*
X781187Y643219D01*
G01D02*
X778995Y643604D01*
G01X780965Y644223D02*
X779547Y644472D01*
G01X778995Y643604D02*
X778178Y644770D01*
G01X779547Y644472D02*
X779182Y644993D01*
G01X778178Y644770D02*
X779692Y653362D01*
G01X779182Y644993D02*
X780696Y653585D01*
G01X777388Y653766D02*
X775680Y644066D01*
G01X776520Y654319D02*
X774812Y644619D01*
G01X775680Y644066D02*
X774512Y643249D01*
G01X774812Y644619D02*
X774289Y644253D01*
G01X775680Y644066D02*
X774512Y643249D01*
G01D02*
X772318Y643634D01*
G01X774289Y644253D02*
X772872Y644502D01*
G01X772318Y643634D02*
X771503Y644803D01*
G01X772872Y644502D02*
X772507Y645025D01*
G01X771503Y644803D02*
X773011Y653366D01*
G01X772507Y645025D02*
X774016Y653589D01*
G01X770709Y653772D02*
X769011Y644125D01*
G01X769841Y654325D02*
X768143Y644679D01*
G01X769011Y644125D02*
X767843Y643310D01*
G01X768143Y644679D02*
X767620Y644314D01*
G01X769011Y644125D02*
X767843Y643310D01*
G01D02*
X765647Y643694D01*
G01X767620Y644314D02*
X766200Y644562D01*
G01X765647Y643694D02*
X764832Y644861D01*
G01X766200Y644562D02*
X765836Y645083D01*
G01X764832Y644861D02*
X766329Y653355D01*
G01X765836Y645083D02*
X767333Y653578D01*
G01X764025Y653760D02*
X762313Y644043D01*
G01X763157Y654313D02*
X761445Y644596D01*
G01X762313Y644043D02*
X761145Y643226D01*
G01X761445Y644596D02*
X760922Y644230D01*
G01X762313Y644043D02*
X761145Y643226D01*
G01D02*
X758951Y643611D01*
G01X760922Y644230D02*
X759505Y644479D01*
G01X758951Y643611D02*
X758136Y644780D01*
G01X759505Y644479D02*
X759140Y645002D01*
G01X758136Y644780D02*
X759646Y653351D01*
G01X759140Y645002D02*
X760651Y653574D01*
G01X757344Y653758D02*
X755635Y644057D01*
G01X756476Y654311D02*
X754767Y644610D01*
G01X755635Y644057D02*
X754469Y643243D01*
G01X754767Y644610D02*
X754247Y644247D01*
G01X755635Y644057D02*
X754469Y643243D01*
G01D02*
X752275Y643629D01*
G01X754247Y644247D02*
X752828Y644497D01*
G01X752275Y643629D02*
X751459Y644794D01*
G01X752828Y644497D02*
X752463Y645017D01*
G01X751459Y644794D02*
X752985Y653449D01*
G01X752463Y645017D02*
X753989Y653672D01*
G01X750678Y653853D02*
X748969Y644152D01*
G01X749810Y654406D02*
X748101Y644705D01*
G01X748969Y644152D02*
X747804Y643336D01*
G01X748101Y644705D02*
X747581Y644341D01*
G01X748969Y644152D02*
X747804Y643336D01*
G01D02*
X745610Y643723D01*
G01X747581Y644341D02*
X746163Y644591D01*
G01X745610Y643723D02*
X744794Y644889D01*
G01X746163Y644591D02*
X745799Y645112D01*
G01X744794Y644889D02*
X746305Y653461D01*
G01X745799Y645112D02*
X747309Y653683D01*
G01X744000Y653867D02*
X742288Y644150D01*
G01X743132Y654420D02*
X741420Y644703D01*
G01X742288Y644150D02*
X741122Y643334D01*
G01X741420Y644703D02*
X740900Y644339D01*
G01X742288Y644150D02*
X741122Y643334D01*
G01D02*
X738928Y643721D01*
G01X740900Y644339D02*
X739481Y644589D01*
G01X738928Y643721D02*
X738112Y644885D01*
G01X739481Y644589D02*
X739116Y645108D01*
G01X738112Y644885D02*
X739609Y653380D01*
G01X739116Y645108D02*
X740613Y653602D01*
G01X737302Y653784D02*
X735604Y644138D01*
G01X736434Y654338D02*
X734736Y644691D01*
G01X735604Y644138D02*
X734439Y643322D01*
G01X734736Y644691D02*
X734216Y644326D01*
G01X735604Y644138D02*
X734439Y643322D01*
G01D02*
X732245Y643708D01*
G01X734216Y644326D02*
X732798Y644576D01*
G01X732245Y643708D02*
X731429Y644874D01*
G01X732798Y644576D02*
X732434Y645097D01*
G01X731429Y644874D02*
X732924Y653358D01*
G01X732434Y645097D02*
X733928Y653580D01*
G01X730619Y653764D02*
X728925Y644144D01*
G01X729751Y654317D02*
X728057Y644697D01*
G01X728925Y644144D02*
X727759Y643328D01*
G01X728057Y644697D02*
X727537Y644333D01*
G01X728925Y644144D02*
X727759Y643328D01*
G01D02*
X725565Y643713D01*
G01X727537Y644333D02*
X726117Y644581D01*
G01D02*
X725753Y645101D01*
G01D02*
X727250Y653596D01*
G01X787650Y644243D02*
X786232Y644492D01*
G01X787650Y644243D02*
X786232Y644492D01*
G01X787873Y643239D02*
X785680Y643624D01*
G01X786232Y644492D02*
X785867Y645013D01*
G01X785680Y643624D02*
X784863Y644790D01*
G01X785867Y645013D02*
X787389Y653651D01*
G01X784863Y644790D02*
X786385Y653428D01*
G01X783214Y654386D02*
X781488Y644588D01*
G01X784082Y653833D02*
X782356Y644034D01*
G01X781488Y644588D02*
X780965Y644223D01*
G01D02*
X779547Y644472D01*
G01X782356Y644034D02*
X781187Y643219D01*
G01X780965Y644223D02*
X779547Y644472D01*
G01X781187Y643219D02*
X778995Y643604D01*
G01X779547Y644472D02*
X779182Y644993D01*
G01X778995Y643604D02*
X778178Y644770D01*
G01X779182Y644993D02*
X780696Y653585D01*
G01X778178Y644770D02*
X779692Y653362D01*
G01X776520Y654319D02*
X774812Y644619D01*
G01X777388Y653766D02*
X775680Y644066D01*
G01X774812Y644619D02*
X774289Y644253D01*
G01D02*
X772872Y644502D01*
G01X775680Y644066D02*
X774512Y643249D01*
G01X774289Y644253D02*
X772872Y644502D01*
G01X774512Y643249D02*
X772318Y643634D01*
G01X772872Y644502D02*
X772507Y645025D01*
G01X772318Y643634D02*
X771503Y644803D01*
G01X772507Y645025D02*
X774016Y653589D01*
G01X771503Y644803D02*
X773011Y653366D01*
G01X769841Y654325D02*
X768143Y644679D01*
G01X770709Y653772D02*
X769011Y644125D01*
G01X768143Y644679D02*
X767620Y644314D01*
G01D02*
X766200Y644562D01*
G01X769011Y644125D02*
X767843Y643310D01*
G01X767620Y644314D02*
X766200Y644562D01*
G01X767843Y643310D02*
X765647Y643694D01*
G01X766200Y644562D02*
X765836Y645083D01*
G01X765647Y643694D02*
X764832Y644861D01*
G01X765836Y645083D02*
X767333Y653578D01*
G01X764832Y644861D02*
X766329Y653355D01*
G01X763157Y654313D02*
X761445Y644596D01*
G01X764025Y653760D02*
X762313Y644043D01*
G01X761445Y644596D02*
X760922Y644230D01*
G01D02*
X759505Y644479D01*
G01X762313Y644043D02*
X761145Y643226D01*
G01X760922Y644230D02*
X759505Y644479D01*
G01X761145Y643226D02*
X758951Y643611D01*
G01X759505Y644479D02*
X759140Y645002D01*
G01X758951Y643611D02*
X758136Y644780D01*
G01X759140Y645002D02*
X760651Y653574D01*
G01X758136Y644780D02*
X759646Y653351D01*
G01X756476Y654311D02*
X754767Y644610D01*
G01X757344Y653758D02*
X755635Y644057D01*
G01X754767Y644610D02*
X754247Y644247D01*
G01D02*
X752828Y644497D01*
G01X755635Y644057D02*
X754469Y643243D01*
G01X754247Y644247D02*
X752828Y644497D01*
G01X754469Y643243D02*
X752275Y643629D01*
G01X752828Y644497D02*
X752463Y645017D01*
G01X752275Y643629D02*
X751459Y644794D01*
G01X752463Y645017D02*
X753989Y653672D01*
G01X751459Y644794D02*
X752985Y653449D01*
G01X749810Y654406D02*
X748101Y644705D01*
G01X750678Y653853D02*
X748969Y644152D01*
G01X748101Y644705D02*
X747581Y644341D01*
G01D02*
X746163Y644591D01*
G01X748969Y644152D02*
X747804Y643336D01*
G01X747581Y644341D02*
X746163Y644591D01*
G01X747804Y643336D02*
X745610Y643723D01*
G01X746163Y644591D02*
X745799Y645112D01*
G01X745610Y643723D02*
X744794Y644889D01*
G01X745799Y645112D02*
X747309Y653683D01*
G01X744794Y644889D02*
X746305Y653461D01*
G01X743132Y654420D02*
X741420Y644703D01*
G01X744000Y653867D02*
X742288Y644150D01*
G01X741420Y644703D02*
X740900Y644339D01*
G01D02*
X739481Y644589D01*
G01X742288Y644150D02*
X741122Y643334D01*
G01X740900Y644339D02*
X739481Y644589D01*
G01X741122Y643334D02*
X738928Y643721D01*
G01X739481Y644589D02*
X739116Y645108D01*
G01X738928Y643721D02*
X738112Y644885D01*
G01X739116Y645108D02*
X740613Y653602D01*
G01X738112Y644885D02*
X739609Y653380D01*
G01X736434Y654338D02*
X734736Y644691D01*
G01X737302Y653784D02*
X735604Y644138D01*
G01X734736Y644691D02*
X734216Y644326D01*
G01D02*
X732798Y644576D01*
G01X735604Y644138D02*
X734439Y643322D01*
G01X734216Y644326D02*
X732798Y644576D01*
G01X734439Y643322D02*
X732245Y643708D01*
G01X732798Y644576D02*
X732434Y645097D01*
G01X732245Y643708D02*
X731429Y644874D01*
G01X732434Y645097D02*
X733928Y653580D01*
G01X731429Y644874D02*
X732924Y653358D01*
G01X729751Y654317D02*
X728057Y644697D01*
G01X730619Y653764D02*
X728925Y644144D01*
G01X728057Y644697D02*
X727537Y644333D01*
G01D02*
X726117Y644581D01*
G01X728925Y644144D02*
X727759Y643328D01*
G01X727537Y644333D02*
X726117Y644581D01*
G01X727759Y643328D02*
X725565Y643713D01*
G01X726117Y644581D02*
X725753Y645101D01*
G01D02*
X727250Y653596D01*
G01X786385Y653428D02*
X786021Y653948D01*
G01X787389Y653651D02*
X786573Y654816D01*
G01X786021Y653948D02*
X784601Y654196D01*
G01X786573Y654816D02*
X784379Y655201D01*
G01X786021Y653948D02*
X784601Y654196D01*
G01D02*
X784082Y653833D01*
G01X784379Y655201D02*
X783214Y654386D01*
G01X779692Y653362D02*
X779328Y653882D01*
G01X780696Y653585D02*
X779880Y654750D01*
G01X779328Y653882D02*
X777908Y654130D01*
G01X779880Y654750D02*
X777686Y655135D01*
G01X779328Y653882D02*
X777908Y654130D01*
G01D02*
X777388Y653766D01*
G01X777686Y655135D02*
X776520Y654319D01*
G01X773011Y653366D02*
X772647Y653887D01*
G01X774016Y653589D02*
X773200Y654755D01*
G01X772647Y653887D02*
X771229Y654137D01*
G01X773200Y654755D02*
X771006Y655141D01*
G01X772647Y653887D02*
X771229Y654137D01*
G01D02*
X770709Y653772D01*
G01X771006Y655141D02*
X769841Y654325D01*
G01X766329Y653355D02*
X765964Y653874D01*
G01X767333Y653578D02*
X766517Y654742D01*
G01X765964Y653874D02*
X764545Y654124D01*
G01X766517Y654742D02*
X764323Y655129D01*
G01X765964Y653874D02*
X764545Y654124D01*
G01D02*
X764025Y653760D01*
G01X764323Y655129D02*
X763157Y654313D01*
G01X759646Y653351D02*
X759282Y653872D01*
G01X760651Y653574D02*
X759835Y654740D01*
G01X759282Y653872D02*
X757864Y654122D01*
G01X759835Y654740D02*
X757641Y655127D01*
G01X759282Y653872D02*
X757864Y654122D01*
G01D02*
X757344Y653758D01*
G01X757641Y655127D02*
X756476Y654311D01*
G01X752985Y653449D02*
X752620Y653970D01*
G01X753989Y653672D02*
X753172Y654838D01*
G01X752620Y653970D02*
X751201Y654219D01*
G01X753172Y654838D02*
X750978Y655223D01*
G01X752620Y653970D02*
X751201Y654219D01*
G01D02*
X750678Y653853D01*
G01X750978Y655223D02*
X749810Y654406D01*
G01X746305Y653461D02*
X745940Y653984D01*
G01X747309Y653683D02*
X746494Y654852D01*
G01X745940Y653984D02*
X744523Y654233D01*
G01X746494Y654852D02*
X744300Y655237D01*
G01X745940Y653984D02*
X744523Y654233D01*
G01D02*
X744000Y653867D01*
G01X744300Y655237D02*
X743132Y654420D01*
G01X739609Y653380D02*
X739245Y653901D01*
G01X740613Y653602D02*
X739798Y654769D01*
G01X739245Y653901D02*
X737825Y654149D01*
G01X739798Y654769D02*
X737602Y655153D01*
G01X739245Y653901D02*
X737825Y654149D01*
G01D02*
X737302Y653784D01*
G01X737602Y655153D02*
X736434Y654338D01*
G01X732924Y653358D02*
X732559Y653881D01*
G01X733928Y653580D02*
X733113Y654749D01*
G01X732559Y653881D02*
X731142Y654130D01*
G01X733113Y654749D02*
X730919Y655134D01*
G01X732559Y653881D02*
X731142Y654130D01*
G01D02*
X730619Y653764D01*
G01X730919Y655134D02*
X729751Y654317D01*
G01X726246Y653373D02*
X725881Y653894D01*
G01X727250Y653596D02*
X726433Y654762D01*
G01X787389Y653651D02*
X786573Y654816D01*
G01X786385Y653428D02*
X786021Y653948D01*
G01X786573Y654816D02*
X784379Y655201D01*
G01D02*
X783214Y654386D01*
G01X786021Y653948D02*
X784601Y654196D01*
G01X784379Y655201D02*
X783214Y654386D01*
G01X784601Y654196D02*
X784082Y653833D01*
G01X780696Y653585D02*
X779880Y654750D01*
G01X779692Y653362D02*
X779328Y653882D01*
G01X779880Y654750D02*
X777686Y655135D01*
G01D02*
X776520Y654319D01*
G01X779328Y653882D02*
X777908Y654130D01*
G01X777686Y655135D02*
X776520Y654319D01*
G01X777908Y654130D02*
X777388Y653766D01*
G01X774016Y653589D02*
X773200Y654755D01*
G01X773011Y653366D02*
X772647Y653887D01*
G01X773200Y654755D02*
X771006Y655141D01*
G01D02*
X769841Y654325D01*
G01X772647Y653887D02*
X771229Y654137D01*
G01X771006Y655141D02*
X769841Y654325D01*
G01X771229Y654137D02*
X770709Y653772D01*
G01X767333Y653578D02*
X766517Y654742D01*
G01X766329Y653355D02*
X765964Y653874D01*
G01X766517Y654742D02*
X764323Y655129D01*
G01D02*
X763157Y654313D01*
G01X765964Y653874D02*
X764545Y654124D01*
G01X764323Y655129D02*
X763157Y654313D01*
G01X764545Y654124D02*
X764025Y653760D01*
G01X760651Y653574D02*
X759835Y654740D01*
G01X759646Y653351D02*
X759282Y653872D01*
G01X759835Y654740D02*
X757641Y655127D01*
G01D02*
X756476Y654311D01*
G01X759282Y653872D02*
X757864Y654122D01*
G01X757641Y655127D02*
X756476Y654311D01*
G01X757864Y654122D02*
X757344Y653758D01*
G01X753989Y653672D02*
X753172Y654838D01*
G01X752985Y653449D02*
X752620Y653970D01*
G01X753172Y654838D02*
X750978Y655223D01*
G01D02*
X749810Y654406D01*
G01X752620Y653970D02*
X751201Y654219D01*
G01X750978Y655223D02*
X749810Y654406D01*
G01X751201Y654219D02*
X750678Y653853D01*
G01X747309Y653683D02*
X746494Y654852D01*
G01X746305Y653461D02*
X745940Y653984D01*
G01X746494Y654852D02*
X744300Y655237D01*
G01D02*
X743132Y654420D01*
G01X745940Y653984D02*
X744523Y654233D01*
G01X744300Y655237D02*
X743132Y654420D01*
G01X744523Y654233D02*
X744000Y653867D01*
G01X740613Y653602D02*
X739798Y654769D01*
G01X739609Y653380D02*
X739245Y653901D01*
G01X739798Y654769D02*
X737602Y655153D01*
G01D02*
X736434Y654338D01*
G01X739245Y653901D02*
X737825Y654149D01*
G01X737602Y655153D02*
X736434Y654338D01*
G01X737825Y654149D02*
X737302Y653784D01*
G01X733928Y653580D02*
X733113Y654749D01*
G01X732924Y653358D02*
X732559Y653881D01*
G01X733113Y654749D02*
X730919Y655134D01*
G01D02*
X729751Y654317D01*
G01X732559Y653881D02*
X731142Y654130D01*
G01X730919Y655134D02*
X729751Y654317D01*
G01X731142Y654130D02*
X730619Y653764D01*
G01X727250Y653596D02*
X726433Y654762D01*
G01X726246Y653373D02*
X725881Y653894D01*
G01X906282Y-46582D02*
X803509D01*
G01X905888Y-47532D02*
X803509D01*
G01X905888D02*
X803509D01*
G01X906282Y-46582D02*
X803509D01*
G01X850029Y654370D02*
X848320Y644668D01*
G01X849188Y644115D02*
X848023Y643300D01*
G01X848320Y644668D02*
X847801Y644305D01*
G01X849188Y644115D02*
X848023Y643300D01*
G01D02*
X845829Y643685D01*
G01X847801Y644305D02*
X846381Y644553D01*
G01X845829Y643685D02*
X845013Y644850D01*
G01X846381Y644553D02*
X846017Y645073D01*
G01X845013Y644850D02*
X846518Y653391D01*
G01X846017Y645073D02*
X847522Y653614D01*
G01X844212Y653795D02*
X842508Y644123D01*
G01X843344Y654348D02*
X841640Y644676D01*
G01X842508Y644123D02*
X841330Y643298D01*
G01X841640Y644676D02*
X841107Y644303D01*
G01X842508Y644123D02*
X841330Y643298D01*
G01D02*
X839159Y643681D01*
G01X841107Y644303D02*
X839711Y644549D01*
G01X839159Y643681D02*
X838330Y644860D01*
G01X839711Y644549D02*
X839335Y645084D01*
G01X838330Y644860D02*
X839838Y653414D01*
G01X839335Y645084D02*
X840842Y653636D01*
G01X837533Y653818D02*
X835825Y644109D01*
G01X836665Y654371D02*
X834957Y644662D01*
G01X835825Y644109D02*
X834660Y643294D01*
G01X834957Y644662D02*
X834437Y644298D01*
G01X835825Y644109D02*
X834660Y643294D01*
G01D02*
X832462Y643680D01*
G01X834437Y644298D02*
X833016Y644548D01*
G01X832462Y643680D02*
X831649Y644846D01*
G01X833016Y644548D02*
X832653Y645068D01*
G01X831649Y644846D02*
X833157Y653412D01*
G01X832653Y645068D02*
X834161Y653635D01*
G01X830852Y653815D02*
X829148Y644142D01*
G01X829984Y654368D02*
X828280Y644695D01*
G01X829148Y644142D02*
X827983Y643327D01*
G01X828280Y644695D02*
X827760Y644331D01*
G01X829148Y644142D02*
X827983Y643327D01*
G01D02*
X825788Y643712D01*
G01X827760Y644331D02*
X826340Y644580D01*
G01X825788Y643712D02*
X824971Y644879D01*
G01X826340Y644580D02*
X825975Y645102D01*
G01X824971Y644879D02*
X826473Y653397D01*
G01X825975Y645102D02*
X827477Y653619D01*
G01X824169Y653803D02*
X823465Y649816D01*
G01X823301Y654356D02*
X822311Y648746D01*
G01X823465Y649816D02*
X822458Y644109D01*
G01X822311Y648746D02*
X821590Y644662D01*
G01X822458Y644109D02*
X821292Y643293D01*
G01X821590Y644662D02*
X821070Y644298D01*
G01X822458Y644109D02*
X821292Y643293D01*
G01D02*
X819098Y643678D01*
G01X821070Y644298D02*
X819650Y644546D01*
G01X819098Y643678D02*
X818282Y644843D01*
G01X819650Y644546D02*
X819286Y645066D01*
G01X818282Y644843D02*
X819796Y653435D01*
G01X819286Y645066D02*
X820800Y653658D01*
G01X817490Y653840D02*
X815764Y644042D01*
G01X816622Y654394D02*
X814896Y644595D01*
G01X815764Y644042D02*
X814599Y643227D01*
G01X814896Y644595D02*
X814377Y644232D01*
G01X815764Y644042D02*
X814599Y643227D01*
G01D02*
X812405Y643612D01*
G01X814377Y644232D02*
X812957Y644480D01*
G01X812405Y643612D02*
X811589Y644777D01*
G01X812957Y644480D02*
X812593Y645000D01*
G01X811589Y644777D02*
X813111Y653415D01*
G01X812593Y645000D02*
X814115Y653638D01*
G01X810805Y653819D02*
X809084Y644050D01*
G01X809937Y654372D02*
X808216Y644603D01*
G01X809084Y644050D02*
X807906Y643225D01*
G01X808216Y644603D02*
X807683Y644230D01*
G01X809084Y644050D02*
X807906Y643225D01*
G01D02*
X805735Y643608D01*
G01X807683Y644230D02*
X806287Y644476D01*
G01X805735Y643608D02*
X804906Y644787D01*
G01X806287Y644476D02*
X805911Y645011D01*
G01X804906Y644787D02*
X806431Y653438D01*
G01X805911Y645011D02*
X807435Y653660D01*
G01X804126Y653842D02*
X802418Y644133D01*
G01X803258Y654395D02*
X801550Y644686D01*
G01X802418Y644133D02*
X801253Y643318D01*
G01X801550Y644686D02*
X801030Y644322D01*
G01X802418Y644133D02*
X801253Y643318D01*
G01D02*
X799055Y643704D01*
G01X801030Y644322D02*
X799609Y644572D01*
G01X799055Y643704D02*
X798242Y644870D01*
G01X799609Y644572D02*
X799246Y645092D01*
G01X798242Y644870D02*
X799750Y653436D01*
G01X799246Y645092D02*
X800754Y653659D01*
G01X797445Y653839D02*
X795723Y644050D01*
G01X796577Y654392D02*
X794855Y644603D01*
G01X795723Y644050D02*
X794554Y643233D01*
G01X794855Y644603D02*
X794332Y644237D01*
G01X795723Y644050D02*
X794554Y643233D01*
G01D02*
X792362Y643618D01*
G01X794332Y644237D02*
X792915Y644486D01*
G01X792362Y643618D02*
X791546Y644785D01*
G01X792915Y644486D02*
X792550Y645007D01*
G01X791546Y644785D02*
X793067Y653417D01*
G01X792550Y645007D02*
X794072Y653641D01*
G01X790762Y653825D02*
X789041Y644056D01*
G01X789894Y654378D02*
X788173Y644609D01*
G01X789041Y644056D02*
X787873Y643239D01*
G01X788173Y644609D02*
X787650Y644243D01*
G01X789041Y644056D02*
X787873Y643239D01*
G01X850029Y654370D02*
X848320Y644668D01*
G01D02*
X847801Y644305D01*
G01D02*
X846381Y644553D01*
G01X849188Y644115D02*
X848023Y643300D01*
G01X847801Y644305D02*
X846381Y644553D01*
G01X848023Y643300D02*
X845829Y643685D01*
G01X846381Y644553D02*
X846017Y645073D01*
G01X845829Y643685D02*
X845013Y644850D01*
G01X846017Y645073D02*
X847522Y653614D01*
G01X845013Y644850D02*
X846518Y653391D01*
G01X843344Y654348D02*
X841640Y644676D01*
G01X844212Y653795D02*
X842508Y644123D01*
G01X841640Y644676D02*
X841107Y644303D01*
G01D02*
X839711Y644549D01*
G01X842508Y644123D02*
X841330Y643298D01*
G01X841107Y644303D02*
X839711Y644549D01*
G01X841330Y643298D02*
X839159Y643681D01*
G01X839711Y644549D02*
X839335Y645084D01*
G01X839159Y643681D02*
X838330Y644860D01*
G01X839335Y645084D02*
X840842Y653636D01*
G01X838330Y644860D02*
X839838Y653414D01*
G01X836665Y654371D02*
X834957Y644662D01*
G01X837533Y653818D02*
X835825Y644109D01*
G01X834957Y644662D02*
X834437Y644298D01*
G01D02*
X833016Y644548D01*
G01X835825Y644109D02*
X834660Y643294D01*
G01X834437Y644298D02*
X833016Y644548D01*
G01X834660Y643294D02*
X832462Y643680D01*
G01X833016Y644548D02*
X832653Y645068D01*
G01X832462Y643680D02*
X831649Y644846D01*
G01X832653Y645068D02*
X834161Y653635D01*
G01X831649Y644846D02*
X833157Y653412D01*
G01X829984Y654368D02*
X828280Y644695D01*
G01X830852Y653815D02*
X829148Y644142D01*
G01X828280Y644695D02*
X827760Y644331D01*
G01D02*
X826340Y644580D01*
G01X829148Y644142D02*
X827983Y643327D01*
G01X827760Y644331D02*
X826340Y644580D01*
G01X827983Y643327D02*
X825788Y643712D01*
G01X826340Y644580D02*
X825975Y645102D01*
G01X825788Y643712D02*
X824971Y644879D01*
G01X825975Y645102D02*
X827477Y653619D01*
G01X824971Y644879D02*
X826473Y653397D01*
G01X823301Y654356D02*
X822311Y648746D01*
G01X824169Y653803D02*
X823465Y649816D01*
G01X822311Y648746D02*
X821590Y644662D01*
G01X823465Y649816D02*
X822458Y644109D01*
G01X821590Y644662D02*
X821070Y644298D01*
G01D02*
X819650Y644546D01*
G01X822458Y644109D02*
X821292Y643293D01*
G01X821070Y644298D02*
X819650Y644546D01*
G01X821292Y643293D02*
X819098Y643678D01*
G01X819650Y644546D02*
X819286Y645066D01*
G01X819098Y643678D02*
X818282Y644843D01*
G01X819286Y645066D02*
X820800Y653658D01*
G01X818282Y644843D02*
X819796Y653435D01*
G01X816622Y654394D02*
X814896Y644595D01*
G01X817490Y653840D02*
X815764Y644042D01*
G01X814896Y644595D02*
X814377Y644232D01*
G01D02*
X812957Y644480D01*
G01X815764Y644042D02*
X814599Y643227D01*
G01X814377Y644232D02*
X812957Y644480D01*
G01X814599Y643227D02*
X812405Y643612D01*
G01X812957Y644480D02*
X812593Y645000D01*
G01X812405Y643612D02*
X811589Y644777D01*
G01X812593Y645000D02*
X814115Y653638D01*
G01X811589Y644777D02*
X813111Y653415D01*
G01X809937Y654372D02*
X808216Y644603D01*
G01X810805Y653819D02*
X809084Y644050D01*
G01X808216Y644603D02*
X807683Y644230D01*
G01D02*
X806287Y644476D01*
G01X809084Y644050D02*
X807906Y643225D01*
G01X807683Y644230D02*
X806287Y644476D01*
G01X807906Y643225D02*
X805735Y643608D01*
G01X806287Y644476D02*
X805911Y645011D01*
G01X805735Y643608D02*
X804906Y644787D01*
G01X805911Y645011D02*
X807435Y653660D01*
G01X804906Y644787D02*
X806431Y653438D01*
G01X803258Y654395D02*
X801550Y644686D01*
G01X804126Y653842D02*
X802418Y644133D01*
G01X801550Y644686D02*
X801030Y644322D01*
G01D02*
X799609Y644572D01*
G01X802418Y644133D02*
X801253Y643318D01*
G01X801030Y644322D02*
X799609Y644572D01*
G01X801253Y643318D02*
X799055Y643704D01*
G01X799609Y644572D02*
X799246Y645092D01*
G01X799055Y643704D02*
X798242Y644870D01*
G01X799246Y645092D02*
X800754Y653659D01*
G01X798242Y644870D02*
X799750Y653436D01*
G01X796577Y654392D02*
X794855Y644603D01*
G01X797445Y653839D02*
X795723Y644050D01*
G01X794855Y644603D02*
X794332Y644237D01*
G01D02*
X792915Y644486D01*
G01X795723Y644050D02*
X794554Y643233D01*
G01X794332Y644237D02*
X792915Y644486D01*
G01X794554Y643233D02*
X792362Y643618D01*
G01X792915Y644486D02*
X792550Y645007D01*
G01X792362Y643618D02*
X791546Y644785D01*
G01X792550Y645007D02*
X794072Y653641D01*
G01X791546Y644785D02*
X793067Y653417D01*
G01X789894Y654378D02*
X788173Y644609D01*
G01X790762Y653825D02*
X789041Y644056D01*
G01X788173Y644609D02*
X787650Y644243D01*
G01X789041Y644056D02*
X787873Y643239D01*
G01X846518Y653391D02*
X846153Y653912D01*
G01X847522Y653614D02*
X846705Y654780D01*
G01X846153Y653912D02*
X844735Y654161D01*
G01X846705Y654780D02*
X844512Y655165D01*
G01X846153Y653912D02*
X844735Y654161D01*
G01D02*
X844212Y653795D01*
G01X844512Y655165D02*
X843344Y654348D01*
G01X839838Y653414D02*
X839473Y653935D01*
G01X840842Y653636D02*
X840026Y654803D01*
G01X839473Y653935D02*
X838056Y654184D01*
G01X840026Y654803D02*
X837834Y655188D01*
G01X839473Y653935D02*
X838056Y654184D01*
G01D02*
X837533Y653818D01*
G01X837834Y655188D02*
X836665Y654371D01*
G01X833157Y653412D02*
X832792Y653933D01*
G01X834161Y653635D02*
X833344Y654801D01*
G01X832792Y653933D02*
X831376Y654181D01*
G01X833344Y654801D02*
X831153Y655185D01*
G01X832792Y653933D02*
X831376Y654181D01*
G01D02*
X830852Y653815D01*
G01X831153Y655185D02*
X829984Y654368D01*
G01X826473Y653397D02*
X826108Y653920D01*
G01X827477Y653619D02*
X826662Y654788D01*
G01X826108Y653920D02*
X824692Y654169D01*
G01X826662Y654788D02*
X824469Y655173D01*
G01X826108Y653920D02*
X824692Y654169D01*
G01D02*
X824169Y653803D01*
G01X824469Y655173D02*
X823301Y654356D01*
G01X819796Y653435D02*
X819431Y653956D01*
G01X820800Y653658D02*
X819983Y654824D01*
G01X819431Y653956D02*
X818013Y654205D01*
G01X819983Y654824D02*
X817791Y655209D01*
G01X819431Y653956D02*
X818013Y654205D01*
G01D02*
X817490Y653840D01*
G01X817791Y655209D02*
X816622Y654394D01*
G01X813111Y653415D02*
X812746Y653936D01*
G01X814115Y653638D02*
X813298Y654804D01*
G01X812746Y653936D02*
X811328Y654185D01*
G01X813298Y654804D02*
X811105Y655189D01*
G01X812746Y653936D02*
X811328Y654185D01*
G01D02*
X810805Y653819D01*
G01X811105Y655189D02*
X809937Y654372D01*
G01X806431Y653438D02*
X806066Y653959D01*
G01X807435Y653660D02*
X806619Y654827D01*
G01X806066Y653959D02*
X804649Y654208D01*
G01X806619Y654827D02*
X804427Y655212D01*
G01X806066Y653959D02*
X804649Y654208D01*
G01D02*
X804126Y653842D01*
G01X804427Y655212D02*
X803258Y654395D01*
G01X799750Y653436D02*
X799385Y653957D01*
G01X800754Y653659D02*
X799937Y654825D01*
G01X799385Y653957D02*
X797969Y654205D01*
G01X799937Y654825D02*
X797746Y655209D01*
G01X799385Y653957D02*
X797969Y654205D01*
G01D02*
X797445Y653839D01*
G01X797746Y655209D02*
X796577Y654392D01*
G01X793067Y653417D02*
X792691Y653952D01*
G01X794072Y653641D02*
X793243Y654820D01*
G01X792691Y653952D02*
X791295Y654198D01*
G01X793243Y654820D02*
X791072Y655203D01*
G01X792691Y653952D02*
X791295Y654198D01*
G01D02*
X790762Y653825D01*
G01X791072Y655203D02*
X789894Y654378D01*
G01X847522Y653614D02*
X846705Y654780D01*
G01X846518Y653391D02*
X846153Y653912D01*
G01X846705Y654780D02*
X844512Y655165D01*
G01D02*
X843344Y654348D01*
G01X846153Y653912D02*
X844735Y654161D01*
G01X844512Y655165D02*
X843344Y654348D01*
G01X844735Y654161D02*
X844212Y653795D01*
G01X840842Y653636D02*
X840026Y654803D01*
G01X839838Y653414D02*
X839473Y653935D01*
G01X840026Y654803D02*
X837834Y655188D01*
G01D02*
X836665Y654371D01*
G01X839473Y653935D02*
X838056Y654184D01*
G01X837834Y655188D02*
X836665Y654371D01*
G01X838056Y654184D02*
X837533Y653818D01*
G01X834161Y653635D02*
X833344Y654801D01*
G01X833157Y653412D02*
X832792Y653933D01*
G01X833344Y654801D02*
X831153Y655185D01*
G01D02*
X829984Y654368D01*
G01X832792Y653933D02*
X831376Y654181D01*
G01X831153Y655185D02*
X829984Y654368D01*
G01X831376Y654181D02*
X830852Y653815D01*
G01X827477Y653619D02*
X826662Y654788D01*
G01X826473Y653397D02*
X826108Y653920D01*
G01X826662Y654788D02*
X824469Y655173D01*
G01D02*
X823301Y654356D01*
G01X826108Y653920D02*
X824692Y654169D01*
G01X824469Y655173D02*
X823301Y654356D01*
G01X824692Y654169D02*
X824169Y653803D01*
G01X820800Y653658D02*
X819983Y654824D01*
G01X819796Y653435D02*
X819431Y653956D01*
G01X819983Y654824D02*
X817791Y655209D01*
G01D02*
X816622Y654394D01*
G01X819431Y653956D02*
X818013Y654205D01*
G01X817791Y655209D02*
X816622Y654394D01*
G01X818013Y654205D02*
X817490Y653840D01*
G01X814115Y653638D02*
X813298Y654804D01*
G01X813111Y653415D02*
X812746Y653936D01*
G01X813298Y654804D02*
X811105Y655189D01*
G01D02*
X809937Y654372D01*
G01X812746Y653936D02*
X811328Y654185D01*
G01X811105Y655189D02*
X809937Y654372D01*
G01X811328Y654185D02*
X810805Y653819D01*
G01X807435Y653660D02*
X806619Y654827D01*
G01X806431Y653438D02*
X806066Y653959D01*
G01X806619Y654827D02*
X804427Y655212D01*
G01D02*
X803258Y654395D01*
G01X806066Y653959D02*
X804649Y654208D01*
G01X804427Y655212D02*
X803258Y654395D01*
G01X804649Y654208D02*
X804126Y653842D01*
G01X800754Y653659D02*
X799937Y654825D01*
G01X799750Y653436D02*
X799385Y653957D01*
G01X799937Y654825D02*
X797746Y655209D01*
G01D02*
X796577Y654392D01*
G01X799385Y653957D02*
X797969Y654205D01*
G01X797746Y655209D02*
X796577Y654392D01*
G01X797969Y654205D02*
X797445Y653839D01*
G01X794072Y653641D02*
X793243Y654820D01*
G01X793067Y653417D02*
X792691Y653952D01*
G01X793243Y654820D02*
X791072Y655203D01*
G01D02*
X789894Y654378D01*
G01X792691Y653952D02*
X791295Y654198D01*
G01X791072Y655203D02*
X789894Y654378D01*
G01X791295Y654198D02*
X790762Y653825D01*
G01X910581Y-50881D02*
X906282Y-46582D01*
G01X910187Y-51831D02*
X905888Y-47532D01*
G01X910187Y-51831D02*
X905888Y-47532D01*
G01X910581Y-50881D02*
X906282Y-46582D01*
G01X895896Y648798D02*
X893845D01*
G01X895896Y649748D02*
X893882D01*
G01X893845Y648798D02*
X889575Y649128D01*
G01X893882Y649748D02*
X889533Y650085D01*
G01X889575Y649128D02*
X884715Y648315D01*
G01X889533Y650085D02*
X884204Y649193D01*
G01X884715Y648315D02*
X882954Y646149D01*
G01X884204Y649193D02*
X882061Y646557D01*
G01X882954Y646149D02*
X882592Y644094D01*
G01X882061Y646557D02*
X881724Y644648D01*
G01X882592Y644094D02*
X881426Y643281D01*
G01X881724Y644648D02*
X881204Y644285D01*
G01X882592Y644094D02*
X881426Y643281D01*
G01D02*
X879232Y643667D01*
G01X881204Y644285D02*
X879785Y644535D01*
G01X879232Y643667D02*
X878416Y644832D01*
G01X879785Y644535D02*
X879420Y645055D01*
G01X878416Y644832D02*
X879942Y653487D01*
G01X879420Y645055D02*
X880946Y653710D01*
G01X877635Y653891D02*
X875926Y644190D01*
G01X876767Y654444D02*
X875058Y644743D01*
G01X875926Y644190D02*
X874761Y643374D01*
G01X875058Y644743D02*
X874538Y644379D01*
G01X875926Y644190D02*
X874761Y643374D01*
G01D02*
X872567Y643761D01*
G01X874538Y644379D02*
X873120Y644629D01*
G01X872567Y643761D02*
X871751Y644927D01*
G01X873120Y644629D02*
X872756Y645150D01*
G01X871751Y644927D02*
X873262Y653499D01*
G01X872756Y645150D02*
X874266Y653721D01*
G01X870957Y653905D02*
X869245Y644188D01*
G01X870089Y654458D02*
X868377Y644741D01*
G01X869245Y644188D02*
X868079Y643372D01*
G01X868377Y644741D02*
X867857Y644377D01*
G01X869245Y644188D02*
X868079Y643372D01*
G01D02*
X865885Y643759D01*
G01X867857Y644377D02*
X866438Y644627D01*
G01X865885Y643759D02*
X865069Y644923D01*
G01X866438Y644627D02*
X866073Y645146D01*
G01X865069Y644923D02*
X866566Y653418D01*
G01X866073Y645146D02*
X867570Y653640D01*
G01X864259Y653822D02*
X862561Y644176D01*
G01X863391Y654376D02*
X861693Y644729D01*
G01X862561Y644176D02*
X861396Y643360D01*
G01X861693Y644729D02*
X861173Y644364D01*
G01X862561Y644176D02*
X861396Y643360D01*
G01D02*
X859202Y643746D01*
G01X861173Y644364D02*
X859755Y644614D01*
G01X859202Y643746D02*
X858386Y644912D01*
G01X859755Y644614D02*
X859391Y645135D01*
G01X858386Y644912D02*
X859881Y653396D01*
G01X859391Y645135D02*
X860885Y653618D01*
G01X857576Y653802D02*
X855882Y644182D01*
G01X856708Y654355D02*
X855014Y644735D01*
G01X855882Y644182D02*
X854716Y643366D01*
G01X855014Y644735D02*
X854494Y644371D01*
G01X855882Y644182D02*
X854716Y643366D01*
G01D02*
X852522Y643751D01*
G01X854494Y644371D02*
X853074Y644619D01*
G01X852522Y643751D02*
X851706Y644916D01*
G01X853074Y644619D02*
X852710Y645139D01*
G01X851706Y644916D02*
X853203Y653411D01*
G01X852710Y645139D02*
X854207Y653634D01*
G01X850897Y653816D02*
X849188Y644115D01*
G01X895896Y649748D02*
X893882D01*
G01X895896Y648798D02*
X893845D01*
G01X893882Y649748D02*
X889533Y650085D01*
G01X893845Y648798D02*
X889575Y649128D01*
G01X889533Y650085D02*
X884204Y649193D01*
G01X889575Y649128D02*
X884715Y648315D01*
G01X884204Y649193D02*
X882061Y646557D01*
G01X884715Y648315D02*
X882954Y646149D01*
G01X882061Y646557D02*
X881724Y644648D01*
G01X882954Y646149D02*
X882592Y644094D01*
G01X881724Y644648D02*
X881204Y644285D01*
G01D02*
X879785Y644535D01*
G01X882592Y644094D02*
X881426Y643281D01*
G01X881204Y644285D02*
X879785Y644535D01*
G01X881426Y643281D02*
X879232Y643667D01*
G01X879785Y644535D02*
X879420Y645055D01*
G01X879232Y643667D02*
X878416Y644832D01*
G01X879420Y645055D02*
X880946Y653710D01*
G01X878416Y644832D02*
X879942Y653487D01*
G01X876767Y654444D02*
X875058Y644743D01*
G01X877635Y653891D02*
X875926Y644190D01*
G01X875058Y644743D02*
X874538Y644379D01*
G01D02*
X873120Y644629D01*
G01X875926Y644190D02*
X874761Y643374D01*
G01X874538Y644379D02*
X873120Y644629D01*
G01X874761Y643374D02*
X872567Y643761D01*
G01X873120Y644629D02*
X872756Y645150D01*
G01X872567Y643761D02*
X871751Y644927D01*
G01X872756Y645150D02*
X874266Y653721D01*
G01X871751Y644927D02*
X873262Y653499D01*
G01X870089Y654458D02*
X868377Y644741D01*
G01X870957Y653905D02*
X869245Y644188D01*
G01X868377Y644741D02*
X867857Y644377D01*
G01D02*
X866438Y644627D01*
G01X869245Y644188D02*
X868079Y643372D01*
G01X867857Y644377D02*
X866438Y644627D01*
G01X868079Y643372D02*
X865885Y643759D01*
G01X866438Y644627D02*
X866073Y645146D01*
G01X865885Y643759D02*
X865069Y644923D01*
G01X866073Y645146D02*
X867570Y653640D01*
G01X865069Y644923D02*
X866566Y653418D01*
G01X863391Y654376D02*
X861693Y644729D01*
G01X864259Y653822D02*
X862561Y644176D01*
G01X861693Y644729D02*
X861173Y644364D01*
G01D02*
X859755Y644614D01*
G01X862561Y644176D02*
X861396Y643360D01*
G01X861173Y644364D02*
X859755Y644614D01*
G01X861396Y643360D02*
X859202Y643746D01*
G01X859755Y644614D02*
X859391Y645135D01*
G01X859202Y643746D02*
X858386Y644912D01*
G01X859391Y645135D02*
X860885Y653618D01*
G01X858386Y644912D02*
X859881Y653396D01*
G01X856708Y654355D02*
X855014Y644735D01*
G01X857576Y653802D02*
X855882Y644182D01*
G01X855014Y644735D02*
X854494Y644371D01*
G01D02*
X853074Y644619D01*
G01X855882Y644182D02*
X854716Y643366D01*
G01X854494Y644371D02*
X853074Y644619D01*
G01X854716Y643366D02*
X852522Y643751D01*
G01X853074Y644619D02*
X852710Y645139D01*
G01X852522Y643751D02*
X851706Y644916D01*
G01X852710Y645139D02*
X854207Y653634D01*
G01X851706Y644916D02*
X853203Y653411D01*
G01X850897Y653816D02*
X849188Y644115D01*
G01X879942Y653487D02*
X879577Y654008D01*
G01X880946Y653710D02*
X880129Y654876D01*
G01X879577Y654008D02*
X878158Y654257D01*
G01X880129Y654876D02*
X877935Y655261D01*
G01X879577Y654008D02*
X878158Y654257D01*
G01D02*
X877635Y653891D01*
G01X877935Y655261D02*
X876767Y654444D01*
G01X873262Y653499D02*
X872897Y654022D01*
G01X874266Y653721D02*
X873451Y654890D01*
G01X872897Y654022D02*
X871480Y654271D01*
G01X873451Y654890D02*
X871257Y655275D01*
G01X872897Y654022D02*
X871480Y654271D01*
G01D02*
X870957Y653905D01*
G01X871257Y655275D02*
X870089Y654458D01*
G01X866566Y653418D02*
X866202Y653939D01*
G01X867570Y653640D02*
X866755Y654807D01*
G01X866202Y653939D02*
X864782Y654187D01*
G01X866755Y654807D02*
X864559Y655191D01*
G01X866202Y653939D02*
X864782Y654187D01*
G01D02*
X864259Y653822D01*
G01X864559Y655191D02*
X863391Y654376D01*
G01X859881Y653396D02*
X859516Y653919D01*
G01X860885Y653618D02*
X860070Y654787D01*
G01X859516Y653919D02*
X858099Y654168D01*
G01X860070Y654787D02*
X857876Y655172D01*
G01X859516Y653919D02*
X858099Y654168D01*
G01D02*
X857576Y653802D01*
G01X857876Y655172D02*
X856708Y654355D01*
G01X853203Y653411D02*
X852838Y653932D01*
G01X854207Y653634D02*
X853390Y654800D01*
G01X852838Y653932D02*
X851420Y654181D01*
G01X853390Y654800D02*
X851198Y655185D01*
G01X852838Y653932D02*
X851420Y654181D01*
G01D02*
X850897Y653816D01*
G01X851198Y655185D02*
X850029Y654370D01*
G01X880946Y653710D02*
X880129Y654876D01*
G01X879942Y653487D02*
X879577Y654008D01*
G01X880129Y654876D02*
X877935Y655261D01*
G01D02*
X876767Y654444D01*
G01X879577Y654008D02*
X878158Y654257D01*
G01X877935Y655261D02*
X876767Y654444D01*
G01X878158Y654257D02*
X877635Y653891D01*
G01X874266Y653721D02*
X873451Y654890D01*
G01X873262Y653499D02*
X872897Y654022D01*
G01X873451Y654890D02*
X871257Y655275D01*
G01D02*
X870089Y654458D01*
G01X872897Y654022D02*
X871480Y654271D01*
G01X871257Y655275D02*
X870089Y654458D01*
G01X871480Y654271D02*
X870957Y653905D01*
G01X867570Y653640D02*
X866755Y654807D01*
G01X866566Y653418D02*
X866202Y653939D01*
G01X866755Y654807D02*
X864559Y655191D01*
G01D02*
X863391Y654376D01*
G01X866202Y653939D02*
X864782Y654187D01*
G01X864559Y655191D02*
X863391Y654376D01*
G01X864782Y654187D02*
X864259Y653822D01*
G01X860885Y653618D02*
X860070Y654787D01*
G01X859881Y653396D02*
X859516Y653919D01*
G01X860070Y654787D02*
X857876Y655172D01*
G01D02*
X856708Y654355D01*
G01X859516Y653919D02*
X858099Y654168D01*
G01X857876Y655172D02*
X856708Y654355D01*
G01X858099Y654168D02*
X857576Y653802D01*
G01X854207Y653634D02*
X853390Y654800D01*
G01X853203Y653411D02*
X852838Y653932D01*
G01X853390Y654800D02*
X851198Y655185D01*
G01D02*
X850029Y654370D01*
G01X852838Y653932D02*
X851420Y654181D01*
G01X851198Y655185D02*
X850029Y654370D01*
G01X851420Y654181D02*
X850897Y653816D01*
G01X1107118Y-41481D02*
X914200D01*
G01X1107118Y-42431D02*
X914200D01*
G01Y-41481D02*
G03Y-47131I0J-2825D01*
G01Y-42431D02*
G03Y-46181I0J-1875D01*
G01Y-47131D02*
X1108549D01*
G01X914200Y-46181D02*
X1108550D01*
G01X1108549Y-50881D02*
X910581D01*
G01X1108550Y-51831D02*
X910187D01*
G01X1107118Y-42431D02*
X914200D01*
G01X1107118Y-41481D02*
X914200D01*
G01Y-42431D02*
G03Y-46181I0J-1875D01*
G01Y-41481D02*
G03Y-47131I0J-2825D01*
G01Y-46181D02*
X1108550D01*
G01X914200Y-47131D02*
X1108549D01*
G01X1108550Y-51831D02*
X910187D01*
G01X1108549Y-50881D02*
X910581D01*
G01X1108549Y-47131D02*
G02Y-50881I0J-1875D01*
G01X1108550Y-46181D02*
G02Y-51831I0J-2825D01*
G01Y-46181D02*
G02Y-51831I0J-2825D01*
G01X1108549Y-47131D02*
G02Y-50881I0J-1875D01*
G01X1231749Y260500D02*
X1211373Y289058D01*
G01X1231749Y260500D02*
X1211373Y289058D01*
G01X1231749Y260500D02*
X1211373Y289058D01*
G01X1231749Y260500D02*
X1211373Y289058D01*
G01X1232428Y261186D02*
X1212147Y289609D01*
G01X1214187Y314371D02*
X1215485D01*
G01X1214187Y315321D02*
X1215879D01*
G01X1215485Y314371D02*
X1227456Y302400D01*
G01X1215879Y315321D02*
X1228180Y303020D01*
G01X1217332Y308743D02*
X1243227Y272436D01*
G01X1216558Y308192D02*
X1242549Y271749D01*
G01X1214640Y304281D02*
X1239851Y268936D01*
G01X1215414Y304832D02*
X1240529Y269623D01*
G01X1213297Y299525D02*
X1237098Y266159D01*
G01X1237776Y266846D02*
X1214071Y300076D01*
G01X1235135Y263994D02*
X1211199Y297547D01*
G01X1210425Y296996D02*
X1234456Y263307D01*
G01X1232428Y261186D02*
X1212147Y289609D01*
G01X1243457Y325089D02*
X1217293Y338571D01*
G01X1244103Y325826D02*
X1217524Y339521D01*
G01X1217293Y338571D02*
X1211124D01*
G01X1217524Y339521D02*
X1211124D01*
G01X1216518Y334671D02*
X1240382Y322378D01*
G01X1241026Y323115D02*
X1216749Y335621D01*
G01X1214220Y334671D02*
X1216518D01*
G01X1216749Y335621D02*
X1214220D01*
G01X1219604Y328800D02*
X1207722D01*
G01X1219835Y329750D02*
X1207766D01*
G01X1213251Y324921D02*
X1218824D01*
G01X1219055Y325871D02*
X1213164D01*
G01X1216119Y321021D02*
X1218032D01*
G01X1216206Y321971D02*
X1218263D01*
G01X1218032Y321021D02*
X1230003Y314857D01*
G01X1218263Y321971D02*
X1230643Y315597D01*
G01X1217894Y316850D02*
X1217322D01*
G01Y317800D02*
X1218199D01*
G01X1229102Y308840D02*
X1217894Y316850D01*
G01D02*
X1217322D01*
G01X1218199Y317800D02*
X1229784Y309521D01*
G01X1214187Y315321D02*
X1215879D01*
G01X1214187Y314371D02*
X1215485D01*
G01X1215879Y315321D02*
X1228180Y303020D01*
G01X1215485Y314371D02*
X1227456Y302400D01*
G01X1216558Y308192D02*
X1242549Y271749D01*
G01X1217332Y308743D02*
X1243227Y272436D01*
G01X1215414Y304832D02*
X1240529Y269623D01*
G01X1214640Y304281D02*
X1239851Y268936D01*
G01X1237776Y266846D02*
X1214071Y300076D01*
G01X1213297Y299525D02*
X1237098Y266159D01*
G01X1210425Y296996D02*
X1234456Y263307D01*
G01X1235135Y263994D02*
X1211199Y297547D01*
G01X1244103Y325826D02*
X1217524Y339521D01*
G01X1243457Y325089D02*
X1217293Y338571D01*
G01X1217524Y339521D02*
X1211124D01*
G01X1217293Y338571D02*
X1211124D01*
G01X1216749Y335621D02*
X1214220D01*
G01Y334671D02*
X1216518D01*
G01X1241026Y323115D02*
X1216749Y335621D01*
G01X1216518Y334671D02*
X1240382Y322378D01*
G01X1219835Y329750D02*
X1207766D01*
G01X1219604Y328800D02*
X1207722D01*
G01X1219055Y325871D02*
X1213164D01*
G01X1213251Y324921D02*
X1218824D01*
G01X1216206Y321971D02*
X1218263D01*
G01X1216119Y321021D02*
X1218032D01*
G01X1218263Y321971D02*
X1230643Y315597D01*
G01X1218032Y321021D02*
X1230003Y314857D01*
G01X1218199Y317800D02*
X1229784Y309521D01*
G01X1229102Y308840D02*
X1217894Y316850D01*
G01X1217322Y317800D02*
X1218199D01*
G01D02*
X1229784Y309521D01*
G01X1217894Y316850D02*
X1217322D01*
G01X1232428Y261186D02*
X1212147Y289609D01*
G01X1214640Y304281D02*
X1239851Y268936D01*
G01X1215414Y304832D02*
X1240529Y269623D01*
G01X1216518Y334671D02*
X1240382Y322378D01*
G01X1241026Y323115D02*
X1216749Y335621D01*
G01X1214220Y334671D02*
X1216518D01*
G01X1216749Y335621D02*
X1214220D01*
G01X1219604Y328800D02*
X1207722D01*
G01X1219835Y329750D02*
X1207766D01*
G01X1213251Y324921D02*
X1218824D01*
G01X1219055Y325871D02*
X1213164D01*
G01X1217894Y316850D02*
X1217322D01*
G01Y317800D02*
X1218199D01*
G01X1229102Y308840D02*
X1217894Y316850D01*
G01D02*
X1217322D01*
G01X1218199Y317800D02*
X1229784Y309521D01*
G01X1216558Y308192D02*
X1242549Y271749D01*
G01X1217332Y308743D02*
X1243227Y272436D01*
G01X1215414Y304832D02*
X1240529Y269623D01*
G01X1214640Y304281D02*
X1239851Y268936D01*
G01X1216749Y335621D02*
X1214220D01*
G01Y334671D02*
X1216518D01*
G01X1241026Y323115D02*
X1216749Y335621D01*
G01X1216518Y334671D02*
X1240382Y322378D01*
G01X1219835Y329750D02*
X1207766D01*
G01X1219604Y328800D02*
X1207722D01*
G01X1219055Y325871D02*
X1213164D01*
G01X1213251Y324921D02*
X1218824D01*
G01X1218199Y317800D02*
X1229784Y309521D01*
G01X1229102Y308840D02*
X1217894Y316850D01*
G01X1217322Y317800D02*
X1218199D01*
G01D02*
X1229784Y309521D01*
G01X1217894Y316850D02*
X1217322D01*
G01X1243457Y325089D02*
X1217293Y338571D01*
G01X1244103Y325826D02*
X1217524Y339521D01*
G01X1217293Y338571D02*
X1211124D01*
G01X1217524Y339521D02*
X1211124D01*
G01X1244103Y325826D02*
X1217524Y339521D01*
G01X1243457Y325089D02*
X1217293Y338571D01*
G01X1217524Y339521D02*
X1211124D01*
G01X1217293Y338571D02*
X1211124D01*
G01X1214187Y314371D02*
X1215485D01*
G01X1214187Y315321D02*
X1215879D01*
G01X1215485Y314371D02*
X1227456Y302400D01*
G01X1215879Y315321D02*
X1228180Y303020D01*
G01X1217332Y308743D02*
X1243227Y272436D01*
G01X1216558Y308192D02*
X1242549Y271749D01*
G01X1213297Y299525D02*
X1237098Y266159D01*
G01X1237776Y266846D02*
X1214071Y300076D01*
G01X1235135Y263994D02*
X1211199Y297547D01*
G01X1210425Y296996D02*
X1234456Y263307D01*
G01X1214187Y315321D02*
X1215879D01*
G01X1214187Y314371D02*
X1215485D01*
G01X1215879Y315321D02*
X1228180Y303020D01*
G01X1215485Y314371D02*
X1227456Y302400D01*
G01X1237776Y266846D02*
X1214071Y300076D01*
G01X1213297Y299525D02*
X1237098Y266159D01*
G01X1210425Y296996D02*
X1234456Y263307D01*
G01X1235135Y263994D02*
X1211199Y297547D01*
G01X1232428Y261186D02*
X1212147Y289609D01*
G01X1216119Y321021D02*
X1218032D01*
G01X1216206Y321971D02*
X1218263D01*
G01X1218032Y321021D02*
X1230003Y314857D01*
G01X1218263Y321971D02*
X1230643Y315597D01*
G01X1216206Y321971D02*
X1218263D01*
G01X1216119Y321021D02*
X1218032D01*
G01X1218263Y321971D02*
X1230643Y315597D01*
G01X1218032Y321021D02*
X1230003Y314857D01*
G01X1219017Y346388D02*
X1217325D01*
G01X1219247Y347338D02*
X1217325D01*
G01X1245973Y328189D02*
X1218013Y342471D01*
G01X1246617Y328927D02*
X1218242Y343421D01*
G01X1218013Y342471D02*
X1215100D01*
G01X1218242Y343421D02*
X1215187D01*
G01X1219247Y347338D02*
X1217325D01*
G01X1219017Y346388D02*
X1217325D01*
G01X1246617Y328927D02*
X1218242Y343421D01*
G01X1245973Y328189D02*
X1218013Y342471D01*
G01X1218242Y343421D02*
X1215187D01*
G01X1218013Y342471D02*
X1215100D01*
G01X1212085Y401433D02*
X1220616Y409965D01*
G01X1211413Y402105D02*
X1219829Y410523D01*
G01X1220996Y391702D02*
X1218302Y389900D01*
G01X1220243Y392342D02*
X1218013Y390850D01*
G01X1220996Y391702D02*
X1218302Y389900D01*
G01D02*
X1216901D01*
G01X1218013Y390850D02*
X1216901D01*
G01X1215447Y393800D02*
X1216510D01*
G01D02*
X1217391Y394389D01*
G01X1215447Y394750D02*
X1216221D01*
G01X1216510Y393800D02*
X1217391Y394389D01*
G01X1216221Y394750D02*
X1216649Y395036D01*
G01X1217391Y394389D02*
X1226416Y412909D01*
G01X1216649Y395036D02*
X1225670Y413549D01*
G01X1211413Y402105D02*
X1219829Y410523D01*
G01X1212085Y401433D02*
X1220616Y409965D01*
G01X1220243Y392342D02*
X1218013Y390850D01*
G01D02*
X1216901D01*
G01X1220996Y391702D02*
X1218302Y389900D01*
G01X1218013Y390850D02*
X1216901D01*
G01X1218302Y389900D02*
X1216901D01*
G01X1215447Y394750D02*
X1216221D01*
G01X1215447Y393800D02*
X1216510D01*
G01X1215447Y394750D02*
X1216221D01*
G01D02*
X1216649Y395036D01*
G01X1216510Y393800D02*
X1217391Y394389D01*
G01X1216649Y395036D02*
X1225670Y413549D01*
G01X1217391Y394389D02*
X1226416Y412909D01*
G01X1226379Y358541D02*
X1217364D01*
G01X1226616Y359491D02*
X1217364D01*
G01X1230387Y366310D02*
X1217113D01*
G01Y367260D02*
X1230616D01*
G01X1231415Y370192D02*
X1215721D01*
G01X1231644Y371142D02*
X1215721D01*
G01X1217755Y377822D02*
X1221220D01*
G01X1217755Y378772D02*
X1221020D01*
G01X1220207Y381629D02*
X1215795D01*
G01X1220007Y382579D02*
X1215795D01*
G01X1218765Y386437D02*
X1216124D01*
G01X1218965Y385487D02*
X1216124D01*
G01X1226616Y359491D02*
X1217364D01*
G01X1226379Y358541D02*
X1217364D01*
G01X1217113Y367260D02*
X1230616D01*
G01X1230387Y366310D02*
X1217113D01*
G01X1231644Y371142D02*
X1215721D01*
G01X1231415Y370192D02*
X1215721D01*
G01X1217755Y378772D02*
X1221020D01*
G01X1217755Y377822D02*
X1221220D01*
G01X1220007Y382579D02*
X1215795D01*
G01X1220207Y381629D02*
X1215795D01*
G01X1218965Y385487D02*
X1216124D01*
G01X1218765Y386437D02*
X1216124D01*
G01X1219017Y346388D02*
X1217325D01*
G01X1219247Y347338D02*
X1217325D01*
G01X1245973Y328189D02*
X1218013Y342471D01*
G01X1246617Y328927D02*
X1218242Y343421D01*
G01X1218013Y342471D02*
X1215100D01*
G01X1218242Y343421D02*
X1215187D01*
G01X1219247Y347338D02*
X1217325D01*
G01X1219017Y346388D02*
X1217325D01*
G01X1246617Y328927D02*
X1218242Y343421D01*
G01X1245973Y328189D02*
X1218013Y342471D01*
G01X1218242Y343421D02*
X1215187D01*
G01X1218013Y342471D02*
X1215100D01*
G01X1226616Y359491D02*
X1217364D01*
G01X1226379Y358541D02*
X1217364D01*
G01X1230387Y366310D02*
X1217113D01*
G01Y367260D02*
X1230616D01*
G01X1231415Y370192D02*
X1215721D01*
G01X1231644Y371142D02*
X1215721D01*
G01X1217113Y367260D02*
X1230616D01*
G01X1230387Y366310D02*
X1217113D01*
G01X1231644Y371142D02*
X1215721D01*
G01X1231415Y370192D02*
X1215721D01*
G01X1212085Y401433D02*
X1220616Y409965D01*
G01X1211413Y402105D02*
X1219829Y410523D01*
G01X1220996Y391702D02*
X1218302Y389900D01*
G01X1220243Y392342D02*
X1218013Y390850D01*
G01X1220996Y391702D02*
X1218302Y389900D01*
G01D02*
X1216901D01*
G01X1218013Y390850D02*
X1216901D01*
G01X1215447Y393800D02*
X1216510D01*
G01D02*
X1217391Y394389D01*
G01X1215447Y394750D02*
X1216221D01*
G01X1216510Y393800D02*
X1217391Y394389D01*
G01X1216221Y394750D02*
X1216649Y395036D01*
G01X1217391Y394389D02*
X1226416Y412909D01*
G01X1216649Y395036D02*
X1225670Y413549D01*
G01X1211413Y402105D02*
X1219829Y410523D01*
G01X1212085Y401433D02*
X1220616Y409965D01*
G01X1220243Y392342D02*
X1218013Y390850D01*
G01D02*
X1216901D01*
G01X1220996Y391702D02*
X1218302Y389900D01*
G01X1218013Y390850D02*
X1216901D01*
G01X1218302Y389900D02*
X1216901D01*
G01X1215447Y394750D02*
X1216221D01*
G01X1215447Y393800D02*
X1216510D01*
G01X1215447Y394750D02*
X1216221D01*
G01D02*
X1216649Y395036D01*
G01X1216510Y393800D02*
X1217391Y394389D01*
G01X1216649Y395036D02*
X1225670Y413549D01*
G01X1217391Y394389D02*
X1226416Y412909D01*
G01X1226379Y358541D02*
X1217364D01*
G01X1226616Y359491D02*
X1217364D01*
G01X1217755Y377822D02*
X1221220D01*
G01X1217755Y378772D02*
X1221020D01*
G01X1220207Y381629D02*
X1215795D01*
G01X1220007Y382579D02*
X1215795D01*
G01X1218765Y386437D02*
X1216124D01*
G01X1218965Y385487D02*
X1216124D01*
G01X1217755Y378772D02*
X1221020D01*
G01X1217755Y377822D02*
X1221220D01*
G01X1220007Y382579D02*
X1215795D01*
G01X1220207Y381629D02*
X1215795D01*
G01X1218965Y385487D02*
X1216124D01*
G01X1218765Y386437D02*
X1216124D01*
G01X1215840Y412647D02*
X1233714Y447419D01*
G01X1234444Y446760D02*
X1218264Y415282D01*
G01X1215840Y412647D02*
X1233714Y447419D01*
G01X1217235Y413281D02*
X1216618Y412080D01*
G01X1214065Y410871D02*
X1215841Y412647D01*
G01X1216618Y412080D02*
X1214737Y410199D01*
G01X1216185Y419641D02*
X1212179Y415635D01*
G01X1210588Y414044D02*
X1209634Y413089D01*
G01X1208043Y411498D02*
X1206403Y409858D01*
G01X1205731Y410530D02*
X1215399Y420200D01*
G01X1234060Y456651D02*
X1216185Y419641D01*
G01X1215399Y420200D02*
X1233317Y457297D01*
G01X1214746Y425602D02*
X1211943Y422799D01*
G01X1210352Y421208D02*
X1202572Y413428D01*
G01X1201900Y414100D02*
X1213958Y426158D01*
G01X1231450Y460730D02*
X1214746Y425602D01*
G01X1213958Y426158D02*
X1230611Y461180D01*
G01X1229608Y465962D02*
X1212705Y430705D01*
G01X1228851Y466582D02*
X1211918Y431262D01*
G01X1212705Y430705D02*
X1210036Y428036D01*
G01X1208445Y426445D02*
X1207491Y425491D01*
G01X1205900Y423900D02*
X1204945Y422945D01*
G01X1211917Y431262D02*
X1204272Y423616D01*
G01X1195825Y419475D02*
X1206977Y430627D01*
G01X1195153Y420147D02*
X1206187Y431181D01*
G01X1206977Y430627D02*
X1207578Y431891D01*
G01X1208600Y434041D02*
X1224024Y466488D01*
G01X1206187Y431181D02*
X1217335Y454636D01*
G01X1208600Y434041D02*
X1224024Y466488D01*
G01X1217335Y454636D02*
X1223252Y467080D01*
G01X1216618Y412080D02*
X1214737Y410199D01*
G01X1214065Y410871D02*
X1215841Y412647D01*
G01X1234444Y446760D02*
X1218264Y415282D01*
G01X1217235Y413281D02*
X1216618Y412080D01*
G01X1215840Y412647D02*
X1233714Y447419D01*
G01X1215399Y420200D02*
X1233317Y457297D01*
G01X1234060Y456651D02*
X1216185Y419641D01*
G01X1205731Y410530D02*
X1215399Y420200D01*
G01X1216185Y419641D02*
X1212179Y415635D01*
G01X1205731Y410530D02*
X1215399Y420200D01*
G01X1210588Y414044D02*
X1209634Y413089D01*
G01X1205731Y410530D02*
X1215399Y420200D01*
G01X1208043Y411498D02*
X1206403Y409858D01*
G01X1213958Y426158D02*
X1230611Y461180D01*
G01X1231450Y460730D02*
X1214746Y425602D01*
G01X1201900Y414100D02*
X1213958Y426158D01*
G01X1214746Y425602D02*
X1211943Y422799D01*
G01X1201900Y414100D02*
X1213958Y426158D01*
G01X1210352Y421208D02*
X1202572Y413428D01*
G01X1228851Y466582D02*
X1211918Y431262D01*
G01X1229608Y465962D02*
X1212705Y430705D01*
G01X1211917Y431262D02*
X1204272Y423616D01*
G01X1212705Y430705D02*
X1210036Y428036D01*
G01X1211917Y431262D02*
X1204272Y423616D01*
G01X1208445Y426445D02*
X1207491Y425491D01*
G01X1211917Y431262D02*
X1204272Y423616D01*
G01X1205900Y423900D02*
X1204945Y422945D01*
G01X1195153Y420147D02*
X1206187Y431181D01*
G01X1195825Y419475D02*
X1206977Y430627D01*
G01X1206187Y431181D02*
X1217335Y454636D01*
G01X1206977Y430627D02*
X1207578Y431891D01*
G01X1206187Y431181D02*
X1217335Y454636D01*
G01D02*
X1223252Y467080D01*
G01X1208600Y434041D02*
X1224024Y466488D01*
G01X1215840Y412647D02*
X1233714Y447419D01*
G01X1234444Y446760D02*
X1218264Y415282D01*
G01X1215840Y412647D02*
X1233714Y447419D01*
G01X1217235Y413281D02*
X1216618Y412080D01*
G01X1214065Y410871D02*
X1215841Y412647D01*
G01X1216618Y412080D02*
X1214737Y410199D01*
G01X1216185Y419641D02*
X1212179Y415635D01*
G01X1210588Y414044D02*
X1209634Y413089D01*
G01X1208043Y411498D02*
X1206403Y409858D01*
G01X1205731Y410530D02*
X1215399Y420200D01*
G01X1234060Y456651D02*
X1216185Y419641D01*
G01X1215399Y420200D02*
X1233317Y457297D01*
G01X1216618Y412080D02*
X1214737Y410199D01*
G01X1214065Y410871D02*
X1215841Y412647D01*
G01X1234444Y446760D02*
X1218264Y415282D01*
G01X1217235Y413281D02*
X1216618Y412080D01*
G01X1215840Y412647D02*
X1233714Y447419D01*
G01X1214746Y425602D02*
X1211943Y422799D01*
G01X1210352Y421208D02*
X1202572Y413428D01*
G01X1201900Y414100D02*
X1213958Y426158D01*
G01X1231450Y460730D02*
X1214746Y425602D01*
G01X1213958Y426158D02*
X1230611Y461180D01*
G01X1229608Y465962D02*
X1212705Y430705D01*
G01X1228851Y466582D02*
X1211918Y431262D01*
G01X1212705Y430705D02*
X1210036Y428036D01*
G01X1208445Y426445D02*
X1207491Y425491D01*
G01X1205900Y423900D02*
X1204945Y422945D01*
G01X1211917Y431262D02*
X1204272Y423616D01*
G01X1195825Y419475D02*
X1206977Y430627D01*
G01X1195153Y420147D02*
X1206187Y431181D01*
G01X1206977Y430627D02*
X1207578Y431891D01*
G01X1208600Y434041D02*
X1224024Y466488D01*
G01X1206187Y431181D02*
X1217335Y454636D01*
G01X1208600Y434041D02*
X1224024Y466488D01*
G01X1217335Y454636D02*
X1223252Y467080D01*
G01X1215399Y420200D02*
X1233317Y457297D01*
G01X1234060Y456651D02*
X1216185Y419641D01*
G01X1205731Y410530D02*
X1215399Y420200D01*
G01X1216185Y419641D02*
X1212179Y415635D01*
G01X1205731Y410530D02*
X1215399Y420200D01*
G01X1210588Y414044D02*
X1209634Y413089D01*
G01X1205731Y410530D02*
X1215399Y420200D01*
G01X1208043Y411498D02*
X1206403Y409858D01*
G01X1213958Y426158D02*
X1230611Y461180D01*
G01X1231450Y460730D02*
X1214746Y425602D01*
G01X1201900Y414100D02*
X1213958Y426158D01*
G01X1214746Y425602D02*
X1211943Y422799D01*
G01X1201900Y414100D02*
X1213958Y426158D01*
G01X1210352Y421208D02*
X1202572Y413428D01*
G01X1228851Y466582D02*
X1211918Y431262D01*
G01X1229608Y465962D02*
X1212705Y430705D01*
G01X1211917Y431262D02*
X1204272Y423616D01*
G01X1212705Y430705D02*
X1210036Y428036D01*
G01X1211917Y431262D02*
X1204272Y423616D01*
G01X1208445Y426445D02*
X1207491Y425491D01*
G01X1211917Y431262D02*
X1204272Y423616D01*
G01X1205900Y423900D02*
X1204945Y422945D01*
G01X1195153Y420147D02*
X1206187Y431181D01*
G01X1195825Y419475D02*
X1206977Y430627D01*
G01X1206187Y431181D02*
X1217335Y454636D01*
G01X1206977Y430627D02*
X1207578Y431891D01*
G01X1206187Y431181D02*
X1217335Y454636D01*
G01D02*
X1223252Y467080D01*
G01X1208600Y434041D02*
X1224024Y466488D01*
G01X1303911Y188584D02*
X1279928Y207308D01*
G01D02*
X1273225Y212542D01*
G01X1288111Y199713D02*
X1272527Y211880D01*
G01X1273225Y212542D02*
X1265200Y224210D01*
G01X1272527Y211880D02*
X1264417Y223671D01*
G01X1279672Y216874D02*
X1281987Y215066D01*
G01X1253685Y254659D02*
X1279672Y216874D01*
G01X1280372Y217533D02*
X1254369Y255341D01*
G01X1275094Y216642D02*
X1273158Y219456D01*
G01X1248582Y253512D02*
X1274395Y215981D01*
G01X1286850Y207463D02*
X1275094Y216642D01*
G01X1274396Y215981D02*
X1296586Y198653D01*
G01X1303911Y188584D02*
X1279928Y207308D01*
G01X1288111Y199713D02*
X1272527Y211880D01*
G01X1279928Y207308D02*
X1273225Y212542D01*
G01X1272527Y211880D02*
X1264417Y223671D01*
G01X1273225Y212542D02*
X1265200Y224210D01*
G01X1280372Y217533D02*
X1254369Y255341D01*
G01X1253685Y254659D02*
X1279672Y216874D01*
G01D02*
X1281987Y215066D01*
G01X1274396Y215981D02*
X1296586Y198653D01*
G01X1286850Y207463D02*
X1275094Y216642D01*
G01X1248582Y253512D02*
X1274395Y215981D01*
G01X1275094Y216642D02*
X1273158Y219456D01*
G01X1248582Y253512D02*
X1274395Y215981D01*
G01X1303911Y188584D02*
X1279928Y207308D01*
G01X1288111Y199713D02*
X1272527Y211880D01*
G01X1279928Y207308D02*
X1273225Y212542D01*
G01X1272527Y211880D02*
X1264417Y223671D01*
G01X1273225Y212542D02*
X1265200Y224210D01*
G01X1279672Y216874D02*
X1281987Y215066D01*
G01X1253685Y254659D02*
X1279672Y216874D01*
G01X1280372Y217533D02*
X1254369Y255341D01*
G01X1275094Y216642D02*
X1273158Y219456D01*
G01X1248582Y253512D02*
X1274395Y215981D01*
G01X1286850Y207463D02*
X1275094Y216642D01*
G01X1274396Y215981D02*
X1296586Y198653D01*
G01X1280372Y217533D02*
X1254369Y255341D01*
G01X1253685Y254659D02*
X1279672Y216874D01*
G01D02*
X1281987Y215066D01*
G01X1274396Y215981D02*
X1296586Y198653D01*
G01X1286850Y207463D02*
X1275094Y216642D01*
G01X1248582Y253512D02*
X1274395Y215981D01*
G01X1275094Y216642D02*
X1273158Y219456D01*
G01X1248582Y253512D02*
X1274395Y215981D01*
G01X1303911Y188584D02*
X1279928Y207308D01*
G01D02*
X1273225Y212542D01*
G01X1288111Y199713D02*
X1272527Y211880D01*
G01X1273225Y212542D02*
X1265200Y224210D01*
G01X1272527Y211880D02*
X1264417Y223671D01*
G01X1265200Y224210D02*
X1246461Y251456D01*
G01X1264417Y223671D02*
X1245777Y250774D01*
G01X1246461Y251456D02*
X1232428Y261186D01*
G01X1245777Y250774D02*
X1231749Y260500D01*
G01X1227456Y302400D02*
X1246891Y275788D01*
G01X1248218Y273971D02*
X1249475Y272250D01*
G01X1228180Y303020D02*
X1250153Y272934D01*
G01X1249475Y272250D02*
X1266883Y259771D01*
G01X1250153Y272934D02*
X1267572Y260446D01*
G01X1266883Y259771D02*
X1291756Y223606D01*
G01X1267572Y260446D02*
X1292458Y224263D01*
G01X1290284Y220702D02*
X1267805Y253386D01*
G01X1243227Y272436D02*
X1265163Y257227D01*
G01X1242549Y271749D02*
X1264479Y256545D01*
G01X1290284Y220702D02*
X1267805Y253386D01*
G01X1265163Y257227D02*
X1267805Y253386D01*
G01X1264479Y256545D02*
X1284290Y227739D01*
G01X1254526Y258759D02*
X1256357Y257489D01*
G01X1239851Y268936D02*
X1254526Y258759D01*
G01X1245946Y265866D02*
X1257042Y258171D01*
G01X1256357Y257489D02*
X1282219Y219893D01*
G01X1257042Y258171D02*
X1282919Y220552D01*
G01X1239851Y268936D02*
X1254526Y258759D01*
G01X1240529Y269623D02*
X1245946Y265866D01*
G01X1237098Y266159D02*
X1253685Y254659D01*
G01X1254369Y255341D02*
X1237776Y266846D01*
G01X1249266Y254194D02*
X1235135Y263994D01*
G01X1234457Y263307D02*
X1248582Y253512D01*
G01X1273158Y219456D02*
X1249266Y254194D01*
G01X1264417Y223671D02*
X1245777Y250774D01*
G01X1265200Y224210D02*
X1246461Y251456D01*
G01X1245777Y250774D02*
X1231749Y260500D01*
G01X1246461Y251456D02*
X1232428Y261186D01*
G01X1266721Y284758D02*
X1287724Y270188D01*
G01X1288425Y270858D02*
X1267402Y285442D01*
G01X1284040Y268105D02*
X1263698Y282207D01*
G01X1284731Y268782D02*
X1264376Y282894D01*
G01X1278914Y266929D02*
X1309983Y225460D01*
G01X1310564Y226270D02*
X1279582Y267622D01*
G01X1261113Y279272D02*
X1278914Y266929D01*
G01X1279582Y267622D02*
X1261791Y279959D01*
G01X1237316Y312648D02*
X1261113Y279272D01*
G01X1237316Y312648D02*
X1261113Y279272D01*
G01X1230003Y314857D02*
X1256888Y277152D01*
G01X1230643Y315596D02*
X1257566Y277839D01*
G01X1256888Y277152D02*
X1276527Y263536D01*
G01X1257566Y277839D02*
X1277195Y264229D01*
G01X1276527Y263536D02*
X1308511Y220845D01*
G01X1277195Y264229D02*
X1309200Y221511D01*
G01X1254085Y273798D02*
X1252354Y276226D01*
G01D02*
X1229102Y308840D01*
G01X1236150Y300592D02*
X1254763Y274485D01*
G01X1274862Y259393D02*
X1254085Y273798D01*
G01X1254763Y274485D02*
X1275530Y260086D01*
G01X1306990Y216465D02*
X1274862Y259393D01*
G01X1275530Y260086D02*
X1307675Y217136D01*
G01X1252354Y276226D02*
X1229102Y308840D01*
G01X1228180Y303020D02*
X1250153Y272934D01*
G01X1227456Y302400D02*
X1246891Y275788D01*
G01X1228180Y303020D02*
X1250153Y272934D01*
G01X1248218Y273971D02*
X1249475Y272250D01*
G01X1250153Y272934D02*
X1267572Y260446D01*
G01X1249475Y272250D02*
X1266883Y259771D01*
G01X1267572Y260446D02*
X1292458Y224263D01*
G01X1266883Y259771D02*
X1291756Y223606D01*
G01X1264479Y256545D02*
X1284290Y227739D01*
G01X1290284Y220702D02*
X1267805Y253386D01*
G01X1242549Y271749D02*
X1264479Y256545D01*
G01X1243227Y272436D02*
X1265163Y257227D01*
G01X1264479Y256545D02*
X1284290Y227739D01*
G01X1265163Y257227D02*
X1267805Y253386D01*
G01X1245946Y265866D02*
X1257042Y258171D01*
G01X1254526Y258759D02*
X1256357Y257489D01*
G01X1257042Y258171D02*
X1282919Y220552D01*
G01X1256357Y257489D02*
X1282219Y219893D01*
G01X1245946Y265866D02*
X1257042Y258171D01*
G01X1240529Y269623D02*
X1245946Y265866D01*
G01X1239851Y268936D02*
X1254526Y258759D01*
G01X1254369Y255341D02*
X1237776Y266846D01*
G01X1237098Y266159D02*
X1253685Y254659D01*
G01X1273158Y219456D02*
X1249266Y254194D01*
G01X1234457Y263307D02*
X1248582Y253512D01*
G01X1249266Y254194D02*
X1235135Y263994D01*
G01X1288425Y270858D02*
X1267402Y285442D01*
G01X1266721Y284758D02*
X1287724Y270188D01*
G01X1284731Y268782D02*
X1264376Y282894D01*
G01X1284040Y268105D02*
X1263698Y282207D01*
G01X1237316Y312648D02*
X1261113Y279272D01*
G01X1279582Y267622D02*
X1261791Y279959D01*
G01X1261113Y279272D02*
X1278914Y266929D01*
G01X1310564Y226270D02*
X1279582Y267622D01*
G01X1278914Y266929D02*
X1309983Y225460D01*
G01X1230643Y315596D02*
X1257566Y277839D01*
G01X1230003Y314857D02*
X1256888Y277152D01*
G01X1257566Y277839D02*
X1277195Y264229D01*
G01X1256888Y277152D02*
X1276527Y263536D01*
G01X1277195Y264229D02*
X1309200Y221511D01*
G01X1276527Y263536D02*
X1308511Y220845D01*
G01X1275530Y260086D02*
X1307675Y217136D01*
G01X1306990Y216465D02*
X1274862Y259393D01*
G01X1254763Y274485D02*
X1275530Y260086D01*
G01X1274862Y259393D02*
X1254085Y273798D01*
G01X1236150Y300592D02*
X1254763Y274485D01*
G01X1254085Y273798D02*
X1252354Y276226D01*
G01X1236150Y300592D02*
X1254763Y274485D01*
G01X1252354Y276226D02*
X1229102Y308840D01*
G01X1264417Y223671D02*
X1245777Y250774D01*
G01X1265200Y224210D02*
X1246461Y251456D01*
G01X1245777Y250774D02*
X1231749Y260500D01*
G01X1246461Y251456D02*
X1232428Y261186D01*
G01X1254526Y258759D02*
X1256357Y257489D01*
G01X1239851Y268936D02*
X1254526Y258759D01*
G01X1245946Y265866D02*
X1257042Y258171D01*
G01X1256357Y257489D02*
X1282219Y219893D01*
G01X1257042Y258171D02*
X1282919Y220552D01*
G01X1239851Y268936D02*
X1254526Y258759D01*
G01X1240529Y269623D02*
X1245946Y265866D01*
G01X1266721Y284758D02*
X1287724Y270188D01*
G01X1288425Y270858D02*
X1267402Y285442D01*
G01X1284040Y268105D02*
X1263698Y282207D01*
G01X1284731Y268782D02*
X1264376Y282894D01*
G01X1278914Y266929D02*
X1309983Y225460D01*
G01X1310564Y226270D02*
X1279582Y267622D01*
G01X1261113Y279272D02*
X1278914Y266929D01*
G01X1279582Y267622D02*
X1261791Y279959D01*
G01X1237316Y312648D02*
X1261113Y279272D01*
G01X1237316Y312648D02*
X1261113Y279272D01*
G01X1254085Y273798D02*
X1252354Y276226D01*
G01D02*
X1229102Y308840D01*
G01X1236150Y300592D02*
X1254763Y274485D01*
G01X1274862Y259393D02*
X1254085Y273798D01*
G01X1254763Y274485D02*
X1275530Y260086D01*
G01X1306990Y216465D02*
X1274862Y259393D01*
G01X1275530Y260086D02*
X1307675Y217136D01*
G01X1252354Y276226D02*
X1229102Y308840D01*
G01X1264479Y256545D02*
X1284290Y227739D01*
G01X1290284Y220702D02*
X1267805Y253386D01*
G01X1242549Y271749D02*
X1264479Y256545D01*
G01X1243227Y272436D02*
X1265163Y257227D01*
G01X1264479Y256545D02*
X1284290Y227739D01*
G01X1265163Y257227D02*
X1267805Y253386D01*
G01X1245946Y265866D02*
X1257042Y258171D01*
G01X1254526Y258759D02*
X1256357Y257489D01*
G01X1257042Y258171D02*
X1282919Y220552D01*
G01X1256357Y257489D02*
X1282219Y219893D01*
G01X1245946Y265866D02*
X1257042Y258171D01*
G01X1240529Y269623D02*
X1245946Y265866D01*
G01X1239851Y268936D02*
X1254526Y258759D01*
G01X1288425Y270858D02*
X1267402Y285442D01*
G01X1266721Y284758D02*
X1287724Y270188D01*
G01X1284731Y268782D02*
X1264376Y282894D01*
G01X1284040Y268105D02*
X1263698Y282207D01*
G01X1237316Y312648D02*
X1261113Y279272D01*
G01X1279582Y267622D02*
X1261791Y279959D01*
G01X1261113Y279272D02*
X1278914Y266929D01*
G01X1310564Y226270D02*
X1279582Y267622D01*
G01X1278914Y266929D02*
X1309983Y225460D01*
G01X1275530Y260086D02*
X1307675Y217136D01*
G01X1306990Y216465D02*
X1274862Y259393D01*
G01X1254763Y274485D02*
X1275530Y260086D01*
G01X1274862Y259393D02*
X1254085Y273798D01*
G01X1236150Y300592D02*
X1254763Y274485D01*
G01X1254085Y273798D02*
X1252354Y276226D01*
G01X1236150Y300592D02*
X1254763Y274485D01*
G01X1252354Y276226D02*
X1229102Y308840D01*
G01X1227456Y302400D02*
X1246891Y275788D01*
G01X1248218Y273971D02*
X1249475Y272250D01*
G01X1228180Y303020D02*
X1250153Y272934D01*
G01X1249475Y272250D02*
X1266883Y259771D01*
G01X1250153Y272934D02*
X1267572Y260446D01*
G01X1266883Y259771D02*
X1291756Y223606D01*
G01X1267572Y260446D02*
X1292458Y224263D01*
G01X1290284Y220702D02*
X1267805Y253386D01*
G01X1243227Y272436D02*
X1265163Y257227D01*
G01X1242549Y271749D02*
X1264479Y256545D01*
G01X1290284Y220702D02*
X1267805Y253386D01*
G01X1265163Y257227D02*
X1267805Y253386D01*
G01X1264479Y256545D02*
X1284290Y227739D01*
G01X1237098Y266159D02*
X1253685Y254659D01*
G01X1254369Y255341D02*
X1237776Y266846D01*
G01X1249266Y254194D02*
X1235135Y263994D01*
G01X1234457Y263307D02*
X1248582Y253512D01*
G01X1273158Y219456D02*
X1249266Y254194D01*
G01X1228180Y303020D02*
X1250153Y272934D01*
G01X1227456Y302400D02*
X1246891Y275788D01*
G01X1228180Y303020D02*
X1250153Y272934D01*
G01X1248218Y273971D02*
X1249475Y272250D01*
G01X1250153Y272934D02*
X1267572Y260446D01*
G01X1249475Y272250D02*
X1266883Y259771D01*
G01X1267572Y260446D02*
X1292458Y224263D01*
G01X1266883Y259771D02*
X1291756Y223606D01*
G01X1254369Y255341D02*
X1237776Y266846D01*
G01X1237098Y266159D02*
X1253685Y254659D01*
G01X1273158Y219456D02*
X1249266Y254194D01*
G01X1234457Y263307D02*
X1248582Y253512D01*
G01X1249266Y254194D02*
X1235135Y263994D01*
G01X1265200Y224210D02*
X1246461Y251456D01*
G01X1264417Y223671D02*
X1245777Y250774D01*
G01X1246461Y251456D02*
X1232428Y261186D01*
G01X1245777Y250774D02*
X1231749Y260500D01*
G01X1230003Y314857D02*
X1256888Y277152D01*
G01X1230643Y315596D02*
X1257566Y277839D01*
G01X1256888Y277152D02*
X1276527Y263536D01*
G01X1257566Y277839D02*
X1277195Y264229D01*
G01X1276527Y263536D02*
X1308511Y220845D01*
G01X1277195Y264229D02*
X1309200Y221511D01*
G01X1230643Y315596D02*
X1257566Y277839D01*
G01X1230003Y314857D02*
X1256888Y277152D01*
G01X1257566Y277839D02*
X1277195Y264229D01*
G01X1256888Y277152D02*
X1276527Y263536D01*
G01X1277195Y264229D02*
X1309200Y221511D01*
G01X1276527Y263536D02*
X1308511Y220845D01*
G01X1292804Y271830D02*
X1269534Y287619D01*
G01X1293498Y272508D02*
X1270214Y288307D01*
G01X1269534Y287619D02*
X1245219Y322557D01*
G01X1270214Y288307D02*
X1261972Y300150D01*
G01X1269534Y287619D02*
X1245219Y322557D01*
G01D02*
X1243457Y325089D01*
G01X1261972Y300151D02*
X1244103Y325826D01*
G01X1260848Y293146D02*
X1266721Y284758D01*
G01X1267402Y285442D02*
X1265720Y287844D01*
G01X1240382Y322378D02*
X1260848Y293146D01*
G01X1265720Y287844D02*
X1241026Y323115D01*
G01X1263698Y282207D02*
X1248995Y302830D01*
G01X1264376Y282894D02*
X1253964Y297498D01*
G01X1248995Y302830D02*
X1236792Y319946D01*
G01X1253964Y297498D02*
X1237432Y320685D01*
G01X1236792Y319946D02*
X1219604Y328800D01*
G01X1237432Y320685D02*
X1219835Y329750D01*
G01X1261791Y279959D02*
X1254493Y290195D01*
G01X1234223Y316987D02*
X1237316Y312648D01*
G01X1254493Y290195D02*
X1234863Y317726D01*
G01X1218824Y324921D02*
X1234223Y316987D01*
G01X1234863Y317726D02*
X1219055Y325871D01*
G01X1229784Y309521D02*
X1236150Y300592D01*
G01X1293498Y272508D02*
X1270214Y288307D01*
G01X1292804Y271830D02*
X1269534Y287619D01*
G01X1270214Y288307D02*
X1261972Y300150D01*
G01Y300151D02*
X1244103Y325826D01*
G01X1269534Y287619D02*
X1245219Y322557D01*
G01X1261972Y300151D02*
X1244103Y325826D01*
G01X1245219Y322557D02*
X1243457Y325089D01*
G01X1267402Y285442D02*
X1265720Y287844D01*
G01X1260848Y293146D02*
X1266721Y284758D01*
G01X1265720Y287844D02*
X1241026Y323115D01*
G01X1240382Y322378D02*
X1260848Y293146D01*
G01X1264376Y282894D02*
X1253964Y297498D01*
G01X1263698Y282207D02*
X1248995Y302830D01*
G01X1253964Y297498D02*
X1237432Y320685D01*
G01X1248995Y302830D02*
X1236792Y319946D01*
G01X1237432Y320685D02*
X1219835Y329750D01*
G01X1236792Y319946D02*
X1219604Y328800D01*
G01X1261791Y279959D02*
X1254493Y290195D01*
G01D02*
X1234863Y317726D01*
G01D02*
X1219055Y325871D01*
G01X1218824Y324921D02*
X1234223Y316987D01*
G01X1254493Y290195D02*
X1234863Y317726D01*
G01X1234223Y316987D02*
X1237316Y312648D01*
G01X1229784Y309521D02*
X1236150Y300592D01*
G01X1260234Y328907D02*
X1280669Y299033D01*
G01X1265488Y322910D02*
X1281351Y299719D01*
G01X1260234Y328907D02*
X1253965Y338072D01*
G01X1265488Y322910D02*
X1254610Y338813D01*
G01X1253965Y338072D02*
X1221591Y354171D01*
G01X1254610Y338813D02*
X1221815Y355121D01*
G01X1269395Y310026D02*
X1278431Y297021D01*
G01X1264182Y315862D02*
X1277751Y296334D01*
G01X1278431Y297021D02*
X1313774Y273011D01*
G01X1277751Y296334D02*
X1313300Y272183D01*
G01X1251323Y336036D02*
X1269395Y310026D01*
G01X1264182Y315862D02*
X1250681Y335293D01*
G01X1221789Y350722D02*
X1251323Y336036D01*
G01X1250681Y335294D02*
X1221366Y349871D01*
G01X1311427Y268832D02*
X1274916Y293551D01*
G01X1311900Y269660D02*
X1275595Y294239D01*
G01X1274916Y293551D02*
X1268941Y302140D01*
G01D02*
X1251491Y327228D01*
G01X1275595Y294239D02*
X1256754Y321327D01*
G01X1251491Y327228D02*
X1248821Y331067D01*
G01X1256754Y321327D02*
X1249466Y331804D01*
G01X1248821Y331067D02*
X1219017Y346388D01*
G01X1249466Y331804D02*
X1219247Y347338D01*
G01X1255730Y314160D02*
X1271853Y290980D01*
G01X1261585Y307408D02*
X1272534Y291667D01*
G01X1271853Y290980D02*
X1308436Y266035D01*
G01X1272534Y291667D02*
X1308910Y266862D01*
G01X1255730Y314160D02*
X1245973Y328189D01*
G01X1261585Y307408D02*
X1246617Y328927D01*
G01X1265488Y322910D02*
X1281351Y299719D01*
G01X1260234Y328907D02*
X1280669Y299033D01*
G01X1265488Y322910D02*
X1254610Y338813D01*
G01X1260234Y328907D02*
X1253965Y338072D01*
G01X1254610Y338813D02*
X1221815Y355121D01*
G01X1253965Y338072D02*
X1221591Y354171D01*
G01X1264182Y315862D02*
X1277751Y296334D01*
G01X1269395Y310026D02*
X1278431Y297021D01*
G01X1277751Y296334D02*
X1313300Y272183D01*
G01X1278431Y297021D02*
X1313774Y273011D01*
G01X1250681Y335294D02*
X1221366Y349871D01*
G01X1221789Y350722D02*
X1251323Y336036D01*
G01X1264182Y315862D02*
X1250681Y335293D01*
G01X1251323Y336036D02*
X1269395Y310026D01*
G01X1311900Y269660D02*
X1275595Y294239D01*
G01X1311427Y268832D02*
X1274916Y293551D01*
G01X1275595Y294239D02*
X1256754Y321327D01*
G01X1274916Y293551D02*
X1268941Y302140D01*
G01X1275595Y294239D02*
X1256754Y321327D01*
G01X1268941Y302140D02*
X1251491Y327228D01*
G01X1256754Y321327D02*
X1249466Y331804D01*
G01X1251491Y327228D02*
X1248821Y331067D01*
G01X1249466Y331804D02*
X1219247Y347338D01*
G01X1248821Y331067D02*
X1219017Y346388D01*
G01X1261585Y307408D02*
X1272534Y291667D01*
G01X1255730Y314160D02*
X1271853Y290980D01*
G01X1272534Y291667D02*
X1308910Y266862D01*
G01X1271853Y290980D02*
X1308436Y266035D01*
G01X1261585Y307408D02*
X1246617Y328927D01*
G01X1255730Y314160D02*
X1245973Y328189D01*
G01X1274699Y333959D02*
X1316076Y316948D01*
G01X1274699Y333959D02*
X1266005Y337534D01*
G01X1285536Y330531D02*
X1266411Y338395D01*
G01X1266005Y337534D02*
X1226379Y358541D01*
G01X1266411Y338395D02*
X1226616Y359491D01*
G01X1306698Y328639D02*
X1270947Y340517D01*
G01X1329371Y322110D02*
X1271318Y341395D01*
G01X1270947Y340517D02*
X1268614Y341717D01*
G01X1274699Y333959D02*
X1316076Y316948D01*
G01X1285536Y330531D02*
X1266411Y338395D01*
G01X1274699Y333959D02*
X1266005Y337534D01*
G01X1266411Y338395D02*
X1226616Y359491D01*
G01X1266005Y337534D02*
X1226379Y358541D01*
G01X1329371Y322110D02*
X1271318Y341395D01*
G01X1329371Y322110D02*
X1271318Y341395D01*
G01X1329371Y322110D02*
X1271318Y341395D01*
G01X1329371Y322110D02*
X1271318Y341395D01*
G01X1329371Y322110D02*
X1271318Y341395D01*
G01X1306698Y328639D02*
X1270947Y340517D01*
G01D02*
X1268614Y341717D01*
G01X1260848Y293146D02*
X1266721Y284758D01*
G01X1267402Y285442D02*
X1265720Y287844D01*
G01X1240382Y322378D02*
X1260848Y293146D01*
G01X1265720Y287844D02*
X1241026Y323115D01*
G01X1263698Y282207D02*
X1248995Y302830D01*
G01X1264376Y282894D02*
X1253964Y297498D01*
G01X1248995Y302830D02*
X1236792Y319946D01*
G01X1253964Y297498D02*
X1237432Y320685D01*
G01X1236792Y319946D02*
X1219604Y328800D01*
G01X1237432Y320685D02*
X1219835Y329750D01*
G01X1261791Y279959D02*
X1254493Y290195D01*
G01X1234223Y316987D02*
X1237316Y312648D01*
G01X1254493Y290195D02*
X1234863Y317726D01*
G01X1218824Y324921D02*
X1234223Y316987D01*
G01X1234863Y317726D02*
X1219055Y325871D01*
G01X1229784Y309521D02*
X1236150Y300592D01*
G01X1267402Y285442D02*
X1265720Y287844D01*
G01X1260848Y293146D02*
X1266721Y284758D01*
G01X1265720Y287844D02*
X1241026Y323115D01*
G01X1240382Y322378D02*
X1260848Y293146D01*
G01X1264376Y282894D02*
X1253964Y297498D01*
G01X1263698Y282207D02*
X1248995Y302830D01*
G01X1253964Y297498D02*
X1237432Y320685D01*
G01X1248995Y302830D02*
X1236792Y319946D01*
G01X1237432Y320685D02*
X1219835Y329750D01*
G01X1236792Y319946D02*
X1219604Y328800D01*
G01X1261791Y279959D02*
X1254493Y290195D01*
G01D02*
X1234863Y317726D01*
G01D02*
X1219055Y325871D01*
G01X1218824Y324921D02*
X1234223Y316987D01*
G01X1254493Y290195D02*
X1234863Y317726D01*
G01X1234223Y316987D02*
X1237316Y312648D01*
G01X1229784Y309521D02*
X1236150Y300592D01*
G01X1260234Y328907D02*
X1280669Y299033D01*
G01X1265488Y322910D02*
X1281351Y299719D01*
G01X1260234Y328907D02*
X1253965Y338072D01*
G01X1265488Y322910D02*
X1254610Y338813D01*
G01X1253965Y338072D02*
X1221591Y354171D01*
G01X1254610Y338813D02*
X1221815Y355121D01*
G01X1269395Y310026D02*
X1278431Y297021D01*
G01X1264182Y315862D02*
X1277751Y296334D01*
G01X1278431Y297021D02*
X1313774Y273011D01*
G01X1277751Y296334D02*
X1313300Y272183D01*
G01X1251323Y336036D02*
X1269395Y310026D01*
G01X1264182Y315862D02*
X1250681Y335293D01*
G01X1221789Y350722D02*
X1251323Y336036D01*
G01X1250681Y335294D02*
X1221366Y349871D01*
G01X1311427Y268832D02*
X1274916Y293551D01*
G01X1311900Y269660D02*
X1275595Y294239D01*
G01X1274916Y293551D02*
X1268941Y302140D01*
G01D02*
X1251491Y327228D01*
G01X1275595Y294239D02*
X1256754Y321327D01*
G01X1251491Y327228D02*
X1248821Y331067D01*
G01X1256754Y321327D02*
X1249466Y331804D01*
G01X1248821Y331067D02*
X1219017Y346388D01*
G01X1249466Y331804D02*
X1219247Y347338D01*
G01X1255730Y314160D02*
X1271853Y290980D01*
G01X1261585Y307408D02*
X1272534Y291667D01*
G01X1271853Y290980D02*
X1308436Y266035D01*
G01X1272534Y291667D02*
X1308910Y266862D01*
G01X1255730Y314160D02*
X1245973Y328189D01*
G01X1261585Y307408D02*
X1246617Y328927D01*
G01X1292804Y271830D02*
X1269534Y287619D01*
G01X1293498Y272508D02*
X1270214Y288307D01*
G01X1269534Y287619D02*
X1245219Y322557D01*
G01X1270214Y288307D02*
X1261972Y300150D01*
G01X1269534Y287619D02*
X1245219Y322557D01*
G01D02*
X1243457Y325089D01*
G01X1261972Y300151D02*
X1244103Y325826D01*
G01X1265488Y322910D02*
X1281351Y299719D01*
G01X1260234Y328907D02*
X1280669Y299033D01*
G01X1265488Y322910D02*
X1254610Y338813D01*
G01X1260234Y328907D02*
X1253965Y338072D01*
G01X1254610Y338813D02*
X1221815Y355121D01*
G01X1253965Y338072D02*
X1221591Y354171D01*
G01X1264182Y315862D02*
X1277751Y296334D01*
G01X1269395Y310026D02*
X1278431Y297021D01*
G01X1277751Y296334D02*
X1313300Y272183D01*
G01X1278431Y297021D02*
X1313774Y273011D01*
G01X1250681Y335294D02*
X1221366Y349871D01*
G01X1221789Y350722D02*
X1251323Y336036D01*
G01X1264182Y315862D02*
X1250681Y335293D01*
G01X1251323Y336036D02*
X1269395Y310026D01*
G01X1311900Y269660D02*
X1275595Y294239D01*
G01X1311427Y268832D02*
X1274916Y293551D01*
G01X1275595Y294239D02*
X1256754Y321327D01*
G01X1274916Y293551D02*
X1268941Y302140D01*
G01X1275595Y294239D02*
X1256754Y321327D01*
G01X1268941Y302140D02*
X1251491Y327228D01*
G01X1256754Y321327D02*
X1249466Y331804D01*
G01X1251491Y327228D02*
X1248821Y331067D01*
G01X1249466Y331804D02*
X1219247Y347338D01*
G01X1248821Y331067D02*
X1219017Y346388D01*
G01X1261585Y307408D02*
X1272534Y291667D01*
G01X1255730Y314160D02*
X1271853Y290980D01*
G01X1272534Y291667D02*
X1308910Y266862D01*
G01X1271853Y290980D02*
X1308436Y266035D01*
G01X1261585Y307408D02*
X1246617Y328927D01*
G01X1255730Y314160D02*
X1245973Y328189D01*
G01X1293498Y272508D02*
X1270214Y288307D01*
G01X1292804Y271830D02*
X1269534Y287619D01*
G01X1270214Y288307D02*
X1261972Y300150D01*
G01Y300151D02*
X1244103Y325826D01*
G01X1269534Y287619D02*
X1245219Y322557D01*
G01X1261972Y300151D02*
X1244103Y325826D01*
G01X1245219Y322557D02*
X1243457Y325089D01*
G01X1306698Y328639D02*
X1270947Y340517D01*
G01X1329371Y322110D02*
X1271318Y341395D01*
G01X1270947Y340517D02*
X1268614Y341717D01*
G01X1274699Y333959D02*
X1316076Y316948D01*
G01X1285536Y330531D02*
X1266411Y338395D01*
G01X1274699Y333959D02*
X1266005Y337534D01*
G01X1266411Y338395D02*
X1226616Y359491D01*
G01X1266005Y337534D02*
X1226379Y358541D01*
G01X1329371Y322110D02*
X1271318Y341395D01*
G01X1329371Y322110D02*
X1271318Y341395D01*
G01X1329371Y322110D02*
X1271318Y341395D01*
G01X1329371Y322110D02*
X1271318Y341395D01*
G01X1329371Y322110D02*
X1271318Y341395D01*
G01X1306698Y328639D02*
X1270947Y340517D01*
G01D02*
X1268614Y341717D01*
G01X1274699Y333959D02*
X1316076Y316948D01*
G01X1274699Y333959D02*
X1266005Y337534D01*
G01X1285536Y330531D02*
X1266411Y338395D01*
G01X1266005Y337534D02*
X1226379Y358541D01*
G01X1266411Y338395D02*
X1226616Y359491D01*
G01X1221591Y354171D02*
X1219459D01*
G01X1221815Y355121D02*
X1219459D01*
G01X1221815D02*
X1219459D01*
G01X1221591Y354171D02*
X1219459D01*
G01X1229414Y410150D02*
X1220996Y391702D01*
G01X1228657Y410780D02*
X1220243Y392342D01*
G01X1228657Y410780D02*
X1220243Y392342D01*
G01X1229414Y410150D02*
X1220996Y391702D01*
G01X1228459Y362373D02*
X1268614Y341717D01*
G01X1271317Y341396D02*
X1247619Y353586D01*
G01X1220316Y362373D02*
X1228459D01*
G01X1220316Y363323D02*
X1228690D01*
G01X1228459Y362373D02*
X1268614Y341717D01*
G01X1228690Y363323D02*
X1247619Y353586D01*
G01X1273256Y344382D02*
X1265918Y348135D01*
G01X1254441Y355073D02*
X1273624Y345262D01*
G01X1330647Y325314D02*
X1273259Y344380D01*
G01X1273624Y345261D02*
X1330708Y326296D01*
G01X1265918Y348135D02*
X1230387Y366310D01*
G01X1230616Y367260D02*
X1254441Y355073D01*
G01X1275145Y347822D02*
X1330815Y329327D01*
G01X1330876Y330308D02*
X1275513Y348701D01*
G01X1267242Y351865D02*
X1267241D01*
G01D02*
X1275145Y347822D01*
G01X1275513Y348701D02*
X1262771Y355219D01*
G01X1248828Y361285D02*
X1267242Y351865D01*
G01X1262771Y355220D02*
X1262770D01*
G01X1246918Y362262D02*
X1248828Y361285D01*
G01D02*
X1267242Y351865D01*
G01X1246918Y362262D02*
X1244742Y363375D01*
G01X1262770Y355221D02*
X1245174Y364221D01*
G01X1244742Y363375D02*
X1231415Y370192D01*
G01X1245174Y364221D02*
X1231644Y371142D01*
G01X1276463Y351535D02*
X1270188Y354743D01*
G01X1270621Y355590D02*
X1276826Y352417D01*
G01X1314384Y338937D02*
X1279500Y350527D01*
G01D02*
X1279501D01*
G01D02*
X1276464Y351536D01*
G01X1276826Y352417D02*
X1314454Y339916D01*
G01X1232416Y374061D02*
X1221789D01*
G01Y375011D02*
X1232647D01*
G01X1270188Y354743D02*
X1232416Y374061D01*
G01X1232647Y375011D02*
X1270621Y355590D01*
G01X1221220Y377822D02*
X1229586Y381495D01*
G01X1221020Y378772D02*
X1228884Y382225D01*
G01X1229586Y381495D02*
X1239859Y402580D01*
G01X1228884Y382225D02*
X1239110Y403212D01*
G01X1239859Y402580D02*
X1244325Y405788D01*
G01X1259976Y404204D02*
X1280397Y389478D01*
G01X1260373Y405090D02*
X1281185Y390082D01*
G01X1283557Y392001D02*
X1275096Y398116D01*
G01X1284347Y392603D02*
X1269301Y403478D01*
G01X1275096Y398116D02*
X1260290Y408817D01*
G01X1236778Y405115D02*
X1226725Y384490D01*
G01X1236029Y405747D02*
X1226023Y385220D01*
G01X1226725Y384490D02*
X1220207Y381629D01*
G01X1226023Y385220D02*
X1220007Y382579D01*
G01X1287443Y395309D02*
X1262595Y413255D01*
G01X1286652Y394706D02*
X1262197Y412369D01*
G01X1232753Y408121D02*
X1223115Y388347D01*
G01X1233502Y407489D02*
X1223817Y387617D01*
G01X1223115Y388347D02*
X1218765Y386437D01*
G01X1223817Y387617D02*
X1218965Y385487D01*
G01X1271317Y341396D02*
X1247619Y353586D01*
G01X1220316Y363323D02*
X1228690D01*
G01X1220316Y362373D02*
X1228459D01*
G01X1271317Y341396D02*
X1247619Y353586D01*
G01X1228690Y363323D02*
X1247619Y353586D01*
G01X1228459Y362373D02*
X1268614Y341717D01*
G01X1273624Y345261D02*
X1330708Y326296D01*
G01X1330647Y325314D02*
X1273259Y344380D01*
G01X1254441Y355073D02*
X1273624Y345262D01*
G01X1273256Y344382D02*
X1265918Y348135D01*
G01X1230616Y367260D02*
X1254441Y355073D01*
G01X1265918Y348135D02*
X1230387Y366310D01*
G01X1262770Y355221D02*
X1245174Y364221D01*
G01X1246918Y362262D02*
X1248828Y361285D01*
G01X1262771Y355220D02*
X1262770D01*
G01Y355221D02*
X1245174Y364221D01*
G01X1248828Y361285D02*
X1267242Y351865D01*
G01X1275513Y348701D02*
X1262771Y355219D01*
G01X1267242Y351865D02*
X1267241D01*
G01X1275513Y348701D02*
X1262771Y355219D01*
G01X1267241Y351865D02*
X1275145Y347822D01*
G01X1330876Y330308D02*
X1275513Y348701D01*
G01X1275145Y347822D02*
X1330815Y329327D01*
G01X1262770Y355221D02*
X1245174Y364221D01*
G01X1246918Y362262D02*
X1244742Y363375D01*
G01X1245174Y364221D02*
X1231644Y371142D01*
G01X1244742Y363375D02*
X1231415Y370192D01*
G01X1276826Y352417D02*
X1314454Y339916D01*
G01X1314384Y338937D02*
X1279500Y350527D01*
G01X1276826Y352417D02*
X1314454Y339916D01*
G01X1279500Y350527D02*
X1279501D01*
G01X1276826Y352417D02*
X1314454Y339916D01*
G01X1279501Y350527D02*
X1276464Y351536D01*
G01X1270621Y355590D02*
X1276826Y352417D01*
G01X1276463Y351535D02*
X1270188Y354743D01*
G01X1232647Y375011D02*
X1270621Y355590D01*
G01X1270188Y354743D02*
X1232416Y374061D01*
G01X1221789Y375011D02*
X1232647D01*
G01X1232416Y374061D02*
X1221789D01*
G01X1221020Y378772D02*
X1228884Y382225D01*
G01X1221220Y377822D02*
X1229586Y381495D01*
G01X1228884Y382225D02*
X1239110Y403212D01*
G01X1229586Y381495D02*
X1239859Y402580D01*
G01D02*
X1244325Y405788D01*
G01X1260373Y405090D02*
X1281185Y390082D01*
G01X1259976Y404204D02*
X1280397Y389478D01*
G01X1284347Y392603D02*
X1269301Y403478D01*
G01X1283557Y392001D02*
X1275096Y398116D01*
G01D02*
X1260290Y408817D01*
G01X1236029Y405747D02*
X1226023Y385220D01*
G01X1236778Y405115D02*
X1226725Y384490D01*
G01X1226023Y385220D02*
X1220007Y382579D01*
G01X1226725Y384490D02*
X1220207Y381629D01*
G01X1286652Y394706D02*
X1262197Y412369D01*
G01X1287443Y395309D02*
X1262595Y413255D01*
G01X1233502Y407489D02*
X1223817Y387617D01*
G01X1232753Y408121D02*
X1223115Y388347D01*
G01X1223817Y387617D02*
X1218965Y385487D01*
G01X1223115Y388347D02*
X1218765Y386437D01*
G01X1221591Y354171D02*
X1219459D01*
G01X1221815Y355121D02*
X1219459D01*
G01X1221815D02*
X1219459D01*
G01X1221591Y354171D02*
X1219459D01*
G01X1228459Y362373D02*
X1268614Y341717D01*
G01X1271317Y341396D02*
X1247619Y353586D01*
G01X1220316Y362373D02*
X1228459D01*
G01X1220316Y363323D02*
X1228690D01*
G01X1228459Y362373D02*
X1268614Y341717D01*
G01X1228690Y363323D02*
X1247619Y353586D01*
G01X1271317Y341396D02*
X1247619Y353586D01*
G01X1220316Y363323D02*
X1228690D01*
G01X1220316Y362373D02*
X1228459D01*
G01X1271317Y341396D02*
X1247619Y353586D01*
G01X1228690Y363323D02*
X1247619Y353586D01*
G01X1228459Y362373D02*
X1268614Y341717D01*
G01X1273256Y344382D02*
X1265918Y348135D01*
G01X1254441Y355073D02*
X1273624Y345262D01*
G01X1330647Y325314D02*
X1273259Y344380D01*
G01X1273624Y345261D02*
X1330708Y326296D01*
G01X1265918Y348135D02*
X1230387Y366310D01*
G01X1230616Y367260D02*
X1254441Y355073D01*
G01X1275145Y347822D02*
X1330815Y329327D01*
G01X1330876Y330308D02*
X1275513Y348701D01*
G01X1267242Y351865D02*
X1267241D01*
G01D02*
X1275145Y347822D01*
G01X1275513Y348701D02*
X1262771Y355219D01*
G01X1248828Y361285D02*
X1267242Y351865D01*
G01X1262771Y355220D02*
X1262770D01*
G01X1246918Y362262D02*
X1248828Y361285D01*
G01D02*
X1267242Y351865D01*
G01X1246918Y362262D02*
X1244742Y363375D01*
G01X1262770Y355221D02*
X1245174Y364221D01*
G01X1244742Y363375D02*
X1231415Y370192D01*
G01X1245174Y364221D02*
X1231644Y371142D01*
G01X1276463Y351535D02*
X1270188Y354743D01*
G01X1270621Y355590D02*
X1276826Y352417D01*
G01X1314384Y338937D02*
X1279500Y350527D01*
G01D02*
X1279501D01*
G01D02*
X1276464Y351536D01*
G01X1276826Y352417D02*
X1314454Y339916D01*
G01X1232416Y374061D02*
X1221789D01*
G01Y375011D02*
X1232647D01*
G01X1270188Y354743D02*
X1232416Y374061D01*
G01X1232647Y375011D02*
X1270621Y355590D01*
G01X1273624Y345261D02*
X1330708Y326296D01*
G01X1330647Y325314D02*
X1273259Y344380D01*
G01X1254441Y355073D02*
X1273624Y345262D01*
G01X1273256Y344382D02*
X1265918Y348135D01*
G01X1230616Y367260D02*
X1254441Y355073D01*
G01X1265918Y348135D02*
X1230387Y366310D01*
G01X1262770Y355221D02*
X1245174Y364221D01*
G01X1246918Y362262D02*
X1248828Y361285D01*
G01X1262771Y355220D02*
X1262770D01*
G01Y355221D02*
X1245174Y364221D01*
G01X1248828Y361285D02*
X1267242Y351865D01*
G01X1275513Y348701D02*
X1262771Y355219D01*
G01X1267242Y351865D02*
X1267241D01*
G01X1275513Y348701D02*
X1262771Y355219D01*
G01X1267241Y351865D02*
X1275145Y347822D01*
G01X1330876Y330308D02*
X1275513Y348701D01*
G01X1275145Y347822D02*
X1330815Y329327D01*
G01X1262770Y355221D02*
X1245174Y364221D01*
G01X1246918Y362262D02*
X1244742Y363375D01*
G01X1245174Y364221D02*
X1231644Y371142D01*
G01X1244742Y363375D02*
X1231415Y370192D01*
G01X1276826Y352417D02*
X1314454Y339916D01*
G01X1314384Y338937D02*
X1279500Y350527D01*
G01X1276826Y352417D02*
X1314454Y339916D01*
G01X1279500Y350527D02*
X1279501D01*
G01X1276826Y352417D02*
X1314454Y339916D01*
G01X1279501Y350527D02*
X1276464Y351536D01*
G01X1270621Y355590D02*
X1276826Y352417D01*
G01X1276463Y351535D02*
X1270188Y354743D01*
G01X1232647Y375011D02*
X1270621Y355590D01*
G01X1270188Y354743D02*
X1232416Y374061D01*
G01X1221789Y375011D02*
X1232647D01*
G01X1232416Y374061D02*
X1221789D01*
G01X1229414Y410150D02*
X1220996Y391702D01*
G01X1228657Y410780D02*
X1220243Y392342D01*
G01X1228657Y410780D02*
X1220243Y392342D01*
G01X1229414Y410150D02*
X1220996Y391702D01*
G01X1221220Y377822D02*
X1229586Y381495D01*
G01X1221020Y378772D02*
X1228884Y382225D01*
G01X1229586Y381495D02*
X1239859Y402580D01*
G01X1228884Y382225D02*
X1239110Y403212D01*
G01X1239859Y402580D02*
X1244325Y405788D01*
G01X1259976Y404204D02*
X1280397Y389478D01*
G01X1260373Y405090D02*
X1281185Y390082D01*
G01X1283557Y392001D02*
X1275096Y398116D01*
G01X1284347Y392603D02*
X1269301Y403478D01*
G01X1275096Y398116D02*
X1260290Y408817D01*
G01X1236778Y405115D02*
X1226725Y384490D01*
G01X1236029Y405747D02*
X1226023Y385220D01*
G01X1226725Y384490D02*
X1220207Y381629D01*
G01X1226023Y385220D02*
X1220007Y382579D01*
G01X1287443Y395309D02*
X1262595Y413255D01*
G01X1286652Y394706D02*
X1262197Y412369D01*
G01X1232753Y408121D02*
X1223115Y388347D01*
G01X1233502Y407489D02*
X1223817Y387617D01*
G01X1223115Y388347D02*
X1218765Y386437D01*
G01X1223817Y387617D02*
X1218965Y385487D01*
G01X1221020Y378772D02*
X1228884Y382225D01*
G01X1221220Y377822D02*
X1229586Y381495D01*
G01X1228884Y382225D02*
X1239110Y403212D01*
G01X1229586Y381495D02*
X1239859Y402580D01*
G01D02*
X1244325Y405788D01*
G01X1260373Y405090D02*
X1281185Y390082D01*
G01X1259976Y404204D02*
X1280397Y389478D01*
G01X1284347Y392603D02*
X1269301Y403478D01*
G01X1283557Y392001D02*
X1275096Y398116D01*
G01D02*
X1260290Y408817D01*
G01X1236029Y405747D02*
X1226023Y385220D01*
G01X1236778Y405115D02*
X1226725Y384490D01*
G01X1226023Y385220D02*
X1220007Y382579D01*
G01X1226725Y384490D02*
X1220207Y381629D01*
G01X1286652Y394706D02*
X1262197Y412369D01*
G01X1287443Y395309D02*
X1262595Y413255D01*
G01X1233502Y407489D02*
X1223817Y387617D01*
G01X1232753Y408121D02*
X1223115Y388347D01*
G01X1223817Y387617D02*
X1218965Y385487D01*
G01X1223115Y388347D02*
X1218765Y386437D01*
G01X1253522Y445355D02*
X1266305Y453863D01*
G01X1260765Y451319D02*
X1266017Y454814D01*
G01X1266305Y453864D02*
X1273252D01*
G01X1266017Y454814D02*
X1272858D01*
G01X1273252Y453864D02*
X1282814Y463426D01*
G01X1272858Y454814D02*
X1282420Y464376D01*
G01X1220616Y409965D02*
X1230003Y429703D01*
G01X1219829Y410523D02*
X1229257Y430349D01*
G01X1230003Y429703D02*
X1242207Y437825D01*
G01X1244081Y439072D02*
X1245204Y439820D01*
G01X1247078Y441067D02*
X1253522Y445355D01*
G01X1229257Y430349D02*
X1260765Y451319D01*
G01X1257949Y466250D02*
X1251312Y459613D01*
G01X1255969Y462926D02*
X1258343Y465300D01*
G01X1262596Y464404D02*
X1260750Y466250D01*
G01X1260356Y465300D02*
X1262202Y463454D01*
G01X1271266Y464404D02*
X1262596D01*
G01X1262202Y463454D02*
X1271150D01*
G01X1257949Y466250D02*
X1251312Y459613D01*
G01X1249922Y458223D02*
X1251312Y459613D01*
G01X1255969Y462926D02*
X1250528Y457484D01*
G01X1242016Y452953D02*
X1249922Y458223D01*
G01X1250528Y457484D02*
X1248482Y456121D01*
G01X1233714Y447419D02*
X1242016Y452953D01*
G01D02*
X1249922Y458223D01*
G01X1248482Y456121D02*
X1234444Y446760D01*
G01X1254389Y470270D02*
X1234060Y456651D01*
G01X1256199Y472626D02*
X1239184Y461228D01*
G01X1254389Y470270D02*
X1234060Y456651D01*
G01X1233317Y457297D02*
X1239184Y461227D01*
G01X1244242Y470373D02*
X1231453Y460735D01*
G01X1230733Y461383D02*
X1248059Y474440D01*
G01X1286680Y436097D02*
X1253042Y422650D01*
G01X1286074Y436879D02*
X1261381Y427008D01*
G01X1253042Y422650D02*
X1239596Y417275D01*
G01X1261381Y427008D02*
X1239141Y418117D01*
G01X1239596Y417275D02*
X1229414Y410150D01*
G01X1239141Y418117D02*
X1228657Y410780D01*
G01X1253007Y431370D02*
X1265588Y440105D01*
G01X1261528Y438443D02*
X1264976Y440837D01*
G01X1265588Y440105D02*
X1284893Y459410D01*
G01X1264976Y440837D02*
X1284499Y460360D01*
G01X1226416Y412909D02*
X1253007Y431370D01*
G01X1225670Y413549D02*
X1226779Y414319D01*
G01X1226416Y412909D02*
X1253007Y431370D01*
G01X1228001Y415715D02*
X1228627Y415602D01*
G01X1226416Y412909D02*
X1253007Y431370D01*
G01X1228627Y415602D02*
X1229736Y416372D01*
G01X1226416Y412909D02*
X1253007Y431370D01*
G01X1230958Y417768D02*
X1231584Y417655D01*
G01X1226416Y412909D02*
X1253007Y431370D01*
G01X1231584Y417655D02*
X1232693Y418425D01*
G01X1226416Y412909D02*
X1253007Y431370D01*
G01X1233915Y419821D02*
X1234541Y419708D01*
G01X1253007Y431370D02*
X1265588Y440105D01*
G01X1226416Y412909D02*
X1253007Y431370D01*
G01X1234541Y419708D02*
X1261528Y438443D01*
G01X1260765Y451319D02*
X1266017Y454814D01*
G01X1253522Y445355D02*
X1266305Y453863D01*
G01X1266017Y454814D02*
X1272858D01*
G01X1266305Y453864D02*
X1273252D01*
G01X1272858Y454814D02*
X1282420Y464376D01*
G01X1273252Y453864D02*
X1282814Y463426D01*
G01X1219829Y410523D02*
X1229257Y430349D01*
G01X1220616Y409965D02*
X1230003Y429703D01*
G01X1229257Y430349D02*
X1260765Y451319D01*
G01X1230003Y429703D02*
X1242207Y437825D01*
G01X1229257Y430349D02*
X1260765Y451319D01*
G01X1244081Y439072D02*
X1245204Y439820D01*
G01X1229257Y430349D02*
X1260765Y451319D01*
G01X1247078Y441067D02*
X1253522Y445355D01*
G01X1262202Y463454D02*
X1271150D01*
G01X1271266Y464404D02*
X1262596D01*
G01X1260356Y465300D02*
X1262202Y463454D01*
G01X1262596Y464404D02*
X1260750Y466250D01*
G01X1255969Y462926D02*
X1258343Y465300D01*
G01X1255969Y462926D02*
X1250528Y457484D01*
G01X1257949Y466250D02*
X1251312Y459613D01*
G01X1248482Y456121D02*
X1234444Y446760D01*
G01X1233714Y447419D02*
X1242016Y452953D01*
G01X1250528Y457484D02*
X1248482Y456121D01*
G01D02*
X1234444Y446760D01*
G01X1242016Y452953D02*
X1249922Y458223D01*
G01X1255969Y462926D02*
X1250528Y457484D01*
G01X1249922Y458223D02*
X1251312Y459613D01*
G01X1256199Y472626D02*
X1239184Y461228D01*
G01X1256199Y472626D02*
X1239184Y461228D01*
G01X1233317Y457297D02*
X1239184Y461227D01*
G01X1254389Y470270D02*
X1234060Y456651D01*
G01X1230733Y461383D02*
X1248059Y474440D01*
G01X1230733Y461383D02*
X1248059Y474440D01*
G01X1244242Y470373D02*
X1231453Y460735D01*
G01X1286074Y436879D02*
X1261381Y427008D01*
G01X1286680Y436097D02*
X1253042Y422650D01*
G01X1261381Y427008D02*
X1239141Y418117D01*
G01X1253042Y422650D02*
X1239596Y417275D01*
G01X1239141Y418117D02*
X1228657Y410780D01*
G01X1239596Y417275D02*
X1229414Y410150D01*
G01X1261528Y438443D02*
X1264976Y440837D01*
G01X1234541Y419708D02*
X1261528Y438443D01*
G01X1253007Y431370D02*
X1265588Y440105D01*
G01X1264976Y440837D02*
X1284499Y460360D01*
G01X1265588Y440105D02*
X1284893Y459410D01*
G01X1225670Y413549D02*
X1226779Y414319D01*
G01X1228001Y415715D02*
X1228627Y415602D01*
G01D02*
X1229736Y416372D01*
G01X1230958Y417768D02*
X1231584Y417655D01*
G01D02*
X1232693Y418425D01*
G01X1233915Y419821D02*
X1234541Y419708D01*
G01D02*
X1261528Y438443D01*
G01X1226416Y412909D02*
X1253007Y431370D01*
G01X1239110Y403212D02*
X1243913Y406662D01*
G01X1244325Y405788D02*
X1248208Y406815D01*
G01X1243913Y406662D02*
X1248188Y407793D01*
G01X1248208Y406815D02*
X1259976Y404204D01*
G01X1248188Y407793D02*
X1260373Y405090D01*
G01X1269301Y403478D02*
X1260688Y409703D01*
G01X1260290Y408817D02*
X1249630Y411179D01*
G01X1260688Y409703D02*
X1249610Y412157D01*
G01X1249630Y411179D02*
X1242640Y409329D01*
G01X1249610Y412157D02*
X1242228Y410203D01*
G01X1242640Y409329D02*
X1236778Y405115D01*
G01X1242228Y410203D02*
X1236029Y405747D01*
G01X1262595Y413255D02*
X1249426Y416182D01*
G01X1262197Y412369D02*
X1249444Y415204D01*
G01X1249426Y416182D02*
X1240852Y413940D01*
G01X1249444Y415204D02*
X1241263Y413065D01*
G01X1240852Y413940D02*
X1232753Y408121D01*
G01X1241263Y413065D02*
X1233502Y407489D01*
G01X1239110Y403212D02*
X1243913Y406662D01*
G01D02*
X1248188Y407793D01*
G01X1244325Y405788D02*
X1248208Y406815D01*
G01X1248188Y407793D02*
X1260373Y405090D01*
G01X1248208Y406815D02*
X1259976Y404204D01*
G01X1269301Y403478D02*
X1260688Y409703D01*
G01D02*
X1249610Y412157D01*
G01X1260290Y408817D02*
X1249630Y411179D01*
G01X1249610Y412157D02*
X1242228Y410203D01*
G01X1249630Y411179D02*
X1242640Y409329D01*
G01X1242228Y410203D02*
X1236029Y405747D01*
G01X1242640Y409329D02*
X1236778Y405115D01*
G01X1262197Y412369D02*
X1249444Y415204D01*
G01X1262595Y413255D02*
X1249426Y416182D01*
G01X1249444Y415204D02*
X1241263Y413065D01*
G01X1249426Y416182D02*
X1240852Y413940D01*
G01X1241263Y413065D02*
X1233502Y407489D01*
G01X1240852Y413940D02*
X1232753Y408121D01*
G01X1253522Y445355D02*
X1266305Y453863D01*
G01X1260765Y451319D02*
X1266017Y454814D01*
G01X1266305Y453864D02*
X1273252D01*
G01X1266017Y454814D02*
X1272858D01*
G01X1273252Y453864D02*
X1282814Y463426D01*
G01X1272858Y454814D02*
X1282420Y464376D01*
G01X1220616Y409965D02*
X1230003Y429703D01*
G01X1219829Y410523D02*
X1229257Y430349D01*
G01X1230003Y429703D02*
X1242207Y437825D01*
G01X1244081Y439072D02*
X1245204Y439820D01*
G01X1247078Y441067D02*
X1253522Y445355D01*
G01X1229257Y430349D02*
X1260765Y451319D01*
G01X1257949Y466250D02*
X1251312Y459613D01*
G01X1255969Y462926D02*
X1258343Y465300D01*
G01X1262596Y464404D02*
X1260750Y466250D01*
G01X1260356Y465300D02*
X1262202Y463454D01*
G01X1271266Y464404D02*
X1262596D01*
G01X1262202Y463454D02*
X1271150D01*
G01X1257949Y466250D02*
X1251312Y459613D01*
G01X1249922Y458223D02*
X1251312Y459613D01*
G01X1255969Y462926D02*
X1250528Y457484D01*
G01X1242016Y452953D02*
X1249922Y458223D01*
G01X1250528Y457484D02*
X1248482Y456121D01*
G01X1233714Y447419D02*
X1242016Y452953D01*
G01D02*
X1249922Y458223D01*
G01X1248482Y456121D02*
X1234444Y446760D01*
G01X1254389Y470270D02*
X1234060Y456651D01*
G01X1256199Y472626D02*
X1239184Y461228D01*
G01X1254389Y470270D02*
X1234060Y456651D01*
G01X1233317Y457297D02*
X1239184Y461227D01*
G01X1286680Y436097D02*
X1253042Y422650D01*
G01X1286074Y436879D02*
X1261381Y427008D01*
G01X1253042Y422650D02*
X1239596Y417275D01*
G01X1261381Y427008D02*
X1239141Y418117D01*
G01X1239596Y417275D02*
X1229414Y410150D01*
G01X1239141Y418117D02*
X1228657Y410780D01*
G01X1253007Y431370D02*
X1265588Y440105D01*
G01X1261528Y438443D02*
X1264976Y440837D01*
G01X1265588Y440105D02*
X1284893Y459410D01*
G01X1264976Y440837D02*
X1284499Y460360D01*
G01X1226416Y412909D02*
X1253007Y431370D01*
G01X1225670Y413549D02*
X1226779Y414319D01*
G01X1226416Y412909D02*
X1253007Y431370D01*
G01X1228001Y415715D02*
X1228627Y415602D01*
G01X1226416Y412909D02*
X1253007Y431370D01*
G01X1228627Y415602D02*
X1229736Y416372D01*
G01X1226416Y412909D02*
X1253007Y431370D01*
G01X1230958Y417768D02*
X1231584Y417655D01*
G01X1226416Y412909D02*
X1253007Y431370D01*
G01X1231584Y417655D02*
X1232693Y418425D01*
G01X1226416Y412909D02*
X1253007Y431370D01*
G01X1233915Y419821D02*
X1234541Y419708D01*
G01X1253007Y431370D02*
X1265588Y440105D01*
G01X1226416Y412909D02*
X1253007Y431370D01*
G01X1234541Y419708D02*
X1261528Y438443D01*
G01X1260765Y451319D02*
X1266017Y454814D01*
G01X1253522Y445355D02*
X1266305Y453863D01*
G01X1266017Y454814D02*
X1272858D01*
G01X1266305Y453864D02*
X1273252D01*
G01X1272858Y454814D02*
X1282420Y464376D01*
G01X1273252Y453864D02*
X1282814Y463426D01*
G01X1219829Y410523D02*
X1229257Y430349D01*
G01X1220616Y409965D02*
X1230003Y429703D01*
G01X1229257Y430349D02*
X1260765Y451319D01*
G01X1230003Y429703D02*
X1242207Y437825D01*
G01X1229257Y430349D02*
X1260765Y451319D01*
G01X1244081Y439072D02*
X1245204Y439820D01*
G01X1229257Y430349D02*
X1260765Y451319D01*
G01X1247078Y441067D02*
X1253522Y445355D01*
G01X1262202Y463454D02*
X1271150D01*
G01X1271266Y464404D02*
X1262596D01*
G01X1260356Y465300D02*
X1262202Y463454D01*
G01X1262596Y464404D02*
X1260750Y466250D01*
G01X1255969Y462926D02*
X1258343Y465300D01*
G01X1255969Y462926D02*
X1250528Y457484D01*
G01X1257949Y466250D02*
X1251312Y459613D01*
G01X1248482Y456121D02*
X1234444Y446760D01*
G01X1233714Y447419D02*
X1242016Y452953D01*
G01X1250528Y457484D02*
X1248482Y456121D01*
G01D02*
X1234444Y446760D01*
G01X1242016Y452953D02*
X1249922Y458223D01*
G01X1255969Y462926D02*
X1250528Y457484D01*
G01X1249922Y458223D02*
X1251312Y459613D01*
G01X1286074Y436879D02*
X1261381Y427008D01*
G01X1286680Y436097D02*
X1253042Y422650D01*
G01X1261381Y427008D02*
X1239141Y418117D01*
G01X1253042Y422650D02*
X1239596Y417275D01*
G01X1239141Y418117D02*
X1228657Y410780D01*
G01X1239596Y417275D02*
X1229414Y410150D01*
G01X1261528Y438443D02*
X1264976Y440837D01*
G01X1234541Y419708D02*
X1261528Y438443D01*
G01X1253007Y431370D02*
X1265588Y440105D01*
G01X1264976Y440837D02*
X1284499Y460360D01*
G01X1265588Y440105D02*
X1284893Y459410D01*
G01X1225670Y413549D02*
X1226779Y414319D01*
G01X1228001Y415715D02*
X1228627Y415602D01*
G01D02*
X1229736Y416372D01*
G01X1230958Y417768D02*
X1231584Y417655D01*
G01D02*
X1232693Y418425D01*
G01X1233915Y419821D02*
X1234541Y419708D01*
G01D02*
X1261528Y438443D01*
G01X1226416Y412909D02*
X1253007Y431370D01*
G01X1277292Y463448D02*
X1281115Y467271D01*
G01X1280721Y468221D02*
X1276898Y464398D01*
G01X1275848Y463448D02*
X1277292D01*
G01X1276898Y464398D02*
X1275802D01*
G01X1276898D02*
X1275802D01*
G01X1275848Y463448D02*
X1277292D01*
G01X1280721Y468221D02*
X1276898Y464398D01*
G01X1277292Y463448D02*
X1281115Y467271D01*
G01X1244242Y470373D02*
X1231453Y460735D01*
G01X1230733Y461383D02*
X1248059Y474440D01*
G01X1256199Y472626D02*
X1239184Y461228D01*
G01X1256199Y472626D02*
X1239184Y461228D01*
G01X1233317Y457297D02*
X1239184Y461227D01*
G01X1254389Y470270D02*
X1234060Y456651D01*
G01X1230733Y461383D02*
X1248059Y474440D01*
G01X1230733Y461383D02*
X1248059Y474440D01*
G01X1244242Y470373D02*
X1231453Y460735D01*
G01X1239110Y403212D02*
X1243913Y406662D01*
G01X1244325Y405788D02*
X1248208Y406815D01*
G01X1243913Y406662D02*
X1248188Y407793D01*
G01X1248208Y406815D02*
X1259976Y404204D01*
G01X1248188Y407793D02*
X1260373Y405090D01*
G01X1269301Y403478D02*
X1260688Y409703D01*
G01X1260290Y408817D02*
X1249630Y411179D01*
G01X1260688Y409703D02*
X1249610Y412157D01*
G01X1249630Y411179D02*
X1242640Y409329D01*
G01X1249610Y412157D02*
X1242228Y410203D01*
G01X1242640Y409329D02*
X1236778Y405115D01*
G01X1242228Y410203D02*
X1236029Y405747D01*
G01X1262595Y413255D02*
X1249426Y416182D01*
G01X1262197Y412369D02*
X1249444Y415204D01*
G01X1249426Y416182D02*
X1240852Y413940D01*
G01X1249444Y415204D02*
X1241263Y413065D01*
G01X1240852Y413940D02*
X1232753Y408121D01*
G01X1241263Y413065D02*
X1233502Y407489D01*
G01X1239110Y403212D02*
X1243913Y406662D01*
G01D02*
X1248188Y407793D01*
G01X1244325Y405788D02*
X1248208Y406815D01*
G01X1248188Y407793D02*
X1260373Y405090D01*
G01X1248208Y406815D02*
X1259976Y404204D01*
G01X1269301Y403478D02*
X1260688Y409703D01*
G01D02*
X1249610Y412157D01*
G01X1260290Y408817D02*
X1249630Y411179D01*
G01X1249610Y412157D02*
X1242228Y410203D01*
G01X1249630Y411179D02*
X1242640Y409329D01*
G01X1242228Y410203D02*
X1236029Y405747D01*
G01X1242640Y409329D02*
X1236778Y405115D01*
G01X1262197Y412369D02*
X1249444Y415204D01*
G01X1262595Y413255D02*
X1249426Y416182D01*
G01X1249444Y415204D02*
X1241263Y413065D01*
G01X1249426Y416182D02*
X1240852Y413940D01*
G01X1241263Y413065D02*
X1233502Y407489D01*
G01X1240852Y413940D02*
X1232753Y408121D01*
G01X1277292Y463448D02*
X1281115Y467271D01*
G01X1280721Y468221D02*
X1276898Y464398D01*
G01X1275848Y463448D02*
X1277292D01*
G01X1276898Y464398D02*
X1275802D01*
G01X1276898D02*
X1275802D01*
G01X1275848Y463448D02*
X1277292D01*
G01X1280721Y468221D02*
X1276898Y464398D01*
G01X1277292Y463448D02*
X1281115Y467271D01*
G01X1260750Y466250D02*
X1257949D01*
G01X1258343Y465300D02*
X1260356D01*
G01X1263824Y471676D02*
X1256488D01*
G01X1263778Y472626D02*
X1256199D01*
G01X1256488Y471676D02*
X1254389Y470270D01*
G01X1277444Y476050D02*
X1270456D01*
G01X1277050Y477000D02*
X1270850D01*
G01X1270456Y476050D02*
X1268446Y478060D01*
G01X1270850Y477000D02*
X1268840Y479010D01*
G01X1268446Y478060D02*
X1259234D01*
G01X1268840Y479010D02*
X1258840D01*
G01X1259234Y478060D02*
X1258126Y476952D01*
G01X1258840Y479010D02*
X1257732Y477902D01*
G01X1258126Y476952D02*
X1252971D01*
G01X1257732Y477902D02*
X1252653D01*
G01X1252971Y476952D02*
X1244243Y470374D01*
G01X1252653Y477902D02*
X1248060Y474441D01*
G01X1252971Y476952D02*
X1244243Y470374D01*
G01X1248060Y474441D02*
X1248059D01*
G01X1244243Y470374D02*
X1244242D01*
G01X1270890Y484550D02*
X1277444D01*
G01X1277300Y485500D02*
X1270496D01*
G01X1269110Y482770D02*
X1270890Y484550D01*
G01X1270496Y485500D02*
X1268716Y483720D01*
G01X1258527Y482770D02*
X1269110D01*
G01X1268716Y483720D02*
X1258133D01*
G01X1256539Y480782D02*
X1258527Y482770D01*
G01X1258133Y483720D02*
X1256145Y481732D01*
G01X1249265Y480782D02*
X1256539D01*
G01X1256145Y481732D02*
X1248947D01*
G01X1232141Y467872D02*
X1249265Y480782D01*
G01X1248947Y481732D02*
X1239722Y474778D01*
G01X1232141Y467872D02*
X1249265Y480782D01*
G01X1232141Y467872D02*
X1229608Y465962D01*
G01X1239722Y474778D02*
X1228851Y466582D01*
G01X1244272Y483753D02*
X1234100Y475081D01*
G01X1224024Y466488D02*
X1234100Y475081D01*
G01X1225284Y468813D02*
X1243800Y484600D01*
G01X1250001Y485591D02*
X1244272Y483753D01*
G01X1243800Y484600D02*
X1249557Y486447D01*
G01X1252850Y487740D02*
X1250001Y485591D01*
G01X1249557Y486447D02*
X1252532Y488690D01*
G01X1261610Y487740D02*
X1252850D01*
G01X1252532Y488690D02*
X1261800D01*
G01X1224024Y466488D02*
X1234100Y475081D01*
G01X1223252Y467080D02*
X1225284Y468813D01*
G01X1258343Y465300D02*
X1260356D01*
G01X1260750Y466250D02*
X1257949D01*
G01X1263778Y472626D02*
X1256199D01*
G01X1263824Y471676D02*
X1256488D01*
G01D02*
X1254389Y470270D01*
G01X1277050Y477000D02*
X1270850D01*
G01X1277444Y476050D02*
X1270456D01*
G01X1270850Y477000D02*
X1268840Y479010D01*
G01X1270456Y476050D02*
X1268446Y478060D01*
G01X1268840Y479010D02*
X1258840D01*
G01X1268446Y478060D02*
X1259234D01*
G01X1258840Y479010D02*
X1257732Y477902D01*
G01X1259234Y478060D02*
X1258126Y476952D01*
G01X1257732Y477902D02*
X1252653D01*
G01X1258126Y476952D02*
X1252971D01*
G01X1252653Y477902D02*
X1248060Y474441D01*
G01D02*
X1248059D01*
G01X1252971Y476952D02*
X1244243Y470374D01*
G01D02*
X1244242D01*
G01X1248947Y481732D02*
X1239722Y474778D01*
G01D02*
X1228851Y466582D01*
G01X1232141Y467872D02*
X1249265Y480782D01*
G01X1256145Y481732D02*
X1248947D01*
G01X1249265Y480782D02*
X1256539D01*
G01X1258133Y483720D02*
X1256145Y481732D01*
G01X1256539Y480782D02*
X1258527Y482770D01*
G01X1268716Y483720D02*
X1258133D01*
G01X1258527Y482770D02*
X1269110D01*
G01X1270496Y485500D02*
X1268716Y483720D01*
G01X1269110Y482770D02*
X1270890Y484550D01*
G01X1277300Y485500D02*
X1270496D01*
G01X1270890Y484550D02*
X1277444D01*
G01X1239722Y474778D02*
X1228851Y466582D01*
G01X1232141Y467872D02*
X1229608Y465962D01*
G01X1252532Y488690D02*
X1261800D01*
G01X1261610Y487740D02*
X1252850D01*
G01X1249557Y486447D02*
X1252532Y488690D01*
G01X1252850Y487740D02*
X1250001Y485591D01*
G01X1243800Y484600D02*
X1249557Y486447D01*
G01X1250001Y485591D02*
X1244272Y483753D01*
G01X1225284Y468813D02*
X1243800Y484600D01*
G01X1244272Y483753D02*
X1234100Y475081D01*
G01X1225284Y468813D02*
X1243800Y484600D01*
G01X1223252Y467080D02*
X1225284Y468813D01*
G01X1224024Y466488D02*
X1234100Y475081D01*
G01X1260750Y466250D02*
X1257949D01*
G01X1258343Y465300D02*
X1260356D01*
G01X1263824Y471676D02*
X1256488D01*
G01X1263778Y472626D02*
X1256199D01*
G01X1256488Y471676D02*
X1254389Y470270D01*
G01X1258343Y465300D02*
X1260356D01*
G01X1260750Y466250D02*
X1257949D01*
G01X1277444Y476050D02*
X1270456D01*
G01X1277050Y477000D02*
X1270850D01*
G01X1270456Y476050D02*
X1268446Y478060D01*
G01X1270850Y477000D02*
X1268840Y479010D01*
G01X1268446Y478060D02*
X1259234D01*
G01X1268840Y479010D02*
X1258840D01*
G01X1259234Y478060D02*
X1258126Y476952D01*
G01X1258840Y479010D02*
X1257732Y477902D01*
G01X1258126Y476952D02*
X1252971D01*
G01X1257732Y477902D02*
X1252653D01*
G01X1252971Y476952D02*
X1244243Y470374D01*
G01X1252653Y477902D02*
X1248060Y474441D01*
G01X1252971Y476952D02*
X1244243Y470374D01*
G01X1248060Y474441D02*
X1248059D01*
G01X1244243Y470374D02*
X1244242D01*
G01X1270890Y484550D02*
X1277444D01*
G01X1277300Y485500D02*
X1270496D01*
G01X1269110Y482770D02*
X1270890Y484550D01*
G01X1270496Y485500D02*
X1268716Y483720D01*
G01X1258527Y482770D02*
X1269110D01*
G01X1268716Y483720D02*
X1258133D01*
G01X1256539Y480782D02*
X1258527Y482770D01*
G01X1258133Y483720D02*
X1256145Y481732D01*
G01X1249265Y480782D02*
X1256539D01*
G01X1256145Y481732D02*
X1248947D01*
G01X1232141Y467872D02*
X1249265Y480782D01*
G01X1248947Y481732D02*
X1239722Y474778D01*
G01X1232141Y467872D02*
X1249265Y480782D01*
G01X1232141Y467872D02*
X1229608Y465962D01*
G01X1239722Y474778D02*
X1228851Y466582D01*
G01X1244272Y483753D02*
X1234100Y475081D01*
G01X1224024Y466488D02*
X1234100Y475081D01*
G01X1225284Y468813D02*
X1243800Y484600D01*
G01X1250001Y485591D02*
X1244272Y483753D01*
G01X1243800Y484600D02*
X1249557Y486447D01*
G01X1252850Y487740D02*
X1250001Y485591D01*
G01X1249557Y486447D02*
X1252532Y488690D01*
G01X1261610Y487740D02*
X1252850D01*
G01X1252532Y488690D02*
X1261800D01*
G01X1224024Y466488D02*
X1234100Y475081D01*
G01X1223252Y467080D02*
X1225284Y468813D01*
G01X1263778Y472626D02*
X1256199D01*
G01X1263824Y471676D02*
X1256488D01*
G01D02*
X1254389Y470270D01*
G01X1277050Y477000D02*
X1270850D01*
G01X1277444Y476050D02*
X1270456D01*
G01X1270850Y477000D02*
X1268840Y479010D01*
G01X1270456Y476050D02*
X1268446Y478060D01*
G01X1268840Y479010D02*
X1258840D01*
G01X1268446Y478060D02*
X1259234D01*
G01X1258840Y479010D02*
X1257732Y477902D01*
G01X1259234Y478060D02*
X1258126Y476952D01*
G01X1257732Y477902D02*
X1252653D01*
G01X1258126Y476952D02*
X1252971D01*
G01X1252653Y477902D02*
X1248060Y474441D01*
G01D02*
X1248059D01*
G01X1252971Y476952D02*
X1244243Y470374D01*
G01D02*
X1244242D01*
G01X1248947Y481732D02*
X1239722Y474778D01*
G01D02*
X1228851Y466582D01*
G01X1232141Y467872D02*
X1249265Y480782D01*
G01X1256145Y481732D02*
X1248947D01*
G01X1249265Y480782D02*
X1256539D01*
G01X1258133Y483720D02*
X1256145Y481732D01*
G01X1256539Y480782D02*
X1258527Y482770D01*
G01X1268716Y483720D02*
X1258133D01*
G01X1258527Y482770D02*
X1269110D01*
G01X1270496Y485500D02*
X1268716Y483720D01*
G01X1269110Y482770D02*
X1270890Y484550D01*
G01X1277300Y485500D02*
X1270496D01*
G01X1270890Y484550D02*
X1277444D01*
G01X1239722Y474778D02*
X1228851Y466582D01*
G01X1232141Y467872D02*
X1229608Y465962D01*
G01X1252532Y488690D02*
X1261800D01*
G01X1261610Y487740D02*
X1252850D01*
G01X1249557Y486447D02*
X1252532Y488690D01*
G01X1252850Y487740D02*
X1250001Y485591D01*
G01X1243800Y484600D02*
X1249557Y486447D01*
G01X1250001Y485591D02*
X1244272Y483753D01*
G01X1225284Y468813D02*
X1243800Y484600D01*
G01X1244272Y483753D02*
X1234100Y475081D01*
G01X1225284Y468813D02*
X1243800Y484600D01*
G01X1223252Y467080D02*
X1225284Y468813D01*
G01X1224024Y466488D02*
X1234100Y475081D01*
G01X1268393Y472351D02*
X1269553D01*
G01X1268521Y471401D02*
X1269159D01*
G01X1269553Y472351D02*
X1272124Y469780D01*
G01X1269159Y471401D02*
X1271730Y468830D01*
G01X1272124Y469780D02*
X1273773D01*
G01X1271730Y468830D02*
X1274167D01*
G01X1273773Y469780D02*
X1276096Y472103D01*
G01X1274167Y468830D02*
X1276490Y471153D01*
G01X1276096Y472103D02*
X1285068D01*
G01X1276490Y471153D02*
X1285462D01*
G01X1266649Y488500D02*
X1266200D01*
G01X1266056Y487550D02*
X1266893D01*
G01X1270691Y490720D02*
X1266649Y488500D01*
G01D02*
X1266200D01*
G01X1266893Y487550D02*
X1271347Y489996D01*
G01X1272514Y493385D02*
X1270691Y490720D01*
G01X1271347Y489996D02*
X1273146Y492626D01*
G01X1276956Y495359D02*
X1272514Y493385D01*
G01X1273146Y492626D02*
X1277055Y494363D01*
G01X1280883Y494484D02*
X1276956Y495359D01*
G01X1277055Y494363D02*
X1281014Y493481D01*
G01X1268521Y471401D02*
X1269159D01*
G01X1268393Y472351D02*
X1269553D01*
G01X1269159Y471401D02*
X1271730Y468830D01*
G01X1269553Y472351D02*
X1272124Y469780D01*
G01X1271730Y468830D02*
X1274167D01*
G01X1272124Y469780D02*
X1273773D01*
G01X1274167Y468830D02*
X1276490Y471153D01*
G01X1273773Y469780D02*
X1276096Y472103D01*
G01X1276490Y471153D02*
X1285462D01*
G01X1276096Y472103D02*
X1285068D01*
G01X1277055Y494363D02*
X1281014Y493481D01*
G01X1280883Y494484D02*
X1276956Y495359D01*
G01X1273146Y492626D02*
X1277055Y494363D01*
G01X1276956Y495359D02*
X1272514Y493385D01*
G01X1271347Y489996D02*
X1273146Y492626D01*
G01X1272514Y493385D02*
X1270691Y490720D01*
G01X1266893Y487550D02*
X1271347Y489996D01*
G01X1270691Y490720D02*
X1266649Y488500D01*
G01X1266056Y487550D02*
X1266893D01*
G01D02*
X1271347Y489996D01*
G01X1266649Y488500D02*
X1266200D01*
G01X1266649D02*
X1266200D01*
G01X1266056Y487550D02*
X1266893D01*
G01X1270691Y490720D02*
X1266649Y488500D01*
G01D02*
X1266200D01*
G01X1266893Y487550D02*
X1271347Y489996D01*
G01X1272514Y493385D02*
X1270691Y490720D01*
G01X1271347Y489996D02*
X1273146Y492626D01*
G01X1276956Y495359D02*
X1272514Y493385D01*
G01X1273146Y492626D02*
X1277055Y494363D01*
G01X1280883Y494484D02*
X1276956Y495359D01*
G01X1277055Y494363D02*
X1281014Y493481D01*
G01X1277055Y494363D02*
X1281014Y493481D01*
G01X1280883Y494484D02*
X1276956Y495359D01*
G01X1273146Y492626D02*
X1277055Y494363D01*
G01X1276956Y495359D02*
X1272514Y493385D01*
G01X1271347Y489996D02*
X1273146Y492626D01*
G01X1272514Y493385D02*
X1270691Y490720D01*
G01X1266893Y487550D02*
X1271347Y489996D01*
G01X1270691Y490720D02*
X1266649Y488500D01*
G01X1266056Y487550D02*
X1266893D01*
G01D02*
X1271347Y489996D01*
G01X1266649Y488500D02*
X1266200D01*
G01X1268393Y472351D02*
X1269553D01*
G01X1268521Y471401D02*
X1269159D01*
G01X1269553Y472351D02*
X1272124Y469780D01*
G01X1269159Y471401D02*
X1271730Y468830D01*
G01X1272124Y469780D02*
X1273773D01*
G01X1271730Y468830D02*
X1274167D01*
G01X1273773Y469780D02*
X1276096Y472103D01*
G01X1274167Y468830D02*
X1276490Y471153D01*
G01X1276096Y472103D02*
X1285068D01*
G01X1276490Y471153D02*
X1285462D01*
G01X1268521Y471401D02*
X1269159D01*
G01X1268393Y472351D02*
X1269553D01*
G01X1269159Y471401D02*
X1271730Y468830D01*
G01X1269553Y472351D02*
X1272124Y469780D01*
G01X1271730Y468830D02*
X1274167D01*
G01X1272124Y469780D02*
X1273773D01*
G01X1274167Y468830D02*
X1276490Y471153D01*
G01X1273773Y469780D02*
X1276096Y472103D01*
G01X1276490Y471153D02*
X1285462D01*
G01X1276096Y472103D02*
X1285068D01*
G01X1343700Y180620D02*
X1334999Y182360D01*
G01X1343700Y179651D02*
X1334999Y181391D01*
G01Y182360D02*
X1327516Y180863D01*
G01X1334997Y181390D02*
X1327458Y179882D01*
G01X1327516Y180863D02*
X1303911Y188584D01*
G01X1327458Y179882D02*
X1303457Y187732D01*
G01D02*
X1288111Y199713D01*
G01X1335451Y201001D02*
X1343550Y199381D01*
G01Y200350D02*
X1335451Y201970D01*
G01X1329046Y199719D02*
X1335451Y201001D01*
G01Y201970D02*
X1329101Y200700D01*
G01X1317211Y203514D02*
X1329046Y199719D01*
G01X1329101Y200700D02*
X1317666Y204368D01*
G01X1293820Y221977D02*
X1317211Y203514D01*
G01X1317666Y204368D02*
X1316231Y205501D01*
G01X1293820Y221977D02*
X1317211Y203514D01*
G01X1292458Y224263D02*
X1316231Y205501D01*
G01X1315359Y201114D02*
X1311820Y203878D01*
G01D02*
X1290284Y220702D01*
G01X1289584Y220043D02*
X1314905Y200262D01*
G01X1328715Y196743D02*
X1315359Y201114D01*
G01X1314905Y200262D02*
X1328656Y195762D01*
G01X1335302Y198059D02*
X1328715Y196743D01*
G01X1328656Y195762D02*
X1335302Y197090D01*
G01X1343500Y196420D02*
X1335302Y198059D01*
G01Y197090D02*
X1343500Y195451D01*
G01X1282219Y219893D02*
X1310944Y197466D01*
G01X1282919Y220552D02*
X1311398Y198318D01*
G01X1310944Y197466D02*
X1328329Y191777D01*
G01X1311398Y198318D02*
X1328387Y192758D01*
G01X1328329Y191777D02*
X1335400Y193191D01*
G01X1328387Y192758D02*
X1335400Y194160D01*
G01X1335402Y193190D02*
X1343550Y191561D01*
G01X1335400Y194160D02*
X1343550Y192530D01*
G01X1343649Y187561D02*
X1335249Y189241D01*
G01X1343649Y188530D02*
X1335251Y190210D01*
G01X1335249Y189240D02*
X1328065Y187804D01*
G01X1335251Y190210D02*
X1328123Y188785D01*
G01X1328065Y187804D02*
X1308849Y194089D01*
G01X1328123Y188785D02*
X1309302Y194942D01*
G01X1308848Y194090D02*
X1281987Y215066D01*
G01X1309302Y194942D02*
X1303647Y199358D01*
G01X1308848Y194090D02*
X1281987Y215066D01*
G01X1303647Y199358D02*
X1303646D01*
G01X1308848Y194090D02*
X1281987Y215066D01*
G01X1303646Y199360D02*
X1280372Y217533D01*
G01X1307208Y191566D02*
X1286850Y207463D01*
G01X1296586Y198653D02*
X1306754Y190714D01*
G01X1327814Y184823D02*
X1307208Y191566D01*
G01X1306754Y190714D02*
X1327756Y183842D01*
G01X1335050Y186270D02*
X1327814Y184823D01*
G01X1327756Y183842D02*
X1335051Y185301D01*
G01X1343750Y184530D02*
X1335050Y186270D01*
G01X1335051Y185300D02*
X1343750Y183561D01*
G01X1343700Y179651D02*
X1334999Y181391D01*
G01X1343700Y180620D02*
X1334999Y182360D01*
G01X1334997Y181390D02*
X1327458Y179882D01*
G01X1334999Y182360D02*
X1327516Y180863D01*
G01X1327458Y179882D02*
X1303457Y187732D01*
G01X1327516Y180863D02*
X1303911Y188584D01*
G01X1303457Y187732D02*
X1288111Y199713D01*
G01X1308511Y220845D02*
X1317625Y213525D01*
G01X1309200Y221511D02*
X1318085Y214375D01*
G01X1317625Y213525D02*
X1323373Y211645D01*
G01X1318085Y214375D02*
X1323431Y212626D01*
G01X1323373Y211645D02*
X1327598Y212491D01*
G01X1323431Y212626D02*
X1327598Y213460D01*
G01Y212491D02*
X1331799Y211651D01*
G01X1327598Y213460D02*
X1331799Y212620D01*
G01Y211651D02*
X1339799Y213251D01*
G01X1331799Y212620D02*
X1339799Y214220D01*
G01Y213251D02*
X1346850Y211841D01*
G01X1339799Y214220D02*
X1346850Y212810D01*
G01X1319142Y206977D02*
X1306990Y216465D01*
G01X1307675Y217136D02*
X1319596Y207829D01*
G01X1329311Y203653D02*
X1319142Y206977D01*
G01X1319596Y207829D02*
X1329369Y204634D01*
G01X1335650Y204921D02*
X1329311Y203653D01*
G01X1329369Y204634D02*
X1335650Y205890D01*
G01X1343650Y203321D02*
X1335650Y204921D01*
G01Y205890D02*
X1343650Y204290D01*
G01X1317666Y204368D02*
X1316231Y205501D01*
G01X1292458Y224263D02*
X1316231Y205501D01*
G01X1293820Y221977D02*
X1317211Y203514D01*
G01X1329101Y200700D02*
X1317666Y204368D01*
G01X1317211Y203514D02*
X1329046Y199719D01*
G01X1335451Y201970D02*
X1329101Y200700D01*
G01X1329046Y199719D02*
X1335451Y201001D01*
G01X1343550Y200350D02*
X1335451Y201970D01*
G01Y201001D02*
X1343550Y199381D01*
G01X1292458Y224263D02*
X1316231Y205501D01*
G01X1335302Y197090D02*
X1343500Y195451D01*
G01Y196420D02*
X1335302Y198059D01*
G01X1328656Y195762D02*
X1335302Y197090D01*
G01Y198059D02*
X1328715Y196743D01*
G01X1314905Y200262D02*
X1328656Y195762D01*
G01X1328715Y196743D02*
X1315359Y201114D01*
G01X1289584Y220043D02*
X1314905Y200262D01*
G01X1315359Y201114D02*
X1311820Y203878D01*
G01X1289584Y220043D02*
X1314905Y200262D01*
G01X1311820Y203878D02*
X1290284Y220702D01*
G01X1282919Y220552D02*
X1311398Y198318D01*
G01X1282219Y219893D02*
X1310944Y197466D01*
G01X1311398Y198318D02*
X1328387Y192758D01*
G01X1310944Y197466D02*
X1328329Y191777D01*
G01X1328387Y192758D02*
X1335400Y194160D01*
G01X1328329Y191777D02*
X1335400Y193191D01*
G01Y194160D02*
X1343550Y192530D01*
G01X1335402Y193190D02*
X1343550Y191561D01*
G01X1343649Y188530D02*
X1335251Y190210D01*
G01X1343649Y187561D02*
X1335249Y189241D01*
G01X1335251Y190210D02*
X1328123Y188785D01*
G01X1335249Y189240D02*
X1328065Y187804D01*
G01X1328123Y188785D02*
X1309302Y194942D01*
G01X1328065Y187804D02*
X1308849Y194089D01*
G01X1309302Y194942D02*
X1303647Y199358D01*
G01D02*
X1303646D01*
G01Y199360D02*
X1280372Y217533D01*
G01X1308848Y194090D02*
X1281987Y215066D01*
G01X1303646Y199360D02*
X1280372Y217533D01*
G01X1335051Y185300D02*
X1343750Y183561D01*
G01Y184530D02*
X1335050Y186270D01*
G01X1327756Y183842D02*
X1335051Y185301D01*
G01X1335050Y186270D02*
X1327814Y184823D01*
G01X1306754Y190714D02*
X1327756Y183842D01*
G01X1327814Y184823D02*
X1307208Y191566D01*
G01X1296586Y198653D02*
X1306754Y190714D01*
G01X1307208Y191566D02*
X1286850Y207463D01*
G01X1309200Y221511D02*
X1318085Y214375D01*
G01X1308511Y220845D02*
X1317625Y213525D01*
G01X1318085Y214375D02*
X1323431Y212626D01*
G01X1317625Y213525D02*
X1323373Y211645D01*
G01X1323431Y212626D02*
X1327598Y213460D01*
G01X1323373Y211645D02*
X1327598Y212491D01*
G01Y213460D02*
X1331799Y212620D01*
G01X1327598Y212491D02*
X1331799Y211651D01*
G01Y212620D02*
X1339799Y214220D01*
G01X1331799Y211651D02*
X1339799Y213251D01*
G01Y214220D02*
X1346850Y212810D01*
G01X1339799Y213251D02*
X1346850Y211841D01*
G01X1335650Y205890D02*
X1343650Y204290D01*
G01Y203321D02*
X1335650Y204921D01*
G01X1329369Y204634D02*
X1335650Y205890D01*
G01Y204921D02*
X1329311Y203653D01*
G01X1319596Y207829D02*
X1329369Y204634D01*
G01X1329311Y203653D02*
X1319142Y206977D01*
G01X1307675Y217136D02*
X1319596Y207829D01*
G01X1319142Y206977D02*
X1306990Y216465D01*
G01X1343700Y179651D02*
X1334999Y181391D01*
G01X1343700Y180620D02*
X1334999Y182360D01*
G01X1334997Y181390D02*
X1327458Y179882D01*
G01X1334999Y182360D02*
X1327516Y180863D01*
G01X1327458Y179882D02*
X1303457Y187732D01*
G01X1327516Y180863D02*
X1303911Y188584D01*
G01X1303457Y187732D02*
X1288111Y199713D01*
G01X1282219Y219893D02*
X1310944Y197466D01*
G01X1282919Y220552D02*
X1311398Y198318D01*
G01X1310944Y197466D02*
X1328329Y191777D01*
G01X1311398Y198318D02*
X1328387Y192758D01*
G01X1328329Y191777D02*
X1335400Y193191D01*
G01X1328387Y192758D02*
X1335400Y194160D01*
G01X1335402Y193190D02*
X1343550Y191561D01*
G01X1335400Y194160D02*
X1343550Y192530D01*
G01X1319142Y206977D02*
X1306990Y216465D01*
G01X1307675Y217136D02*
X1319596Y207829D01*
G01X1329311Y203653D02*
X1319142Y206977D01*
G01X1319596Y207829D02*
X1329369Y204634D01*
G01X1335650Y204921D02*
X1329311Y203653D01*
G01X1329369Y204634D02*
X1335650Y205890D01*
G01X1343650Y203321D02*
X1335650Y204921D01*
G01Y205890D02*
X1343650Y204290D01*
G01X1335302Y197090D02*
X1343500Y195451D01*
G01Y196420D02*
X1335302Y198059D01*
G01X1328656Y195762D02*
X1335302Y197090D01*
G01Y198059D02*
X1328715Y196743D01*
G01X1314905Y200262D02*
X1328656Y195762D01*
G01X1328715Y196743D02*
X1315359Y201114D01*
G01X1289584Y220043D02*
X1314905Y200262D01*
G01X1315359Y201114D02*
X1311820Y203878D01*
G01X1289584Y220043D02*
X1314905Y200262D01*
G01X1311820Y203878D02*
X1290284Y220702D01*
G01X1282919Y220552D02*
X1311398Y198318D01*
G01X1282219Y219893D02*
X1310944Y197466D01*
G01X1311398Y198318D02*
X1328387Y192758D01*
G01X1310944Y197466D02*
X1328329Y191777D01*
G01X1328387Y192758D02*
X1335400Y194160D01*
G01X1328329Y191777D02*
X1335400Y193191D01*
G01Y194160D02*
X1343550Y192530D01*
G01X1335402Y193190D02*
X1343550Y191561D01*
G01X1335650Y205890D02*
X1343650Y204290D01*
G01Y203321D02*
X1335650Y204921D01*
G01X1329369Y204634D02*
X1335650Y205890D01*
G01Y204921D02*
X1329311Y203653D01*
G01X1319596Y207829D02*
X1329369Y204634D01*
G01X1329311Y203653D02*
X1319142Y206977D01*
G01X1307675Y217136D02*
X1319596Y207829D01*
G01X1319142Y206977D02*
X1306990Y216465D01*
G01X1335451Y201001D02*
X1343550Y199381D01*
G01Y200350D02*
X1335451Y201970D01*
G01X1329046Y199719D02*
X1335451Y201001D01*
G01Y201970D02*
X1329101Y200700D01*
G01X1317211Y203514D02*
X1329046Y199719D01*
G01X1329101Y200700D02*
X1317666Y204368D01*
G01X1293820Y221977D02*
X1317211Y203514D01*
G01X1317666Y204368D02*
X1316231Y205501D01*
G01X1293820Y221977D02*
X1317211Y203514D01*
G01X1292458Y224263D02*
X1316231Y205501D01*
G01X1315359Y201114D02*
X1311820Y203878D01*
G01D02*
X1290284Y220702D01*
G01X1289584Y220043D02*
X1314905Y200262D01*
G01X1328715Y196743D02*
X1315359Y201114D01*
G01X1314905Y200262D02*
X1328656Y195762D01*
G01X1335302Y198059D02*
X1328715Y196743D01*
G01X1328656Y195762D02*
X1335302Y197090D01*
G01X1343500Y196420D02*
X1335302Y198059D01*
G01Y197090D02*
X1343500Y195451D01*
G01X1343649Y187561D02*
X1335249Y189241D01*
G01X1343649Y188530D02*
X1335251Y190210D01*
G01X1335249Y189240D02*
X1328065Y187804D01*
G01X1335251Y190210D02*
X1328123Y188785D01*
G01X1328065Y187804D02*
X1308849Y194089D01*
G01X1328123Y188785D02*
X1309302Y194942D01*
G01X1308848Y194090D02*
X1281987Y215066D01*
G01X1309302Y194942D02*
X1303647Y199358D01*
G01X1308848Y194090D02*
X1281987Y215066D01*
G01X1303647Y199358D02*
X1303646D01*
G01X1308848Y194090D02*
X1281987Y215066D01*
G01X1303646Y199360D02*
X1280372Y217533D01*
G01X1307208Y191566D02*
X1286850Y207463D01*
G01X1296586Y198653D02*
X1306754Y190714D01*
G01X1327814Y184823D02*
X1307208Y191566D01*
G01X1306754Y190714D02*
X1327756Y183842D01*
G01X1335050Y186270D02*
X1327814Y184823D01*
G01X1327756Y183842D02*
X1335051Y185301D01*
G01X1343750Y184530D02*
X1335050Y186270D01*
G01X1335051Y185300D02*
X1343750Y183561D01*
G01X1317666Y204368D02*
X1316231Y205501D01*
G01X1292458Y224263D02*
X1316231Y205501D01*
G01X1293820Y221977D02*
X1317211Y203514D01*
G01X1329101Y200700D02*
X1317666Y204368D01*
G01X1317211Y203514D02*
X1329046Y199719D01*
G01X1335451Y201970D02*
X1329101Y200700D01*
G01X1329046Y199719D02*
X1335451Y201001D01*
G01X1343550Y200350D02*
X1335451Y201970D01*
G01Y201001D02*
X1343550Y199381D01*
G01X1292458Y224263D02*
X1316231Y205501D01*
G01X1343649Y188530D02*
X1335251Y190210D01*
G01X1343649Y187561D02*
X1335249Y189241D01*
G01X1335251Y190210D02*
X1328123Y188785D01*
G01X1335249Y189240D02*
X1328065Y187804D01*
G01X1328123Y188785D02*
X1309302Y194942D01*
G01X1328065Y187804D02*
X1308849Y194089D01*
G01X1309302Y194942D02*
X1303647Y199358D01*
G01D02*
X1303646D01*
G01Y199360D02*
X1280372Y217533D01*
G01X1308848Y194090D02*
X1281987Y215066D01*
G01X1303646Y199360D02*
X1280372Y217533D01*
G01X1335051Y185300D02*
X1343750Y183561D01*
G01Y184530D02*
X1335050Y186270D01*
G01X1327756Y183842D02*
X1335051Y185301D01*
G01X1335050Y186270D02*
X1327814Y184823D01*
G01X1306754Y190714D02*
X1327756Y183842D01*
G01X1327814Y184823D02*
X1307208Y191566D01*
G01X1296586Y198653D02*
X1306754Y190714D01*
G01X1307208Y191566D02*
X1286850Y207463D01*
G01X1343700Y180620D02*
X1334999Y182360D01*
G01X1343700Y179651D02*
X1334999Y181391D01*
G01Y182360D02*
X1327516Y180863D01*
G01X1334997Y181390D02*
X1327458Y179882D01*
G01X1327516Y180863D02*
X1303911Y188584D01*
G01X1327458Y179882D02*
X1303457Y187732D01*
G01D02*
X1288111Y199713D01*
G01X1308511Y220845D02*
X1317625Y213525D01*
G01X1309200Y221511D02*
X1318085Y214375D01*
G01X1317625Y213525D02*
X1323373Y211645D01*
G01X1318085Y214375D02*
X1323431Y212626D01*
G01X1323373Y211645D02*
X1327598Y212491D01*
G01X1323431Y212626D02*
X1327598Y213460D01*
G01Y212491D02*
X1331799Y211651D01*
G01X1327598Y213460D02*
X1331799Y212620D01*
G01Y211651D02*
X1339799Y213251D01*
G01X1331799Y212620D02*
X1339799Y214220D01*
G01Y213251D02*
X1346850Y211841D01*
G01X1339799Y214220D02*
X1346850Y212810D01*
G01X1309200Y221511D02*
X1318085Y214375D01*
G01X1308511Y220845D02*
X1317625Y213525D01*
G01X1318085Y214375D02*
X1323431Y212626D01*
G01X1317625Y213525D02*
X1323373Y211645D01*
G01X1323431Y212626D02*
X1327598Y213460D01*
G01X1323373Y211645D02*
X1327598Y212491D01*
G01Y213460D02*
X1331799Y212620D01*
G01X1327598Y212491D02*
X1331799Y211651D01*
G01Y212620D02*
X1339799Y214220D01*
G01X1331799Y211651D02*
X1339799Y213251D01*
G01Y214220D02*
X1346850Y212810D01*
G01X1339799Y213251D02*
X1346850Y211841D01*
G01X1291756Y223606D02*
X1293820Y221977D01*
G01X1284290Y227739D02*
X1289584Y220043D01*
G01X1354190Y245565D02*
X1334233Y249584D01*
G01X1354185Y246536D02*
X1334535Y250493D01*
G01X1334233Y249584D02*
X1316450Y258004D01*
G01X1334535Y250493D02*
X1316810Y258885D01*
G01X1316450Y258004D02*
X1297544Y264540D01*
G01X1316810Y258885D02*
X1298163Y265332D01*
G01X1297544Y264540D02*
X1292804Y271830D01*
G01X1298163Y265332D02*
X1293498Y272508D01*
G01X1310355Y250377D02*
X1354238Y241538D01*
G01X1354233Y242509D02*
X1310702Y251277D01*
G01X1294093Y260052D02*
X1310355Y250377D01*
G01X1310702Y251277D02*
X1294776Y260752D01*
G01X1287724Y270188D02*
X1294093Y260052D01*
G01X1294776Y260752D02*
X1288425Y270858D01*
G01X1347973Y220302D02*
X1332163Y224819D01*
G01X1348013Y221279D02*
X1332197Y225798D01*
G01X1332163Y224819D02*
X1327402Y223810D01*
G01X1332197Y225798D02*
X1327455Y224793D01*
G01X1327402Y223810D02*
X1312779Y228595D01*
G01X1327455Y224793D02*
X1313360Y229405D01*
G01X1312779Y228595D02*
X1290843Y257858D01*
G01X1313360Y229405D02*
X1291620Y258407D01*
G01X1290843Y257858D02*
X1284040Y268105D01*
G01X1291620Y258407D02*
X1284731Y268782D01*
G01X1331933Y220796D02*
X1347587Y216324D01*
G01X1347627Y217301D02*
X1331967Y221775D01*
G01X1327262Y219806D02*
X1331933Y220796D01*
G01X1331967Y221775D02*
X1327315Y220789D01*
G01X1309983Y225460D02*
X1327262Y219806D01*
G01X1327315Y220789D02*
X1310564Y226270D01*
G01X1291756Y223606D02*
X1293820Y221977D01*
G01X1284290Y227739D02*
X1289584Y220043D01*
G01X1354185Y246536D02*
X1334535Y250493D01*
G01X1354190Y245565D02*
X1334233Y249584D01*
G01X1334535Y250493D02*
X1316810Y258885D01*
G01X1334233Y249584D02*
X1316450Y258004D01*
G01X1316810Y258885D02*
X1298163Y265332D01*
G01X1316450Y258004D02*
X1297544Y264540D01*
G01X1298163Y265332D02*
X1293498Y272508D01*
G01X1297544Y264540D02*
X1292804Y271830D01*
G01X1294776Y260752D02*
X1288425Y270858D01*
G01X1287724Y270188D02*
X1294093Y260052D01*
G01X1310702Y251277D02*
X1294776Y260752D01*
G01X1294093Y260052D02*
X1310355Y250377D01*
G01X1354233Y242509D02*
X1310702Y251277D01*
G01X1310355Y250377D02*
X1354238Y241538D01*
G01X1348013Y221279D02*
X1332197Y225798D01*
G01X1347973Y220302D02*
X1332163Y224819D01*
G01X1332197Y225798D02*
X1327455Y224793D01*
G01X1332163Y224819D02*
X1327402Y223810D01*
G01X1327455Y224793D02*
X1313360Y229405D01*
G01X1327402Y223810D02*
X1312779Y228595D01*
G01X1313360Y229405D02*
X1291620Y258407D01*
G01X1312779Y228595D02*
X1290843Y257858D01*
G01X1291620Y258407D02*
X1284731Y268782D01*
G01X1290843Y257858D02*
X1284040Y268105D01*
G01X1327315Y220789D02*
X1310564Y226270D01*
G01X1309983Y225460D02*
X1327262Y219806D01*
G01X1331967Y221775D02*
X1327315Y220789D01*
G01X1327262Y219806D02*
X1331933Y220796D01*
G01X1347627Y217301D02*
X1331967Y221775D01*
G01X1331933Y220796D02*
X1347587Y216324D01*
G01X1280669Y299033D02*
X1315900Y275217D01*
G01X1281351Y299719D02*
X1316372Y276045D01*
G01X1315900Y275217D02*
X1338140Y264683D01*
G01X1316372Y276045D02*
X1338446Y265590D01*
G01X1338140Y264683D02*
X1353949Y261327D01*
G01X1338446Y265590D02*
X1353959Y262297D01*
G01X1313774Y273011D02*
X1337789Y261639D01*
G01X1313300Y272183D02*
X1337487Y260730D01*
G01X1337789Y261639D02*
X1354170Y258340D01*
G01X1337487Y260730D02*
X1354175Y257369D01*
G01X1354196Y253437D02*
X1336347Y257032D01*
G01X1354191Y254408D02*
X1336649Y257941D01*
G01X1336347Y257032D02*
X1311427Y268832D01*
G01X1336649Y257941D02*
X1311900Y269660D01*
G01X1308436Y266035D02*
X1335303Y253315D01*
G01X1308910Y266862D02*
X1335605Y254224D01*
G01X1335303Y253315D02*
X1354216Y249506D01*
G01X1335605Y254224D02*
X1354211Y250477D01*
G01X1281351Y299719D02*
X1316372Y276045D01*
G01X1280669Y299033D02*
X1315900Y275217D01*
G01X1316372Y276045D02*
X1338446Y265590D01*
G01X1315900Y275217D02*
X1338140Y264683D01*
G01X1338446Y265590D02*
X1353959Y262297D01*
G01X1338140Y264683D02*
X1353949Y261327D01*
G01X1313300Y272183D02*
X1337487Y260730D01*
G01X1313774Y273011D02*
X1337789Y261639D01*
G01X1337487Y260730D02*
X1354175Y257369D01*
G01X1337789Y261639D02*
X1354170Y258340D01*
G01X1354191Y254408D02*
X1336649Y257941D01*
G01X1354196Y253437D02*
X1336347Y257032D01*
G01X1336649Y257941D02*
X1311900Y269660D01*
G01X1336347Y257032D02*
X1311427Y268832D01*
G01X1308910Y266862D02*
X1335605Y254224D01*
G01X1308436Y266035D02*
X1335303Y253315D01*
G01X1335605Y254224D02*
X1354211Y250477D01*
G01X1335303Y253315D02*
X1354216Y249506D01*
G01X1310355Y250377D02*
X1354238Y241538D01*
G01X1354233Y242509D02*
X1310702Y251277D01*
G01X1294093Y260052D02*
X1310355Y250377D01*
G01X1310702Y251277D02*
X1294776Y260752D01*
G01X1287724Y270188D02*
X1294093Y260052D01*
G01X1294776Y260752D02*
X1288425Y270858D01*
G01X1347973Y220302D02*
X1332163Y224819D01*
G01X1348013Y221279D02*
X1332197Y225798D01*
G01X1332163Y224819D02*
X1327402Y223810D01*
G01X1332197Y225798D02*
X1327455Y224793D01*
G01X1327402Y223810D02*
X1312779Y228595D01*
G01X1327455Y224793D02*
X1313360Y229405D01*
G01X1312779Y228595D02*
X1290843Y257858D01*
G01X1313360Y229405D02*
X1291620Y258407D01*
G01X1290843Y257858D02*
X1284040Y268105D01*
G01X1291620Y258407D02*
X1284731Y268782D01*
G01X1331933Y220796D02*
X1347587Y216324D01*
G01X1347627Y217301D02*
X1331967Y221775D01*
G01X1327262Y219806D02*
X1331933Y220796D01*
G01X1331967Y221775D02*
X1327315Y220789D01*
G01X1309983Y225460D02*
X1327262Y219806D01*
G01X1327315Y220789D02*
X1310564Y226270D01*
G01X1284290Y227739D02*
X1289584Y220043D01*
G01X1294776Y260752D02*
X1288425Y270858D01*
G01X1287724Y270188D02*
X1294093Y260052D01*
G01X1310702Y251277D02*
X1294776Y260752D01*
G01X1294093Y260052D02*
X1310355Y250377D01*
G01X1354233Y242509D02*
X1310702Y251277D01*
G01X1310355Y250377D02*
X1354238Y241538D01*
G01X1348013Y221279D02*
X1332197Y225798D01*
G01X1347973Y220302D02*
X1332163Y224819D01*
G01X1332197Y225798D02*
X1327455Y224793D01*
G01X1332163Y224819D02*
X1327402Y223810D01*
G01X1327455Y224793D02*
X1313360Y229405D01*
G01X1327402Y223810D02*
X1312779Y228595D01*
G01X1313360Y229405D02*
X1291620Y258407D01*
G01X1312779Y228595D02*
X1290843Y257858D01*
G01X1291620Y258407D02*
X1284731Y268782D01*
G01X1290843Y257858D02*
X1284040Y268105D01*
G01X1327315Y220789D02*
X1310564Y226270D01*
G01X1309983Y225460D02*
X1327262Y219806D01*
G01X1331967Y221775D02*
X1327315Y220789D01*
G01X1327262Y219806D02*
X1331933Y220796D01*
G01X1347627Y217301D02*
X1331967Y221775D01*
G01X1331933Y220796D02*
X1347587Y216324D01*
G01X1280669Y299033D02*
X1315900Y275217D01*
G01X1281351Y299719D02*
X1316372Y276045D01*
G01X1315900Y275217D02*
X1338140Y264683D01*
G01X1316372Y276045D02*
X1338446Y265590D01*
G01X1338140Y264683D02*
X1353949Y261327D01*
G01X1338446Y265590D02*
X1353959Y262297D01*
G01X1313774Y273011D02*
X1337789Y261639D01*
G01X1313300Y272183D02*
X1337487Y260730D01*
G01X1337789Y261639D02*
X1354170Y258340D01*
G01X1337487Y260730D02*
X1354175Y257369D01*
G01X1354196Y253437D02*
X1336347Y257032D01*
G01X1354191Y254408D02*
X1336649Y257941D01*
G01X1336347Y257032D02*
X1311427Y268832D01*
G01X1336649Y257941D02*
X1311900Y269660D01*
G01X1308436Y266035D02*
X1335303Y253315D01*
G01X1308910Y266862D02*
X1335605Y254224D01*
G01X1335303Y253315D02*
X1354216Y249506D01*
G01X1335605Y254224D02*
X1354211Y250477D01*
G01X1354190Y245565D02*
X1334233Y249584D01*
G01X1354185Y246536D02*
X1334535Y250493D01*
G01X1334233Y249584D02*
X1316450Y258004D01*
G01X1334535Y250493D02*
X1316810Y258885D01*
G01X1316450Y258004D02*
X1297544Y264540D01*
G01X1316810Y258885D02*
X1298163Y265332D01*
G01X1297544Y264540D02*
X1292804Y271830D01*
G01X1298163Y265332D02*
X1293498Y272508D01*
G01X1281351Y299719D02*
X1316372Y276045D01*
G01X1280669Y299033D02*
X1315900Y275217D01*
G01X1316372Y276045D02*
X1338446Y265590D01*
G01X1315900Y275217D02*
X1338140Y264683D01*
G01X1338446Y265590D02*
X1353959Y262297D01*
G01X1338140Y264683D02*
X1353949Y261327D01*
G01X1313300Y272183D02*
X1337487Y260730D01*
G01X1313774Y273011D02*
X1337789Y261639D01*
G01X1337487Y260730D02*
X1354175Y257369D01*
G01X1337789Y261639D02*
X1354170Y258340D01*
G01X1354191Y254408D02*
X1336649Y257941D01*
G01X1354196Y253437D02*
X1336347Y257032D01*
G01X1336649Y257941D02*
X1311900Y269660D01*
G01X1336347Y257032D02*
X1311427Y268832D01*
G01X1308910Y266862D02*
X1335605Y254224D01*
G01X1308436Y266035D02*
X1335303Y253315D01*
G01X1335605Y254224D02*
X1354211Y250477D01*
G01X1335303Y253315D02*
X1354216Y249506D01*
G01X1354185Y246536D02*
X1334535Y250493D01*
G01X1354190Y245565D02*
X1334233Y249584D01*
G01X1334535Y250493D02*
X1316810Y258885D01*
G01X1334233Y249584D02*
X1316450Y258004D01*
G01X1316810Y258885D02*
X1298163Y265332D01*
G01X1316450Y258004D02*
X1297544Y264540D01*
G01X1298163Y265332D02*
X1293498Y272508D01*
G01X1297544Y264540D02*
X1292804Y271830D01*
G01X1291756Y223606D02*
X1293820Y221977D01*
G01X1284290Y227739D02*
X1289584Y220043D01*
G01X1291756Y223606D02*
X1293820Y221977D01*
G01X1338454Y310306D02*
Y307149D01*
G01X1339404Y307271D02*
Y310700D01*
G01X1336988Y311772D02*
X1338454Y310306D01*
G01X1339404Y310700D02*
X1337528Y312576D01*
G01X1335906Y312226D02*
X1336988Y311772D01*
G01X1337528Y312576D02*
X1336005Y313215D01*
G01X1330295Y311102D02*
X1335906Y312226D01*
G01X1336005Y313215D02*
X1330390Y312091D01*
G01X1318157Y316092D02*
X1319405Y315579D01*
G01X1321486Y314724D02*
X1322735Y314210D01*
G01X1324816Y313355D02*
X1326064Y312841D01*
G01X1328145Y311986D02*
X1330295Y311102D01*
G01X1330390Y312091D02*
X1285537Y330532D01*
G01X1342968Y321483D02*
X1338009Y322859D01*
G01X1343548Y322309D02*
X1338045Y323835D01*
G01X1338009Y322859D02*
X1332838Y321830D01*
G01X1330631Y321391D02*
X1329307Y321128D01*
G01X1338045Y323835D02*
X1329371Y322110D01*
G01X1329307Y321128D02*
X1319083Y324525D01*
G01X1316947Y325234D02*
X1315666Y325660D01*
G01X1313531Y326369D02*
X1312250Y326795D01*
G01X1310115Y327504D02*
X1308833Y327930D01*
G01X1339134Y327003D02*
X1330647Y325314D01*
G01X1330708Y326295D02*
X1339170Y327979D01*
G01X1340435Y326642D02*
X1339134Y327003D01*
G01X1339170Y327979D02*
X1350708Y324778D01*
G01X1341025Y331357D02*
X1350576Y329444D01*
G01X1369901Y326542D02*
X1341026Y332326D01*
G01X1330815Y329327D02*
X1341025Y331357D01*
G01X1341026Y332326D02*
X1330876Y330308D01*
G01X1320514Y340051D02*
X1314384Y338937D01*
G01X1314454Y339916D02*
X1320563Y341026D01*
G01X1326577Y338300D02*
X1320514Y340051D01*
G01X1320563Y341026D02*
X1326612Y339279D01*
G01X1331736Y339400D02*
X1326577Y338300D01*
G01X1326612Y339279D02*
X1331747Y340374D01*
G01X1338335Y337838D02*
X1331736Y339400D01*
G01X1331747Y340374D02*
X1338258Y338833D01*
G01X1349427Y342345D02*
X1338335Y337838D01*
G01X1338258Y338833D02*
X1349334Y343333D01*
G01X1330390Y312091D02*
X1285537Y330532D01*
G01X1330390Y312091D02*
X1285537Y330532D01*
G01X1318157Y316092D02*
X1319405Y315579D01*
G01X1330390Y312091D02*
X1285537Y330532D01*
G01X1321486Y314724D02*
X1322735Y314210D01*
G01X1330390Y312091D02*
X1285537Y330532D01*
G01X1324816Y313355D02*
X1326064Y312841D01*
G01X1330390Y312091D02*
X1285537Y330532D01*
G01X1328145Y311986D02*
X1330295Y311102D01*
G01X1336005Y313215D02*
X1330390Y312091D01*
G01X1330295Y311102D02*
X1335906Y312226D01*
G01X1337528Y312576D02*
X1336005Y313215D01*
G01X1335906Y312226D02*
X1336988Y311772D01*
G01X1339404Y310700D02*
X1337528Y312576D01*
G01X1336988Y311772D02*
X1338454Y310306D01*
G01X1339404Y307271D02*
Y310700D01*
G01X1338454Y310306D02*
Y307149D01*
G01X1343548Y322309D02*
X1338045Y323835D01*
G01X1343548Y322309D02*
X1338045Y323835D01*
G01X1342968Y321483D02*
X1338009Y322859D01*
G01X1338045Y323835D02*
X1329371Y322110D01*
G01X1338009Y322859D02*
X1332838Y321830D01*
G01X1338045Y323835D02*
X1329371Y322110D01*
G01X1330631Y321391D02*
X1329307Y321128D01*
G01D02*
X1319083Y324525D01*
G01X1316947Y325234D02*
X1315666Y325660D01*
G01X1313531Y326369D02*
X1312250Y326795D01*
G01X1310115Y327504D02*
X1308833Y327930D01*
G01X1339170Y327979D02*
X1350708Y324778D01*
G01X1339170Y327979D02*
X1350708Y324778D01*
G01X1339170Y327979D02*
X1350708Y324778D01*
G01X1340435Y326642D02*
X1339134Y327003D01*
G01X1330708Y326295D02*
X1339170Y327979D01*
G01X1339134Y327003D02*
X1330647Y325314D01*
G01X1341026Y332326D02*
X1330876Y330308D01*
G01X1330815Y329327D02*
X1341025Y331357D01*
G01X1369901Y326542D02*
X1341026Y332326D01*
G01X1341025Y331357D02*
X1350576Y329444D01*
G01X1369901Y326542D02*
X1341026Y332326D01*
G01X1369901Y326542D02*
X1341026Y332326D01*
G01X1369901Y326542D02*
X1341026Y332326D01*
G01X1369901Y326542D02*
X1341026Y332326D01*
G01X1338258Y338833D02*
X1349334Y343333D01*
G01X1349427Y342345D02*
X1338335Y337838D01*
G01X1331747Y340374D02*
X1338258Y338833D01*
G01X1338335Y337838D02*
X1331736Y339400D01*
G01X1326612Y339279D02*
X1331747Y340374D01*
G01X1331736Y339400D02*
X1326577Y338300D01*
G01X1320563Y341026D02*
X1326612Y339279D01*
G01X1326577Y338300D02*
X1320514Y340051D01*
G01X1314454Y339916D02*
X1320563Y341026D01*
G01X1320514Y340051D02*
X1314384Y338937D01*
G01X1342968Y321483D02*
X1338009Y322859D01*
G01X1343548Y322309D02*
X1338045Y323835D01*
G01X1338009Y322859D02*
X1332838Y321830D01*
G01X1330631Y321391D02*
X1329307Y321128D01*
G01X1338045Y323835D02*
X1329371Y322110D01*
G01X1329307Y321128D02*
X1319083Y324525D01*
G01X1316947Y325234D02*
X1315666Y325660D01*
G01X1313531Y326369D02*
X1312250Y326795D01*
G01X1310115Y327504D02*
X1308833Y327930D01*
G01X1330390Y312091D02*
X1285537Y330532D01*
G01X1330390Y312091D02*
X1285537Y330532D01*
G01X1318157Y316092D02*
X1319405Y315579D01*
G01X1330390Y312091D02*
X1285537Y330532D01*
G01X1321486Y314724D02*
X1322735Y314210D01*
G01X1330390Y312091D02*
X1285537Y330532D01*
G01X1324816Y313355D02*
X1326064Y312841D01*
G01X1330390Y312091D02*
X1285537Y330532D01*
G01X1328145Y311986D02*
X1330295Y311102D01*
G01X1336005Y313215D02*
X1330390Y312091D01*
G01X1330295Y311102D02*
X1335906Y312226D01*
G01X1337528Y312576D02*
X1336005Y313215D01*
G01X1335906Y312226D02*
X1336988Y311772D01*
G01X1339404Y310700D02*
X1337528Y312576D01*
G01X1336988Y311772D02*
X1338454Y310306D01*
G01X1339404Y307271D02*
Y310700D01*
G01X1338454Y310306D02*
Y307149D01*
G01X1343548Y322309D02*
X1338045Y323835D01*
G01X1343548Y322309D02*
X1338045Y323835D01*
G01X1342968Y321483D02*
X1338009Y322859D01*
G01X1338045Y323835D02*
X1329371Y322110D01*
G01X1338009Y322859D02*
X1332838Y321830D01*
G01X1338045Y323835D02*
X1329371Y322110D01*
G01X1330631Y321391D02*
X1329307Y321128D01*
G01D02*
X1319083Y324525D01*
G01X1316947Y325234D02*
X1315666Y325660D01*
G01X1313531Y326369D02*
X1312250Y326795D01*
G01X1310115Y327504D02*
X1308833Y327930D01*
G01X1339134Y327003D02*
X1330647Y325314D01*
G01X1330708Y326295D02*
X1339170Y327979D01*
G01X1340435Y326642D02*
X1339134Y327003D01*
G01X1339170Y327979D02*
X1350708Y324778D01*
G01X1341025Y331357D02*
X1350576Y329444D01*
G01X1369901Y326542D02*
X1341026Y332326D01*
G01X1330815Y329327D02*
X1341025Y331357D01*
G01X1341026Y332326D02*
X1330876Y330308D01*
G01X1320514Y340051D02*
X1314384Y338937D01*
G01X1314454Y339916D02*
X1320563Y341026D01*
G01X1326577Y338300D02*
X1320514Y340051D01*
G01X1320563Y341026D02*
X1326612Y339279D01*
G01X1331736Y339400D02*
X1326577Y338300D01*
G01X1326612Y339279D02*
X1331747Y340374D01*
G01X1338335Y337838D02*
X1331736Y339400D01*
G01X1331747Y340374D02*
X1338258Y338833D01*
G01X1349427Y342345D02*
X1338335Y337838D01*
G01X1338258Y338833D02*
X1349334Y343333D01*
G01X1339170Y327979D02*
X1350708Y324778D01*
G01X1339170Y327979D02*
X1350708Y324778D01*
G01X1339170Y327979D02*
X1350708Y324778D01*
G01X1340435Y326642D02*
X1339134Y327003D01*
G01X1330708Y326295D02*
X1339170Y327979D01*
G01X1339134Y327003D02*
X1330647Y325314D01*
G01X1341026Y332326D02*
X1330876Y330308D01*
G01X1330815Y329327D02*
X1341025Y331357D01*
G01X1369901Y326542D02*
X1341026Y332326D01*
G01X1341025Y331357D02*
X1350576Y329444D01*
G01X1369901Y326542D02*
X1341026Y332326D01*
G01X1369901Y326542D02*
X1341026Y332326D01*
G01X1369901Y326542D02*
X1341026Y332326D01*
G01X1369901Y326542D02*
X1341026Y332326D01*
G01X1338258Y338833D02*
X1349334Y343333D01*
G01X1349427Y342345D02*
X1338335Y337838D01*
G01X1331747Y340374D02*
X1338258Y338833D01*
G01X1338335Y337838D02*
X1331736Y339400D01*
G01X1326612Y339279D02*
X1331747Y340374D01*
G01X1331736Y339400D02*
X1326577Y338300D01*
G01X1320563Y341026D02*
X1326612Y339279D01*
G01X1326577Y338300D02*
X1320514Y340051D01*
G01X1314454Y339916D02*
X1320563Y341026D01*
G01X1320514Y340051D02*
X1314384Y338937D01*
G01X1338454Y310306D02*
Y307149D01*
G01X1339404Y307271D02*
Y310700D01*
G01X1336988Y311772D02*
X1338454Y310306D01*
G01X1339404Y310700D02*
X1337528Y312576D01*
G01X1335906Y312226D02*
X1336988Y311772D01*
G01X1337528Y312576D02*
X1336005Y313215D01*
G01X1330295Y311102D02*
X1335906Y312226D01*
G01X1336005Y313215D02*
X1330390Y312091D01*
G01X1318157Y316092D02*
X1319405Y315579D01*
G01X1321486Y314724D02*
X1322735Y314210D01*
G01X1324816Y313355D02*
X1326064Y312841D01*
G01X1328145Y311986D02*
X1330295Y311102D01*
G01X1330390Y312091D02*
X1285537Y330532D01*
G01X1349023Y347876D02*
X1341133Y353136D01*
G01X1349394Y348771D02*
X1341504Y354031D01*
G01X1341133Y353136D02*
X1334382Y354487D01*
G01X1341504Y354031D02*
X1334382Y355456D01*
G01Y354487D02*
X1328819Y353375D01*
G01X1334382Y355456D02*
X1328824Y354345D01*
G01X1328819Y353375D02*
X1321818Y354851D01*
G01X1328824Y354345D02*
X1321823Y355821D01*
G01X1321818Y354851D02*
X1315644Y353618D01*
G01X1321823Y355821D02*
X1315649Y354588D01*
G01X1315644Y353618D02*
X1308005Y355229D01*
G01X1315649Y354588D02*
X1308380Y356121D01*
G01X1308005Y355229D02*
X1288413Y368283D01*
G01X1308380Y356121D02*
X1289194Y368905D01*
G01X1288413Y368283D02*
X1284195Y379437D01*
G01X1280397Y389478D02*
X1284195Y379437D01*
G01X1289194Y368905D02*
X1282412Y386838D01*
G01X1280397Y389478D02*
X1284195Y379437D01*
G01X1281185Y390082D02*
X1282412Y386838D01*
G01X1290105Y374701D02*
X1284927Y388380D01*
G01X1287176Y385127D02*
X1288378Y381950D01*
G01X1291452Y371141D02*
X1290105Y374700D01*
G01Y374701D02*
X1284927Y388380D01*
G01X1288378Y381950D02*
X1292233Y371762D01*
G01X1310054Y358732D02*
X1291452Y371141D01*
G01X1292233Y371762D02*
X1310429Y359624D01*
G01X1315264Y357632D02*
X1310054Y358732D01*
G01X1310429Y359624D02*
X1315269Y358602D01*
G01X1321494Y358878D02*
X1315264Y357632D01*
G01X1315269Y358602D02*
X1321499Y359848D01*
G01X1328379Y357427D02*
X1321494Y358878D01*
G01X1321499Y359848D02*
X1328384Y358397D01*
G01X1333878Y358525D02*
X1328379Y357427D01*
G01X1328384Y358397D02*
X1333878Y359494D01*
G01X1344409Y356418D02*
X1333878Y358525D01*
G01Y359494D02*
X1344780Y357313D01*
G01X1290105Y374701D02*
X1284927Y388380D01*
G01X1287176Y385127D02*
X1285817Y388717D01*
G01X1284927Y388380D02*
X1283557Y392001D01*
G01X1285817Y388717D02*
X1284347Y392603D01*
G01X1338749Y364470D02*
X1345392Y363069D01*
G01X1345017Y362177D02*
X1338744Y363500D01*
G01X1328363Y362393D02*
X1338749Y364470D01*
G01X1338744Y363500D02*
X1328343Y361420D01*
G01X1308216Y367300D02*
X1328363Y362393D01*
G01X1328343Y361420D02*
X1311501Y365522D01*
G01X1308216Y367300D02*
X1328363Y362393D01*
G01X1309188Y366085D02*
X1307828Y366416D01*
G01X1294605Y376369D02*
X1308216Y367300D01*
G01X1307828Y366416D02*
X1306997Y366969D01*
G01X1294605Y376369D02*
X1308216Y367300D01*
G01X1305124Y368216D02*
X1304001Y368965D01*
G01X1294605Y376369D02*
X1308216Y367300D01*
G01X1302129Y370213D02*
X1301005Y370961D01*
G01X1294605Y376369D02*
X1308216Y367300D01*
G01X1301005Y370961D02*
X1300381Y370837D01*
G01X1294605Y376369D02*
X1308216Y367300D01*
G01X1299133Y372209D02*
X1298009Y372958D01*
G01X1294605Y376369D02*
X1308216Y367300D01*
G01X1296137Y374206D02*
X1293824Y375747D01*
G01X1289764Y389170D02*
X1294605Y376369D01*
G01X1293824Y375747D02*
X1291431Y382075D01*
G01X1288657Y392100D02*
X1289764Y389170D01*
G01D02*
X1294605Y376369D01*
G01X1288657Y392100D02*
X1287443Y395309D01*
G01X1291431Y382075D02*
X1286652Y394706D01*
G01X1349394Y348771D02*
X1341504Y354031D01*
G01X1349023Y347876D02*
X1341133Y353136D01*
G01X1341504Y354031D02*
X1334382Y355456D01*
G01X1341133Y353136D02*
X1334382Y354487D01*
G01Y355456D02*
X1328824Y354345D01*
G01X1334382Y354487D02*
X1328819Y353375D01*
G01X1328824Y354345D02*
X1321823Y355821D01*
G01X1328819Y353375D02*
X1321818Y354851D01*
G01X1321823Y355821D02*
X1315649Y354588D01*
G01X1321818Y354851D02*
X1315644Y353618D01*
G01X1315649Y354588D02*
X1308380Y356121D01*
G01X1315644Y353618D02*
X1308005Y355229D01*
G01X1308380Y356121D02*
X1289194Y368905D01*
G01X1308005Y355229D02*
X1288413Y368283D01*
G01X1289194Y368905D02*
X1282412Y386838D01*
G01X1288413Y368283D02*
X1284195Y379437D01*
G01X1289194Y368905D02*
X1282412Y386838D01*
G01X1281185Y390082D02*
X1282412Y386838D01*
G01X1280397Y389478D02*
X1284195Y379437D01*
G01X1333878Y359494D02*
X1344780Y357313D01*
G01X1344409Y356418D02*
X1333878Y358525D01*
G01X1328384Y358397D02*
X1333878Y359494D01*
G01Y358525D02*
X1328379Y357427D01*
G01X1321499Y359848D02*
X1328384Y358397D01*
G01X1328379Y357427D02*
X1321494Y358878D01*
G01X1315269Y358602D02*
X1321499Y359848D01*
G01X1321494Y358878D02*
X1315264Y357632D01*
G01X1310429Y359624D02*
X1315269Y358602D01*
G01X1315264Y357632D02*
X1310054Y358732D01*
G01X1292233Y371762D02*
X1310429Y359624D01*
G01X1310054Y358732D02*
X1291452Y371141D01*
G01X1288378Y381950D02*
X1292233Y371762D01*
G01X1291452Y371141D02*
X1290105Y374700D01*
G01X1287176Y385127D02*
X1288378Y381950D01*
G01D02*
X1292233Y371762D01*
G01X1287176Y385127D02*
X1285817Y388717D01*
G01X1290105Y374701D02*
X1284927Y388380D01*
G01X1285817Y388717D02*
X1284347Y392603D01*
G01X1284927Y388380D02*
X1283557Y392001D01*
G01X1291431Y382075D02*
X1286652Y394706D01*
G01X1288657Y392100D02*
X1289764Y389170D01*
G01X1293824Y375747D02*
X1291431Y382075D01*
G01D02*
X1286652Y394706D01*
G01X1289764Y389170D02*
X1294605Y376369D01*
G01X1307828Y366416D02*
X1306997Y366969D01*
G01X1305124Y368216D02*
X1304001Y368965D01*
G01X1302129Y370213D02*
X1301005Y370961D01*
G01D02*
X1300381Y370837D01*
G01X1299133Y372209D02*
X1298009Y372958D01*
G01X1296137Y374206D02*
X1293824Y375747D01*
G01X1294605Y376369D02*
X1308216Y367300D01*
G01X1328343Y361420D02*
X1311501Y365522D01*
G01X1309188Y366085D02*
X1307828Y366416D01*
G01X1308216Y367300D02*
X1328363Y362393D01*
G01X1338744Y363500D02*
X1328343Y361420D01*
G01X1328363Y362393D02*
X1338749Y364470D01*
G01X1345017Y362177D02*
X1338744Y363500D01*
G01X1338749Y364470D02*
X1345392Y363069D01*
G01X1291431Y382075D02*
X1286652Y394706D01*
G01X1288657Y392100D02*
X1287443Y395309D01*
G01X1349023Y347876D02*
X1341133Y353136D01*
G01X1349394Y348771D02*
X1341504Y354031D01*
G01X1341133Y353136D02*
X1334382Y354487D01*
G01X1341504Y354031D02*
X1334382Y355456D01*
G01Y354487D02*
X1328819Y353375D01*
G01X1334382Y355456D02*
X1328824Y354345D01*
G01X1328819Y353375D02*
X1321818Y354851D01*
G01X1328824Y354345D02*
X1321823Y355821D01*
G01X1321818Y354851D02*
X1315644Y353618D01*
G01X1321823Y355821D02*
X1315649Y354588D01*
G01X1315644Y353618D02*
X1308005Y355229D01*
G01X1315649Y354588D02*
X1308380Y356121D01*
G01X1308005Y355229D02*
X1288413Y368283D01*
G01X1308380Y356121D02*
X1289194Y368905D01*
G01X1288413Y368283D02*
X1284195Y379437D01*
G01X1280397Y389478D02*
X1284195Y379437D01*
G01X1289194Y368905D02*
X1282412Y386838D01*
G01X1280397Y389478D02*
X1284195Y379437D01*
G01X1281185Y390082D02*
X1282412Y386838D01*
G01X1290105Y374701D02*
X1284927Y388380D01*
G01X1287176Y385127D02*
X1288378Y381950D01*
G01X1291452Y371141D02*
X1290105Y374700D01*
G01Y374701D02*
X1284927Y388380D01*
G01X1288378Y381950D02*
X1292233Y371762D01*
G01X1310054Y358732D02*
X1291452Y371141D01*
G01X1292233Y371762D02*
X1310429Y359624D01*
G01X1315264Y357632D02*
X1310054Y358732D01*
G01X1310429Y359624D02*
X1315269Y358602D01*
G01X1321494Y358878D02*
X1315264Y357632D01*
G01X1315269Y358602D02*
X1321499Y359848D01*
G01X1328379Y357427D02*
X1321494Y358878D01*
G01X1321499Y359848D02*
X1328384Y358397D01*
G01X1333878Y358525D02*
X1328379Y357427D01*
G01X1328384Y358397D02*
X1333878Y359494D01*
G01X1344409Y356418D02*
X1333878Y358525D01*
G01Y359494D02*
X1344780Y357313D01*
G01X1290105Y374701D02*
X1284927Y388380D01*
G01X1287176Y385127D02*
X1285817Y388717D01*
G01X1284927Y388380D02*
X1283557Y392001D01*
G01X1285817Y388717D02*
X1284347Y392603D01*
G01X1338749Y364470D02*
X1345392Y363069D01*
G01X1345017Y362177D02*
X1338744Y363500D01*
G01X1328363Y362393D02*
X1338749Y364470D01*
G01X1338744Y363500D02*
X1328343Y361420D01*
G01X1308216Y367300D02*
X1328363Y362393D01*
G01X1328343Y361420D02*
X1311501Y365522D01*
G01X1308216Y367300D02*
X1328363Y362393D01*
G01X1309188Y366085D02*
X1307828Y366416D01*
G01X1294605Y376369D02*
X1308216Y367300D01*
G01X1307828Y366416D02*
X1306997Y366969D01*
G01X1294605Y376369D02*
X1308216Y367300D01*
G01X1305124Y368216D02*
X1304001Y368965D01*
G01X1294605Y376369D02*
X1308216Y367300D01*
G01X1302129Y370213D02*
X1301005Y370961D01*
G01X1294605Y376369D02*
X1308216Y367300D01*
G01X1301005Y370961D02*
X1300381Y370837D01*
G01X1294605Y376369D02*
X1308216Y367300D01*
G01X1299133Y372209D02*
X1298009Y372958D01*
G01X1294605Y376369D02*
X1308216Y367300D01*
G01X1296137Y374206D02*
X1293824Y375747D01*
G01X1289764Y389170D02*
X1294605Y376369D01*
G01X1293824Y375747D02*
X1291431Y382075D01*
G01X1288657Y392100D02*
X1289764Y389170D01*
G01D02*
X1294605Y376369D01*
G01X1288657Y392100D02*
X1287443Y395309D01*
G01X1291431Y382075D02*
X1286652Y394706D01*
G01X1349394Y348771D02*
X1341504Y354031D01*
G01X1349023Y347876D02*
X1341133Y353136D01*
G01X1341504Y354031D02*
X1334382Y355456D01*
G01X1341133Y353136D02*
X1334382Y354487D01*
G01Y355456D02*
X1328824Y354345D01*
G01X1334382Y354487D02*
X1328819Y353375D01*
G01X1328824Y354345D02*
X1321823Y355821D01*
G01X1328819Y353375D02*
X1321818Y354851D01*
G01X1321823Y355821D02*
X1315649Y354588D01*
G01X1321818Y354851D02*
X1315644Y353618D01*
G01X1315649Y354588D02*
X1308380Y356121D01*
G01X1315644Y353618D02*
X1308005Y355229D01*
G01X1308380Y356121D02*
X1289194Y368905D01*
G01X1308005Y355229D02*
X1288413Y368283D01*
G01X1289194Y368905D02*
X1282412Y386838D01*
G01X1288413Y368283D02*
X1284195Y379437D01*
G01X1289194Y368905D02*
X1282412Y386838D01*
G01X1281185Y390082D02*
X1282412Y386838D01*
G01X1280397Y389478D02*
X1284195Y379437D01*
G01X1333878Y359494D02*
X1344780Y357313D01*
G01X1344409Y356418D02*
X1333878Y358525D01*
G01X1328384Y358397D02*
X1333878Y359494D01*
G01Y358525D02*
X1328379Y357427D01*
G01X1321499Y359848D02*
X1328384Y358397D01*
G01X1328379Y357427D02*
X1321494Y358878D01*
G01X1315269Y358602D02*
X1321499Y359848D01*
G01X1321494Y358878D02*
X1315264Y357632D01*
G01X1310429Y359624D02*
X1315269Y358602D01*
G01X1315264Y357632D02*
X1310054Y358732D01*
G01X1292233Y371762D02*
X1310429Y359624D01*
G01X1310054Y358732D02*
X1291452Y371141D01*
G01X1288378Y381950D02*
X1292233Y371762D01*
G01X1291452Y371141D02*
X1290105Y374700D01*
G01X1287176Y385127D02*
X1288378Y381950D01*
G01D02*
X1292233Y371762D01*
G01X1287176Y385127D02*
X1285817Y388717D01*
G01X1290105Y374701D02*
X1284927Y388380D01*
G01X1285817Y388717D02*
X1284347Y392603D01*
G01X1284927Y388380D02*
X1283557Y392001D01*
G01X1291431Y382075D02*
X1286652Y394706D01*
G01X1288657Y392100D02*
X1289764Y389170D01*
G01X1293824Y375747D02*
X1291431Y382075D01*
G01D02*
X1286652Y394706D01*
G01X1289764Y389170D02*
X1294605Y376369D01*
G01X1307828Y366416D02*
X1306997Y366969D01*
G01X1305124Y368216D02*
X1304001Y368965D01*
G01X1302129Y370213D02*
X1301005Y370961D01*
G01D02*
X1300381Y370837D01*
G01X1299133Y372209D02*
X1298009Y372958D01*
G01X1296137Y374206D02*
X1293824Y375747D01*
G01X1294605Y376369D02*
X1308216Y367300D01*
G01X1328343Y361420D02*
X1311501Y365522D01*
G01X1309188Y366085D02*
X1307828Y366416D01*
G01X1308216Y367300D02*
X1328363Y362393D01*
G01X1338744Y363500D02*
X1328343Y361420D01*
G01X1328363Y362393D02*
X1338749Y364470D01*
G01X1345017Y362177D02*
X1338744Y363500D01*
G01X1338749Y364470D02*
X1345392Y363069D01*
G01X1291431Y382075D02*
X1286652Y394706D01*
G01X1288657Y392100D02*
X1287443Y395309D01*
G01X1282814Y463426D02*
X1288723D01*
G01X1282420Y464376D02*
X1288329D01*
G01X1288723Y463426D02*
X1298027Y472730D01*
G01X1288329Y464376D02*
X1297633Y473680D01*
G01X1310100Y463800D02*
X1301393D01*
G01D02*
X1293035Y455442D01*
G01X1300999Y464750D02*
X1292085Y455836D01*
G01X1293035Y455442D02*
Y444766D01*
G01X1292085Y455836D02*
Y445077D01*
G01X1293035Y444766D02*
X1286680Y436097D01*
G01X1292085Y445077D02*
X1287564Y438910D01*
G01X1293035Y444766D02*
X1286680Y436097D01*
G01X1287562Y438910D02*
X1286074Y436879D01*
G01X1284893Y459410D02*
X1290926D01*
G01X1284499Y460360D02*
X1290532D01*
G01X1290926Y459410D02*
X1293966Y462450D01*
G01D02*
X1294602D01*
G01X1295557Y464041D02*
X1300411Y468895D01*
G01X1290532Y460360D02*
X1300017Y469845D01*
G01X1282420Y464376D02*
X1288329D01*
G01X1282814Y463426D02*
X1288723D01*
G01X1288329Y464376D02*
X1297633Y473680D01*
G01X1288723Y463426D02*
X1298027Y472730D01*
G01X1310100Y463800D02*
X1301393D01*
G01X1300999Y464750D02*
X1292085Y455836D01*
G01X1301393Y463800D02*
X1293035Y455442D01*
G01X1292085Y455836D02*
Y445077D01*
G01X1293035Y455442D02*
Y444766D01*
G01X1292085Y445077D02*
X1287564Y438910D01*
G01X1287562D02*
X1286074Y436879D01*
G01X1293035Y444766D02*
X1286680Y436097D01*
G01X1284499Y460360D02*
X1290532D01*
G01X1284893Y459410D02*
X1290926D01*
G01X1290532Y460360D02*
X1300017Y469845D01*
G01X1290926Y459410D02*
X1293966Y462450D01*
G01X1290532Y460360D02*
X1300017Y469845D01*
G01X1293966Y462450D02*
X1294602D01*
G01X1290532Y460360D02*
X1300017Y469845D01*
G01X1295557Y464041D02*
X1300411Y468895D01*
G01X1282814Y463426D02*
X1288723D01*
G01X1282420Y464376D02*
X1288329D01*
G01X1288723Y463426D02*
X1298027Y472730D01*
G01X1288329Y464376D02*
X1297633Y473680D01*
G01X1310100Y463800D02*
X1301393D01*
G01D02*
X1293035Y455442D01*
G01X1300999Y464750D02*
X1292085Y455836D01*
G01X1293035Y455442D02*
Y444766D01*
G01X1292085Y455836D02*
Y445077D01*
G01X1293035Y444766D02*
X1286680Y436097D01*
G01X1292085Y445077D02*
X1287564Y438910D01*
G01X1293035Y444766D02*
X1286680Y436097D01*
G01X1287562Y438910D02*
X1286074Y436879D01*
G01X1284893Y459410D02*
X1290926D01*
G01X1284499Y460360D02*
X1290532D01*
G01X1290926Y459410D02*
X1293966Y462450D01*
G01D02*
X1294602D01*
G01X1295557Y464041D02*
X1300411Y468895D01*
G01X1290532Y460360D02*
X1300017Y469845D01*
G01X1282420Y464376D02*
X1288329D01*
G01X1282814Y463426D02*
X1288723D01*
G01X1288329Y464376D02*
X1297633Y473680D01*
G01X1288723Y463426D02*
X1298027Y472730D01*
G01X1310100Y463800D02*
X1301393D01*
G01X1300999Y464750D02*
X1292085Y455836D01*
G01X1301393Y463800D02*
X1293035Y455442D01*
G01X1292085Y455836D02*
Y445077D01*
G01X1293035Y455442D02*
Y444766D01*
G01X1292085Y445077D02*
X1287564Y438910D01*
G01X1287562D02*
X1286074Y436879D01*
G01X1293035Y444766D02*
X1286680Y436097D01*
G01X1284499Y460360D02*
X1290532D01*
G01X1284893Y459410D02*
X1290926D01*
G01X1290532Y460360D02*
X1300017Y469845D01*
G01X1290926Y459410D02*
X1293966Y462450D01*
G01X1290532Y460360D02*
X1300017Y469845D01*
G01X1293966Y462450D02*
X1294602D01*
G01X1290532Y460360D02*
X1300017Y469845D01*
G01X1295557Y464041D02*
X1300411Y468895D01*
G01X1360707Y461418D02*
X1321253D01*
G01X1360313Y460468D02*
X1320859D01*
G01X1321253Y461418D02*
X1318121Y464550D01*
G01X1320859Y460468D02*
X1317727Y463600D01*
G01X1318121Y464550D02*
X1314580D01*
G01X1317727Y463600D02*
X1314480D01*
G01X1360313Y460468D02*
X1320859D01*
G01X1360707Y461418D02*
X1321253D01*
G01X1320859Y460468D02*
X1317727Y463600D01*
G01X1321253Y461418D02*
X1318121Y464550D01*
G01X1317727Y463600D02*
X1314480D01*
G01X1318121Y464550D02*
X1314580D01*
G01X1360707Y461418D02*
X1321253D01*
G01X1360313Y460468D02*
X1320859D01*
G01X1321253Y461418D02*
X1318121Y464550D01*
G01X1320859Y460468D02*
X1317727Y463600D01*
G01X1318121Y464550D02*
X1314580D01*
G01X1317727Y463600D02*
X1314480D01*
G01X1360313Y460468D02*
X1320859D01*
G01X1360707Y461418D02*
X1321253D01*
G01X1320859Y460468D02*
X1317727Y463600D01*
G01X1321253Y461418D02*
X1318121Y464550D01*
G01X1317727Y463600D02*
X1314480D01*
G01X1318121Y464550D02*
X1314580D01*
G01X1298027Y472730D02*
X1304713D01*
G01X1297633Y473680D02*
X1304319D01*
G01X1304713Y472730D02*
X1306604Y474621D01*
G01X1304319Y473680D02*
X1306210Y475571D01*
G01X1306604Y474621D02*
X1327724D01*
G01X1306210Y475571D02*
X1327724D01*
G01X1310180Y464750D02*
X1300999D01*
G01X1300411Y468895D02*
X1315469D01*
G01X1317719D02*
X1319069D01*
G01X1300017Y469845D02*
X1319463D01*
G01X1317719Y468895D02*
X1319069D01*
G01D02*
X1321479Y466485D01*
G01X1319463Y469845D02*
X1321873Y467435D01*
G01X1321479Y466485D02*
X1334929D01*
G01X1321873Y467435D02*
X1334929D01*
G01X1297633Y473680D02*
X1304319D01*
G01X1298027Y472730D02*
X1304713D01*
G01X1304319Y473680D02*
X1306210Y475571D01*
G01X1304713Y472730D02*
X1306604Y474621D01*
G01X1306210Y475571D02*
X1327724D01*
G01X1306604Y474621D02*
X1327724D01*
G01X1310180Y464750D02*
X1300999D01*
G01X1300017Y469845D02*
X1319463D01*
G01X1300411Y468895D02*
X1315469D01*
G01X1300017Y469845D02*
X1319463D01*
G01D02*
X1321873Y467435D01*
G01X1317719Y468895D02*
X1319069D01*
G01X1319463Y469845D02*
X1321873Y467435D01*
G01X1319069Y468895D02*
X1321479Y466485D01*
G01X1321873Y467435D02*
X1334929D01*
G01X1321479Y466485D02*
X1334929D01*
G01X1298027Y472730D02*
X1304713D01*
G01X1297633Y473680D02*
X1304319D01*
G01X1304713Y472730D02*
X1306604Y474621D01*
G01X1304319Y473680D02*
X1306210Y475571D01*
G01X1306604Y474621D02*
X1327724D01*
G01X1306210Y475571D02*
X1327724D01*
G01X1310180Y464750D02*
X1300999D01*
G01X1300411Y468895D02*
X1315469D01*
G01X1317719D02*
X1319069D01*
G01X1300017Y469845D02*
X1319463D01*
G01X1317719Y468895D02*
X1319069D01*
G01D02*
X1321479Y466485D01*
G01X1319463Y469845D02*
X1321873Y467435D01*
G01X1321479Y466485D02*
X1334929D01*
G01X1321873Y467435D02*
X1334929D01*
G01X1297633Y473680D02*
X1304319D01*
G01X1298027Y472730D02*
X1304713D01*
G01X1304319Y473680D02*
X1306210Y475571D01*
G01X1304713Y472730D02*
X1306604Y474621D01*
G01X1306210Y475571D02*
X1327724D01*
G01X1306604Y474621D02*
X1327724D01*
G01X1310180Y464750D02*
X1300999D01*
G01X1300017Y469845D02*
X1319463D01*
G01X1300411Y468895D02*
X1315469D01*
G01X1300017Y469845D02*
X1319463D01*
G01D02*
X1321873Y467435D01*
G01X1317719Y468895D02*
X1319069D01*
G01X1319463Y469845D02*
X1321873Y467435D01*
G01X1319069Y468895D02*
X1321479Y466485D01*
G01X1321873Y467435D02*
X1334929D01*
G01X1321479Y466485D02*
X1334929D01*
G01X1305200Y479400D02*
X1349779D01*
G01X1307363Y480350D02*
X1352186D01*
G01X1305200Y479400D02*
X1349779D01*
G01X1307363Y480350D02*
X1304806D01*
G01X1303950Y478150D02*
X1305200Y479400D01*
G01X1304806Y480350D02*
X1303556Y479100D01*
G01X1298000Y478150D02*
X1303950D01*
G01X1303556Y479100D02*
X1297606D01*
G01X1287121Y467271D02*
X1298000Y478150D01*
G01X1297606Y479100D02*
X1286727Y468221D01*
G01X1281115Y467271D02*
X1287121D01*
G01X1286727Y468221D02*
X1280721D01*
G01X1307363Y480350D02*
X1352186D01*
G01X1286727Y468221D02*
X1280721D01*
G01X1281115Y467271D02*
X1287121D01*
G01X1297606Y479100D02*
X1286727Y468221D01*
G01X1287121Y467271D02*
X1298000Y478150D01*
G01X1303556Y479100D02*
X1297606D01*
G01X1298000Y478150D02*
X1303950D01*
G01X1304806Y480350D02*
X1303556Y479100D01*
G01X1303950Y478150D02*
X1305200Y479400D01*
G01X1307363Y480350D02*
X1352186D01*
G01X1307363D02*
X1304806D01*
G01X1305200Y479400D02*
X1349779D01*
G01X1285068Y472103D02*
X1296065Y483100D01*
G01X1285462Y471153D02*
X1296459Y482150D01*
G01X1296065Y483100D02*
X1301726D01*
G01X1296459Y482150D02*
X1302120D01*
G01X1301726Y483100D02*
X1302926Y484300D01*
G01X1302120Y482150D02*
X1303320Y483350D01*
G01X1302926Y484300D02*
X1353658D01*
G01X1303320Y483350D02*
X1353264D01*
G01X1294206Y501389D02*
X1280883Y494484D01*
G01X1281014Y493481D02*
X1294347Y500392D01*
G01X1299821Y500269D02*
X1294206Y501389D01*
G01X1294347Y500392D02*
X1299466Y499371D01*
G01X1305975Y496451D02*
X1299821Y500269D01*
G01X1299466Y499371D02*
X1305704Y495500D01*
G01X1360337Y496450D02*
X1305976D01*
G01X1305704Y495500D02*
X1359943D01*
G01X1285462Y471153D02*
X1296459Y482150D01*
G01X1285068Y472103D02*
X1296065Y483100D01*
G01X1296459Y482150D02*
X1302120D01*
G01X1296065Y483100D02*
X1301726D01*
G01X1302120Y482150D02*
X1303320Y483350D01*
G01X1301726Y483100D02*
X1302926Y484300D01*
G01X1303320Y483350D02*
X1353264D01*
G01X1302926Y484300D02*
X1353658D01*
G01X1305704Y495500D02*
X1359943D01*
G01X1360337Y496450D02*
X1305976D01*
G01X1299466Y499371D02*
X1305704Y495500D01*
G01X1305975Y496451D02*
X1299821Y500269D01*
G01X1294347Y500392D02*
X1299466Y499371D01*
G01X1299821Y500269D02*
X1294206Y501389D01*
G01X1281014Y493481D02*
X1294347Y500392D01*
G01X1294206Y501389D02*
X1280883Y494484D01*
G01X1339856Y467027D02*
X1365423D01*
G01X1339856Y466077D02*
X1365029D01*
G01X1346238Y469950D02*
X1341707Y474481D01*
G01X1332340Y475431D02*
X1342101D01*
G01X1341707Y474481D02*
X1332588D01*
G01X1305200Y479400D02*
X1349779D01*
G01X1307363Y480350D02*
X1352186D01*
G01X1305200Y479400D02*
X1349779D01*
G01X1307363Y480350D02*
X1304806D01*
G01X1303950Y478150D02*
X1305200Y479400D01*
G01X1304806Y480350D02*
X1303556Y479100D01*
G01X1298000Y478150D02*
X1303950D01*
G01X1303556Y479100D02*
X1297606D01*
G01X1287121Y467271D02*
X1298000Y478150D01*
G01X1297606Y479100D02*
X1286727Y468221D01*
G01X1281115Y467271D02*
X1287121D01*
G01X1286727Y468221D02*
X1280721D01*
G01X1355028Y488613D02*
X1291369D01*
G01X1354634Y487663D02*
X1291763D01*
G01X1291369Y488613D02*
X1285282Y482526D01*
G01X1291763Y487663D02*
X1286232Y482132D01*
G01X1285282Y482526D02*
Y478558D01*
G01X1286232Y482132D02*
Y478164D01*
G01X1285282Y478558D02*
X1283674Y476950D01*
G01X1286232Y478164D02*
X1284068Y476000D01*
G01X1283674Y476950D02*
X1281664D01*
G01X1284068Y476000D02*
X1281700D01*
G01X1358467Y492569D02*
X1310700D01*
G01X1305074D02*
X1310700D01*
G01X1358467D02*
X1310700D01*
G01X1351800Y491619D02*
X1304842D01*
G01X1297648Y496412D02*
X1305074Y492569D01*
G01X1304842Y491619D02*
X1297333Y495505D01*
G01X1294249Y497072D02*
X1297648Y496412D01*
G01X1297333Y495505D02*
X1294421Y496070D01*
G01X1287943Y493364D02*
X1294249Y497072D01*
G01X1294421Y496070D02*
X1288643Y492672D01*
G01X1284373Y487127D02*
X1287943Y493364D01*
G01X1288643Y492672D02*
X1285108Y486496D01*
G01X1281525Y485475D02*
X1282294D01*
G01D02*
X1284373Y487127D01*
G01X1285108Y486496D02*
X1282626Y484525D01*
G01X1281525Y485475D02*
X1282294D01*
G01X1282626Y484525D02*
X1281701D01*
G01X1341707Y474481D02*
X1332588D01*
G01X1332340Y475431D02*
X1342101D01*
G01X1346238Y469950D02*
X1341707Y474481D01*
G01X1354634Y487663D02*
X1291763D01*
G01X1355028Y488613D02*
X1291369D01*
G01X1291763Y487663D02*
X1286232Y482132D01*
G01X1291369Y488613D02*
X1285282Y482526D01*
G01X1286232Y482132D02*
Y478164D01*
G01X1285282Y482526D02*
Y478558D01*
G01X1286232Y478164D02*
X1284068Y476000D01*
G01X1285282Y478558D02*
X1283674Y476950D01*
G01X1284068Y476000D02*
X1281700D01*
G01X1283674Y476950D02*
X1281664D01*
G01X1285108Y486496D02*
X1282626Y484525D01*
G01D02*
X1281701D01*
G01X1281525Y485475D02*
X1282294D01*
G01X1285108Y486496D02*
X1282626Y484525D01*
G01X1282294Y485475D02*
X1284373Y487127D01*
G01X1288643Y492672D02*
X1285108Y486496D01*
G01X1284373Y487127D02*
X1287943Y493364D01*
G01X1294421Y496070D02*
X1288643Y492672D01*
G01X1287943Y493364D02*
X1294249Y497072D01*
G01X1297333Y495505D02*
X1294421Y496070D01*
G01X1294249Y497072D02*
X1297648Y496412D01*
G01X1304842Y491619D02*
X1297333Y495505D01*
G01X1297648Y496412D02*
X1305074Y492569D01*
G01X1351800Y491619D02*
X1304842D01*
G01X1305074Y492569D02*
X1310700D01*
G01X1351800Y491619D02*
X1304842D01*
G01X1358467Y492569D02*
X1310700D01*
G01X1285108Y486496D02*
X1282626Y484525D01*
G01D02*
X1281701D01*
G01X1281525Y485475D02*
X1282294D01*
G01X1285108Y486496D02*
X1282626Y484525D01*
G01X1282294Y485475D02*
X1284373Y487127D01*
G01X1288643Y492672D02*
X1285108Y486496D01*
G01X1284373Y487127D02*
X1287943Y493364D01*
G01X1294421Y496070D02*
X1288643Y492672D01*
G01X1287943Y493364D02*
X1294249Y497072D01*
G01X1297333Y495505D02*
X1294421Y496070D01*
G01X1294249Y497072D02*
X1297648Y496412D01*
G01X1304842Y491619D02*
X1297333Y495505D01*
G01X1297648Y496412D02*
X1305074Y492569D01*
G01X1351800Y491619D02*
X1304842D01*
G01X1305074Y492569D02*
X1310700D01*
G01X1351800Y491619D02*
X1304842D01*
G01X1358467Y492569D02*
X1310700D01*
G01X1339856Y466077D02*
X1365029D01*
G01X1339856Y467027D02*
X1365423D01*
G01X1355028Y488613D02*
X1291369D01*
G01X1354634Y487663D02*
X1291763D01*
G01X1291369Y488613D02*
X1285282Y482526D01*
G01X1291763Y487663D02*
X1286232Y482132D01*
G01X1285282Y482526D02*
Y478558D01*
G01X1286232Y482132D02*
Y478164D01*
G01X1285282Y478558D02*
X1283674Y476950D01*
G01X1286232Y478164D02*
X1284068Y476000D01*
G01X1283674Y476950D02*
X1281664D01*
G01X1284068Y476000D02*
X1281700D01*
G01X1358467Y492569D02*
X1310700D01*
G01X1305074D02*
X1310700D01*
G01X1358467D02*
X1310700D01*
G01X1351800Y491619D02*
X1304842D01*
G01X1297648Y496412D02*
X1305074Y492569D01*
G01X1304842Y491619D02*
X1297333Y495505D01*
G01X1294249Y497072D02*
X1297648Y496412D01*
G01X1297333Y495505D02*
X1294421Y496070D01*
G01X1287943Y493364D02*
X1294249Y497072D01*
G01X1294421Y496070D02*
X1288643Y492672D01*
G01X1284373Y487127D02*
X1287943Y493364D01*
G01X1288643Y492672D02*
X1285108Y486496D01*
G01X1281525Y485475D02*
X1282294D01*
G01D02*
X1284373Y487127D01*
G01X1285108Y486496D02*
X1282626Y484525D01*
G01X1281525Y485475D02*
X1282294D01*
G01X1282626Y484525D02*
X1281701D01*
G01X1294206Y501389D02*
X1280883Y494484D01*
G01X1281014Y493481D02*
X1294347Y500392D01*
G01X1299821Y500269D02*
X1294206Y501389D01*
G01X1294347Y500392D02*
X1299466Y499371D01*
G01X1305975Y496451D02*
X1299821Y500269D01*
G01X1299466Y499371D02*
X1305704Y495500D01*
G01X1360337Y496450D02*
X1305976D01*
G01X1305704Y495500D02*
X1359943D01*
G01X1307363Y480350D02*
X1352186D01*
G01X1286727Y468221D02*
X1280721D01*
G01X1281115Y467271D02*
X1287121D01*
G01X1297606Y479100D02*
X1286727Y468221D01*
G01X1287121Y467271D02*
X1298000Y478150D01*
G01X1303556Y479100D02*
X1297606D01*
G01X1298000Y478150D02*
X1303950D01*
G01X1304806Y480350D02*
X1303556Y479100D01*
G01X1303950Y478150D02*
X1305200Y479400D01*
G01X1307363Y480350D02*
X1352186D01*
G01X1307363D02*
X1304806D01*
G01X1305200Y479400D02*
X1349779D01*
G01X1305704Y495500D02*
X1359943D01*
G01X1360337Y496450D02*
X1305976D01*
G01X1299466Y499371D02*
X1305704Y495500D01*
G01X1305975Y496451D02*
X1299821Y500269D01*
G01X1294347Y500392D02*
X1299466Y499371D01*
G01X1299821Y500269D02*
X1294206Y501389D01*
G01X1281014Y493481D02*
X1294347Y500392D01*
G01X1294206Y501389D02*
X1280883Y494484D01*
G01X1339856Y467027D02*
X1365423D01*
G01X1339856Y466077D02*
X1365029D01*
G01X1339856D02*
X1365029D01*
G01X1339856Y467027D02*
X1365423D01*
G01X1346238Y469950D02*
X1341707Y474481D01*
G01X1332340Y475431D02*
X1342101D01*
G01X1341707Y474481D02*
X1332588D01*
G01X1285068Y472103D02*
X1296065Y483100D01*
G01X1285462Y471153D02*
X1296459Y482150D01*
G01X1296065Y483100D02*
X1301726D01*
G01X1296459Y482150D02*
X1302120D01*
G01X1301726Y483100D02*
X1302926Y484300D01*
G01X1302120Y482150D02*
X1303320Y483350D01*
G01X1302926Y484300D02*
X1353658D01*
G01X1303320Y483350D02*
X1353264D01*
G01X1341707Y474481D02*
X1332588D01*
G01X1332340Y475431D02*
X1342101D01*
G01X1346238Y469950D02*
X1341707Y474481D01*
G01X1285462Y471153D02*
X1296459Y482150D01*
G01X1285068Y472103D02*
X1296065Y483100D01*
G01X1296459Y482150D02*
X1302120D01*
G01X1296065Y483100D02*
X1301726D01*
G01X1302120Y482150D02*
X1303320Y483350D01*
G01X1301726Y483100D02*
X1302926Y484300D01*
G01X1303320Y483350D02*
X1353264D01*
G01X1302926Y484300D02*
X1353658D01*
G01X1354634Y487663D02*
X1291763D01*
G01X1355028Y488613D02*
X1291369D01*
G01X1291763Y487663D02*
X1286232Y482132D01*
G01X1291369Y488613D02*
X1285282Y482526D01*
G01X1286232Y482132D02*
Y478164D01*
G01X1285282Y482526D02*
Y478558D01*
G01X1286232Y478164D02*
X1284068Y476000D01*
G01X1285282Y478558D02*
X1283674Y476950D01*
G01X1284068Y476000D02*
X1281700D01*
G01X1283674Y476950D02*
X1281664D01*
G01X1411690Y120900D02*
X1403664Y147975D01*
G01D02*
X1406408Y159341D01*
G01X1411690Y120900D02*
X1403664Y147975D01*
G01D02*
X1406408Y159341D01*
G01X1411690Y120900D02*
X1403664Y147975D01*
G01D02*
X1406408Y159341D01*
G01X1411690Y120900D02*
X1403664Y147975D01*
G01D02*
X1406408Y159341D01*
G01X1405690Y167289D02*
X1389382Y178333D01*
G01X1404840Y166717D02*
X1389007Y177438D01*
G01X1389382Y178333D02*
X1376874Y180835D01*
G01X1389007Y177438D02*
X1376874Y179866D01*
G01Y180835D02*
X1368900Y179240D01*
G01X1376874Y179866D02*
X1368900Y178271D01*
G01Y179240D02*
X1352850Y182450D01*
G01X1368900Y178271D02*
X1352850Y181481D01*
G01Y182450D02*
X1343700Y180620D01*
G01X1352850Y181481D02*
X1343700Y179651D01*
G01X1395794Y196220D02*
X1422467Y178190D01*
G01X1423321Y178761D02*
X1396169Y197114D01*
G01X1377723Y199836D02*
X1395794Y196220D01*
G01X1396169Y197114D02*
X1377723Y200805D01*
G01X1368600Y198011D02*
X1377723Y199836D01*
G01Y200805D02*
X1368600Y198980D01*
G01X1352650Y201201D02*
X1368600Y198011D01*
G01Y198980D02*
X1352650Y202170D01*
G01X1343550Y199381D02*
X1352650Y201201D01*
G01Y202170D02*
X1343550Y200350D01*
G01X1352500Y198220D02*
X1343500Y196420D01*
G01Y195451D02*
X1352500Y197251D01*
G01X1368450Y195030D02*
X1352500Y198220D01*
G01Y197251D02*
X1368450Y194061D01*
G01X1377821Y196904D02*
X1368450Y195030D01*
G01Y194061D02*
X1377821Y195935D01*
G01X1394669Y193535D02*
X1377821Y196904D01*
G01Y195935D02*
X1394295Y192640D01*
G01X1419873Y176496D02*
X1394669Y193535D01*
G01X1394295Y192640D02*
X1419019Y175925D01*
G01X1343550Y191561D02*
X1352450Y193341D01*
G01X1343550Y192530D02*
X1352450Y194310D01*
G01Y193341D02*
X1368500Y190131D01*
G01X1352450Y194310D02*
X1368500Y191100D01*
G01Y190131D02*
X1377848Y192001D01*
G01X1368500Y191100D02*
X1377848Y192970D01*
G01Y192001D02*
X1392841Y189003D01*
G01X1377848Y192970D02*
X1393215Y189898D01*
G01X1392841Y189003D02*
X1415464Y173711D01*
G01X1393215Y189898D02*
X1416318Y174281D01*
G01X1411935Y171456D02*
X1390991Y185421D01*
G01X1412788Y172030D02*
X1391362Y186316D01*
G01X1390991Y185421D02*
X1377824Y188056D01*
G01X1391362Y186316D02*
X1377824Y189025D01*
G01Y188056D02*
X1368600Y186211D01*
G01X1377824Y189025D02*
X1368600Y187180D01*
G01Y186211D02*
X1352750Y189381D01*
G01X1368600Y187180D02*
X1352750Y190350D01*
G01Y189381D02*
X1343649Y187561D01*
G01X1352750Y190350D02*
X1343649Y188530D01*
G01X1353100Y186400D02*
X1343750Y184530D01*
G01Y183561D02*
X1353100Y185431D01*
G01X1368929Y183234D02*
X1353100Y186400D01*
G01Y185431D02*
X1368929Y182265D01*
G01X1377575Y184963D02*
X1368929Y183234D01*
G01Y182265D02*
X1377575Y183994D01*
G01X1390110Y182454D02*
X1377575Y184963D01*
G01Y183994D02*
X1389735Y181559D01*
G01X1409234Y169505D02*
X1390110Y182454D01*
G01X1389735Y181559D02*
X1408380Y168935D01*
G01X1404840Y166717D02*
X1389007Y177438D01*
G01X1405690Y167289D02*
X1389382Y178333D01*
G01X1389007Y177438D02*
X1376874Y179866D01*
G01X1389382Y178333D02*
X1376874Y180835D01*
G01Y179866D02*
X1368900Y178271D01*
G01X1376874Y180835D02*
X1368900Y179240D01*
G01Y178271D02*
X1352850Y181481D01*
G01X1368900Y179240D02*
X1352850Y182450D01*
G01Y181481D02*
X1343700Y179651D01*
G01X1352850Y182450D02*
X1343700Y180620D01*
G01X1427664Y200994D02*
X1400180Y219606D01*
G01X1387357Y215964D02*
X1409789Y208240D01*
G01X1410218Y209098D02*
X1387781Y216824D01*
G01X1384809Y217649D02*
X1387357Y215964D01*
G01X1387781Y216824D02*
X1385180Y218544D01*
G01X1369824Y220762D02*
X1384808Y217650D01*
G01X1347587Y216324D02*
X1369822Y220762D01*
G01X1369828Y221732D02*
X1347627Y217301D01*
G01X1394969Y206168D02*
X1394968D01*
G01D02*
X1429825Y182563D01*
G01X1430679Y183133D02*
X1395345Y207061D01*
G01X1371373Y211018D02*
X1394969Y206168D01*
G01D02*
X1394968D01*
G01X1357251Y213921D02*
X1371373Y211018D01*
G01X1395345Y207061D02*
X1360253Y214274D01*
G01X1346850Y211841D02*
X1357251Y213921D01*
G01X1346850Y212810D02*
X1357254Y214891D01*
G01X1357251Y213921D02*
X1371373Y211018D01*
G01X1357254Y214891D02*
X1360253Y214274D01*
G01X1352750Y205141D02*
X1343650Y203321D01*
G01Y204290D02*
X1352750Y206110D01*
G01X1368435Y202004D02*
X1352750Y205141D01*
G01Y206110D02*
X1368435Y202973D01*
G01X1377466Y203810D02*
X1368435Y202004D01*
G01Y202973D02*
X1377466Y204779D01*
G01X1397470Y199810D02*
X1377466Y203810D01*
G01Y204779D02*
X1397844Y200705D01*
G01X1426399Y180277D02*
X1397470Y199810D01*
G01X1397844Y200705D02*
X1427253Y180847D01*
G01X1352650Y202170D02*
X1343550Y200350D01*
G01Y199381D02*
X1352650Y201201D01*
G01X1368600Y198980D02*
X1352650Y202170D01*
G01Y201201D02*
X1368600Y198011D01*
G01X1377723Y200805D02*
X1368600Y198980D01*
G01Y198011D02*
X1377723Y199836D01*
G01X1396169Y197114D02*
X1377723Y200805D01*
G01Y199836D02*
X1395794Y196220D01*
G01X1423321Y178761D02*
X1396169Y197114D01*
G01X1395794Y196220D02*
X1422467Y178190D01*
G01X1394295Y192640D02*
X1419019Y175925D01*
G01X1419873Y176496D02*
X1394669Y193535D01*
G01X1377821Y195935D02*
X1394295Y192640D01*
G01X1394669Y193535D02*
X1377821Y196904D01*
G01X1368450Y194061D02*
X1377821Y195935D01*
G01Y196904D02*
X1368450Y195030D01*
G01X1352500Y197251D02*
X1368450Y194061D01*
G01Y195030D02*
X1352500Y198220D01*
G01X1343500Y195451D02*
X1352500Y197251D01*
G01Y198220D02*
X1343500Y196420D01*
G01X1343550Y192530D02*
X1352450Y194310D01*
G01X1343550Y191561D02*
X1352450Y193341D01*
G01Y194310D02*
X1368500Y191100D01*
G01X1352450Y193341D02*
X1368500Y190131D01*
G01Y191100D02*
X1377848Y192970D01*
G01X1368500Y190131D02*
X1377848Y192001D01*
G01Y192970D02*
X1393215Y189898D01*
G01X1377848Y192001D02*
X1392841Y189003D01*
G01X1393215Y189898D02*
X1416318Y174281D01*
G01X1392841Y189003D02*
X1415464Y173711D01*
G01X1412788Y172030D02*
X1391362Y186316D01*
G01X1411935Y171456D02*
X1390991Y185421D01*
G01X1391362Y186316D02*
X1377824Y189025D01*
G01X1390991Y185421D02*
X1377824Y188056D01*
G01Y189025D02*
X1368600Y187180D01*
G01X1377824Y188056D02*
X1368600Y186211D01*
G01Y187180D02*
X1352750Y190350D01*
G01X1368600Y186211D02*
X1352750Y189381D01*
G01Y190350D02*
X1343649Y188530D01*
G01X1352750Y189381D02*
X1343649Y187561D01*
G01X1389735Y181559D02*
X1408380Y168935D01*
G01X1409234Y169505D02*
X1390110Y182454D01*
G01X1377575Y183994D02*
X1389735Y181559D01*
G01X1390110Y182454D02*
X1377575Y184963D01*
G01X1368929Y182265D02*
X1377575Y183994D01*
G01Y184963D02*
X1368929Y183234D01*
G01X1353100Y185431D02*
X1368929Y182265D01*
G01Y183234D02*
X1353100Y186400D01*
G01X1343750Y183561D02*
X1353100Y185431D01*
G01Y186400D02*
X1343750Y184530D01*
G01X1427664Y200994D02*
X1400180Y219606D01*
G01X1369828Y221732D02*
X1347627Y217301D01*
G01X1347587Y216324D02*
X1369822Y220762D01*
G01X1369824D02*
X1384808Y217650D01*
G01X1387781Y216824D02*
X1385180Y218544D01*
G01X1384809Y217649D02*
X1387357Y215964D01*
G01X1410218Y209098D02*
X1387781Y216824D01*
G01X1387357Y215964D02*
X1409789Y208240D01*
G01X1395345Y207061D02*
X1360253Y214274D01*
G01X1371373Y211018D02*
X1394969Y206168D01*
G01X1430679Y183133D02*
X1395345Y207061D01*
G01D02*
X1360253Y214274D01*
G01X1394969Y206168D02*
X1394968D01*
G01X1430679Y183133D02*
X1395345Y207061D01*
G01X1394968Y206168D02*
X1429825Y182563D01*
G01X1346850Y212810D02*
X1357254Y214891D01*
G01X1346850Y211841D02*
X1357251Y213921D01*
G01X1395345Y207061D02*
X1360253Y214274D01*
G01X1357254Y214891D02*
X1360253Y214274D01*
G01X1357251Y213921D02*
X1371373Y211018D01*
G01X1397844Y200705D02*
X1427253Y180847D01*
G01X1426399Y180277D02*
X1397470Y199810D01*
G01X1377466Y204779D02*
X1397844Y200705D01*
G01X1397470Y199810D02*
X1377466Y203810D01*
G01X1368435Y202973D02*
X1377466Y204779D01*
G01Y203810D02*
X1368435Y202004D01*
G01X1352750Y206110D02*
X1368435Y202973D01*
G01Y202004D02*
X1352750Y205141D01*
G01X1343650Y204290D02*
X1352750Y206110D01*
G01Y205141D02*
X1343650Y203321D01*
G01X1404840Y166717D02*
X1389007Y177438D01*
G01X1405690Y167289D02*
X1389382Y178333D01*
G01X1389007Y177438D02*
X1376874Y179866D01*
G01X1389382Y178333D02*
X1376874Y180835D01*
G01Y179866D02*
X1368900Y178271D01*
G01X1376874Y180835D02*
X1368900Y179240D01*
G01Y178271D02*
X1352850Y181481D01*
G01X1368900Y179240D02*
X1352850Y182450D01*
G01Y181481D02*
X1343700Y179651D01*
G01X1352850Y182450D02*
X1343700Y180620D01*
G01X1343550Y191561D02*
X1352450Y193341D01*
G01X1343550Y192530D02*
X1352450Y194310D01*
G01Y193341D02*
X1368500Y190131D01*
G01X1352450Y194310D02*
X1368500Y191100D01*
G01Y190131D02*
X1377848Y192001D01*
G01X1368500Y191100D02*
X1377848Y192970D01*
G01Y192001D02*
X1392841Y189003D01*
G01X1377848Y192970D02*
X1393215Y189898D01*
G01X1392841Y189003D02*
X1415464Y173711D01*
G01X1393215Y189898D02*
X1416318Y174281D01*
G01X1427664Y200994D02*
X1400180Y219606D01*
G01X1387357Y215964D02*
X1409789Y208240D01*
G01X1410218Y209098D02*
X1387781Y216824D01*
G01X1384809Y217649D02*
X1387357Y215964D01*
G01X1387781Y216824D02*
X1385180Y218544D01*
G01X1369824Y220762D02*
X1384808Y217650D01*
G01X1347587Y216324D02*
X1369822Y220762D01*
G01X1369828Y221732D02*
X1347627Y217301D01*
G01X1352750Y205141D02*
X1343650Y203321D01*
G01Y204290D02*
X1352750Y206110D01*
G01X1368435Y202004D02*
X1352750Y205141D01*
G01Y206110D02*
X1368435Y202973D01*
G01X1377466Y203810D02*
X1368435Y202004D01*
G01Y202973D02*
X1377466Y204779D01*
G01X1397470Y199810D02*
X1377466Y203810D01*
G01Y204779D02*
X1397844Y200705D01*
G01X1426399Y180277D02*
X1397470Y199810D01*
G01X1397844Y200705D02*
X1427253Y180847D01*
G01X1394295Y192640D02*
X1419019Y175925D01*
G01X1419873Y176496D02*
X1394669Y193535D01*
G01X1377821Y195935D02*
X1394295Y192640D01*
G01X1394669Y193535D02*
X1377821Y196904D01*
G01X1368450Y194061D02*
X1377821Y195935D01*
G01Y196904D02*
X1368450Y195030D01*
G01X1352500Y197251D02*
X1368450Y194061D01*
G01Y195030D02*
X1352500Y198220D01*
G01X1343500Y195451D02*
X1352500Y197251D01*
G01Y198220D02*
X1343500Y196420D01*
G01X1343550Y192530D02*
X1352450Y194310D01*
G01X1343550Y191561D02*
X1352450Y193341D01*
G01Y194310D02*
X1368500Y191100D01*
G01X1352450Y193341D02*
X1368500Y190131D01*
G01Y191100D02*
X1377848Y192970D01*
G01X1368500Y190131D02*
X1377848Y192001D01*
G01Y192970D02*
X1393215Y189898D01*
G01X1377848Y192001D02*
X1392841Y189003D01*
G01X1393215Y189898D02*
X1416318Y174281D01*
G01X1392841Y189003D02*
X1415464Y173711D01*
G01X1427664Y200994D02*
X1400180Y219606D01*
G01X1369828Y221732D02*
X1347627Y217301D01*
G01X1347587Y216324D02*
X1369822Y220762D01*
G01X1369824D02*
X1384808Y217650D01*
G01X1387781Y216824D02*
X1385180Y218544D01*
G01X1384809Y217649D02*
X1387357Y215964D01*
G01X1410218Y209098D02*
X1387781Y216824D01*
G01X1387357Y215964D02*
X1409789Y208240D01*
G01X1397844Y200705D02*
X1427253Y180847D01*
G01X1426399Y180277D02*
X1397470Y199810D01*
G01X1377466Y204779D02*
X1397844Y200705D01*
G01X1397470Y199810D02*
X1377466Y203810D01*
G01X1368435Y202973D02*
X1377466Y204779D01*
G01Y203810D02*
X1368435Y202004D01*
G01X1352750Y206110D02*
X1368435Y202973D01*
G01Y202004D02*
X1352750Y205141D01*
G01X1343650Y204290D02*
X1352750Y206110D01*
G01Y205141D02*
X1343650Y203321D01*
G01X1395794Y196220D02*
X1422467Y178190D01*
G01X1423321Y178761D02*
X1396169Y197114D01*
G01X1377723Y199836D02*
X1395794Y196220D01*
G01X1396169Y197114D02*
X1377723Y200805D01*
G01X1368600Y198011D02*
X1377723Y199836D01*
G01Y200805D02*
X1368600Y198980D01*
G01X1352650Y201201D02*
X1368600Y198011D01*
G01Y198980D02*
X1352650Y202170D01*
G01X1343550Y199381D02*
X1352650Y201201D01*
G01Y202170D02*
X1343550Y200350D01*
G01X1352500Y198220D02*
X1343500Y196420D01*
G01Y195451D02*
X1352500Y197251D01*
G01X1368450Y195030D02*
X1352500Y198220D01*
G01Y197251D02*
X1368450Y194061D01*
G01X1377821Y196904D02*
X1368450Y195030D01*
G01Y194061D02*
X1377821Y195935D01*
G01X1394669Y193535D02*
X1377821Y196904D01*
G01Y195935D02*
X1394295Y192640D01*
G01X1419873Y176496D02*
X1394669Y193535D01*
G01X1394295Y192640D02*
X1419019Y175925D01*
G01X1411935Y171456D02*
X1390991Y185421D01*
G01X1412788Y172030D02*
X1391362Y186316D01*
G01X1390991Y185421D02*
X1377824Y188056D01*
G01X1391362Y186316D02*
X1377824Y189025D01*
G01Y188056D02*
X1368600Y186211D01*
G01X1377824Y189025D02*
X1368600Y187180D01*
G01Y186211D02*
X1352750Y189381D01*
G01X1368600Y187180D02*
X1352750Y190350D01*
G01Y189381D02*
X1343649Y187561D01*
G01X1352750Y190350D02*
X1343649Y188530D01*
G01X1353100Y186400D02*
X1343750Y184530D01*
G01Y183561D02*
X1353100Y185431D01*
G01X1368929Y183234D02*
X1353100Y186400D01*
G01Y185431D02*
X1368929Y182265D01*
G01X1377575Y184963D02*
X1368929Y183234D01*
G01Y182265D02*
X1377575Y183994D01*
G01X1390110Y182454D02*
X1377575Y184963D01*
G01Y183994D02*
X1389735Y181559D01*
G01X1409234Y169505D02*
X1390110Y182454D01*
G01X1389735Y181559D02*
X1408380Y168935D01*
G01X1352650Y202170D02*
X1343550Y200350D01*
G01Y199381D02*
X1352650Y201201D01*
G01X1368600Y198980D02*
X1352650Y202170D01*
G01Y201201D02*
X1368600Y198011D01*
G01X1377723Y200805D02*
X1368600Y198980D01*
G01Y198011D02*
X1377723Y199836D01*
G01X1396169Y197114D02*
X1377723Y200805D01*
G01Y199836D02*
X1395794Y196220D01*
G01X1423321Y178761D02*
X1396169Y197114D01*
G01X1395794Y196220D02*
X1422467Y178190D01*
G01X1412788Y172030D02*
X1391362Y186316D01*
G01X1411935Y171456D02*
X1390991Y185421D01*
G01X1391362Y186316D02*
X1377824Y189025D01*
G01X1390991Y185421D02*
X1377824Y188056D01*
G01Y189025D02*
X1368600Y187180D01*
G01X1377824Y188056D02*
X1368600Y186211D01*
G01Y187180D02*
X1352750Y190350D01*
G01X1368600Y186211D02*
X1352750Y189381D01*
G01Y190350D02*
X1343649Y188530D01*
G01X1352750Y189381D02*
X1343649Y187561D01*
G01X1389735Y181559D02*
X1408380Y168935D01*
G01X1409234Y169505D02*
X1390110Y182454D01*
G01X1377575Y183994D02*
X1389735Y181559D01*
G01X1390110Y182454D02*
X1377575Y184963D01*
G01X1368929Y182265D02*
X1377575Y183994D01*
G01Y184963D02*
X1368929Y183234D01*
G01X1353100Y185431D02*
X1368929Y182265D01*
G01Y183234D02*
X1353100Y186400D01*
G01X1343750Y183561D02*
X1353100Y185431D01*
G01Y186400D02*
X1343750Y184530D01*
G01X1405690Y167289D02*
X1389382Y178333D01*
G01X1404840Y166717D02*
X1389007Y177438D01*
G01X1389382Y178333D02*
X1376874Y180835D01*
G01X1389007Y177438D02*
X1376874Y179866D01*
G01Y180835D02*
X1368900Y179240D01*
G01X1376874Y179866D02*
X1368900Y178271D01*
G01Y179240D02*
X1352850Y182450D01*
G01X1368900Y178271D02*
X1352850Y181481D01*
G01Y182450D02*
X1343700Y180620D01*
G01X1352850Y181481D02*
X1343700Y179651D01*
G01X1394969Y206168D02*
X1394968D01*
G01D02*
X1429825Y182563D01*
G01X1430679Y183133D02*
X1395345Y207061D01*
G01X1371373Y211018D02*
X1394969Y206168D01*
G01D02*
X1394968D01*
G01X1357251Y213921D02*
X1371373Y211018D01*
G01X1395345Y207061D02*
X1360253Y214274D01*
G01X1346850Y211841D02*
X1357251Y213921D01*
G01X1346850Y212810D02*
X1357254Y214891D01*
G01X1357251Y213921D02*
X1371373Y211018D01*
G01X1357254Y214891D02*
X1360253Y214274D01*
G01X1395345Y207061D02*
X1360253Y214274D01*
G01X1371373Y211018D02*
X1394969Y206168D01*
G01X1430679Y183133D02*
X1395345Y207061D01*
G01D02*
X1360253Y214274D01*
G01X1394969Y206168D02*
X1394968D01*
G01X1430679Y183133D02*
X1395345Y207061D01*
G01X1394968Y206168D02*
X1429825Y182563D01*
G01X1346850Y212810D02*
X1357254Y214891D01*
G01X1346850Y211841D02*
X1357251Y213921D01*
G01X1395345Y207061D02*
X1360253Y214274D01*
G01X1357254Y214891D02*
X1360253Y214274D01*
G01X1357251Y213921D02*
X1371373Y211018D01*
G01X1407903Y241102D02*
X1403201Y244215D01*
G01X1408589Y241788D02*
X1403570Y245111D01*
G01X1403201Y244215D02*
X1390710Y246691D01*
G01X1403570Y245111D02*
X1390681Y247666D01*
G01X1390710Y246691D02*
X1382795Y244629D01*
G01X1390681Y247666D02*
X1382772Y245606D01*
G01X1382795Y244629D02*
X1376074Y246057D01*
G01X1382772Y245606D02*
X1376074Y247029D01*
G01Y246057D02*
X1371763Y245141D01*
G01X1376074Y247029D02*
X1371763Y246113D01*
G01Y245141D02*
X1366876Y246181D01*
G01X1371763Y246113D02*
X1366876Y247153D01*
G01Y246181D02*
X1362246Y245197D01*
G01X1366876Y247153D02*
X1362246Y246169D01*
G01Y245197D02*
X1357355Y246237D01*
G01X1362246Y246169D02*
X1357355Y247209D01*
G01Y246237D02*
X1354190Y245565D01*
G01X1357355Y247209D02*
X1354185Y246536D01*
G01X1399990Y240801D02*
X1405770Y236973D01*
G01X1406441Y237669D02*
X1400358Y241697D01*
G01X1390734Y242616D02*
X1399990Y240801D01*
G01X1400358Y241697D02*
X1390704Y243590D01*
G01X1383161Y240643D02*
X1390734Y242616D01*
G01X1390704Y243590D02*
X1383138Y241620D01*
G01X1376379Y242084D02*
X1383161Y240643D01*
G01X1383138Y241620D02*
X1376379Y243056D01*
G01X1371762Y241103D02*
X1376379Y242084D01*
G01Y243056D02*
X1371762Y242075D01*
G01X1366824Y242154D02*
X1371762Y241103D01*
G01Y242075D02*
X1366824Y243126D01*
G01X1362195Y241170D02*
X1366824Y242154D01*
G01Y243126D02*
X1362195Y242142D01*
G01X1357354Y242199D02*
X1362195Y241170D01*
G01Y242142D02*
X1357354Y243171D01*
G01X1354238Y241538D02*
X1357354Y242199D01*
G01Y243171D02*
X1354233Y242509D01*
G01X1431333Y199658D02*
X1400559Y220497D01*
G01X1400180Y219606D02*
X1373207Y225343D01*
G01X1400559Y220497D02*
X1373213Y226313D01*
G01X1373207Y225343D02*
X1347973Y220302D01*
G01X1373213Y226313D02*
X1348013Y221279D01*
G01X1385180Y218544D02*
X1369828Y221732D01*
G01X1408589Y241788D02*
X1403570Y245111D01*
G01X1407903Y241102D02*
X1403201Y244215D01*
G01X1403570Y245111D02*
X1390681Y247666D01*
G01X1403201Y244215D02*
X1390710Y246691D01*
G01X1390681Y247666D02*
X1382772Y245606D01*
G01X1390710Y246691D02*
X1382795Y244629D01*
G01X1382772Y245606D02*
X1376074Y247029D01*
G01X1382795Y244629D02*
X1376074Y246057D01*
G01Y247029D02*
X1371763Y246113D01*
G01X1376074Y246057D02*
X1371763Y245141D01*
G01Y246113D02*
X1366876Y247153D01*
G01X1371763Y245141D02*
X1366876Y246181D01*
G01Y247153D02*
X1362246Y246169D01*
G01X1366876Y246181D02*
X1362246Y245197D01*
G01Y246169D02*
X1357355Y247209D01*
G01X1362246Y245197D02*
X1357355Y246237D01*
G01Y247209D02*
X1354185Y246536D01*
G01X1357355Y246237D02*
X1354190Y245565D01*
G01X1357354Y243171D02*
X1354233Y242509D01*
G01X1354238Y241538D02*
X1357354Y242199D01*
G01X1362195Y242142D02*
X1357354Y243171D01*
G01Y242199D02*
X1362195Y241170D01*
G01X1366824Y243126D02*
X1362195Y242142D01*
G01Y241170D02*
X1366824Y242154D01*
G01X1371762Y242075D02*
X1366824Y243126D01*
G01Y242154D02*
X1371762Y241103D01*
G01X1376379Y243056D02*
X1371762Y242075D01*
G01Y241103D02*
X1376379Y242084D01*
G01X1383138Y241620D02*
X1376379Y243056D01*
G01Y242084D02*
X1383161Y240643D01*
G01X1390704Y243590D02*
X1383138Y241620D01*
G01X1383161Y240643D02*
X1390734Y242616D01*
G01X1400358Y241697D02*
X1390704Y243590D01*
G01X1390734Y242616D02*
X1399990Y240801D01*
G01X1406441Y237669D02*
X1400358Y241697D01*
G01X1399990Y240801D02*
X1405770Y236973D01*
G01X1431333Y199658D02*
X1400559Y220497D01*
G01X1431333Y199658D02*
X1400559Y220497D01*
G01X1431333Y199658D02*
X1400559Y220497D01*
G01D02*
X1373213Y226313D01*
G01X1400180Y219606D02*
X1373207Y225343D01*
G01X1373213Y226313D02*
X1348013Y221279D01*
G01X1373207Y225343D02*
X1347973Y220302D01*
G01X1385180Y218544D02*
X1369828Y221732D01*
G01X1353949Y261327D02*
X1357336Y261976D01*
G01X1353959Y262297D02*
X1357335Y262944D01*
G01X1357336Y261976D02*
X1362227Y260937D01*
G01X1357335Y262948D02*
X1362227Y261909D01*
G01Y260937D02*
X1366857Y261920D01*
G01X1362227Y261909D02*
X1366857Y262892D01*
G01Y261920D02*
X1371747Y260881D01*
G01X1366857Y262892D02*
X1371747Y261853D01*
G01Y260881D02*
X1376544Y261900D01*
G01X1371747Y261853D02*
X1376544Y262872D01*
G01Y261900D02*
X1381464Y260855D01*
G01X1376544Y262872D02*
X1381441Y261834D01*
G01X1381464Y260855D02*
X1399717Y265834D01*
G01X1381441Y261834D02*
X1399682Y266810D01*
G01X1399717Y265834D02*
X1413979Y263031D01*
G01X1399682Y266810D02*
X1414377Y263921D01*
G01X1354170Y258340D02*
X1357333Y259012D01*
G01X1354175Y257369D02*
X1357333Y258040D01*
G01Y259012D02*
X1362225Y257973D01*
G01X1357333Y258040D02*
X1362225Y257001D01*
G01Y257973D02*
X1366857Y258956D01*
G01X1362225Y257001D02*
X1366857Y257984D01*
G01Y258956D02*
X1371747Y257917D01*
G01Y257918D02*
X1371758Y257916D01*
G01D02*
X1371796Y257907D01*
G01X1366857Y257984D02*
X1371796Y256935D01*
G01Y257907D02*
X1376583Y258924D01*
G01X1371796Y256935D02*
X1376583Y257952D01*
G01Y258924D02*
X1381755Y257825D01*
G01X1376583Y257952D02*
X1381783Y256847D01*
G01X1381755Y257825D02*
X1399828Y262756D01*
G01X1381783Y256847D02*
X1399863Y261780D01*
G01X1399828Y262756D02*
X1412724Y260220D01*
G01X1399863Y261780D02*
X1412326Y259330D01*
G01X1410673Y255628D02*
X1400009Y257725D01*
G01X1411071Y256519D02*
X1399974Y258701D01*
G01X1400009Y257725D02*
X1382111Y252841D01*
G01X1399974Y258701D02*
X1382083Y253819D01*
G01X1382111Y252841D02*
X1376534Y254026D01*
G01X1382083Y253819D02*
X1376534Y254998D01*
G01Y254026D02*
X1371826Y253025D01*
G01X1376534Y254998D02*
X1371826Y253997D01*
G01Y253025D02*
X1366936Y254064D01*
G01X1371826Y253997D02*
X1366936Y255036D01*
G01Y254064D02*
X1362227Y253064D01*
G01X1366936Y255036D02*
X1362227Y254036D01*
G01Y253064D02*
X1357335Y254104D01*
G01X1362227Y254036D02*
X1357335Y255076D01*
G01Y254104D02*
X1354196Y253437D01*
G01X1357335Y255076D02*
X1354191Y254408D01*
G01X1354216Y249506D02*
X1357335Y250168D01*
G01X1354211Y250477D02*
X1357335Y251140D01*
G01Y250168D02*
X1362227Y249129D01*
G01X1357335Y251140D02*
X1362227Y250101D01*
G01Y249129D02*
X1366857Y250112D01*
G01X1362227Y250101D02*
X1366857Y251084D01*
G01Y250112D02*
X1371784Y249065D01*
G01X1366857Y251084D02*
X1371784Y250037D01*
G01Y249065D02*
X1376572Y250082D01*
G01X1371784Y250037D02*
X1376572Y251054D01*
G01Y250082D02*
X1382899Y248739D01*
G01X1376572Y251054D02*
X1382877Y249715D01*
G01X1382899Y248739D02*
X1390530Y250726D01*
G01X1382877Y249715D02*
X1390500Y251700D01*
G01X1390530Y250726D02*
X1400263Y248819D01*
G01X1390500Y251700D02*
X1400200Y249800D01*
G01X1400263Y248819D02*
X1405300Y250498D01*
G01X1400200Y249800D02*
X1405253Y251484D01*
G01X1353959Y262297D02*
X1357335Y262944D01*
G01X1353949Y261327D02*
X1357336Y261976D01*
G01X1357335Y262948D02*
X1362227Y261909D01*
G01X1357336Y261976D02*
X1362227Y260937D01*
G01Y261909D02*
X1366857Y262892D01*
G01X1362227Y260937D02*
X1366857Y261920D01*
G01Y262892D02*
X1371747Y261853D01*
G01X1366857Y261920D02*
X1371747Y260881D01*
G01Y261853D02*
X1376544Y262872D01*
G01X1371747Y260881D02*
X1376544Y261900D01*
G01Y262872D02*
X1381441Y261834D01*
G01X1376544Y261900D02*
X1381464Y260855D01*
G01X1381441Y261834D02*
X1399682Y266810D01*
G01X1381464Y260855D02*
X1399717Y265834D01*
G01X1399682Y266810D02*
X1414377Y263921D01*
G01X1399717Y265834D02*
X1413979Y263031D01*
G01X1354175Y257369D02*
X1357333Y258040D01*
G01X1354170Y258340D02*
X1357333Y259012D01*
G01Y258040D02*
X1362225Y257001D01*
G01X1357333Y259012D02*
X1362225Y257973D01*
G01Y257001D02*
X1366857Y257984D01*
G01X1362225Y257973D02*
X1366857Y258956D01*
G01Y257984D02*
X1371796Y256935D01*
G01X1366857Y258956D02*
X1371747Y257917D01*
G01X1366857Y257984D02*
X1371796Y256935D01*
G01X1371747Y257918D02*
X1371758Y257916D01*
G01X1366857Y257984D02*
X1371796Y256935D01*
G01X1371758Y257916D02*
X1371796Y257907D01*
G01Y256935D02*
X1376583Y257952D01*
G01X1371796Y257907D02*
X1376583Y258924D01*
G01Y257952D02*
X1381783Y256847D01*
G01X1376583Y258924D02*
X1381755Y257825D01*
G01X1381783Y256847D02*
X1399863Y261780D01*
G01X1381755Y257825D02*
X1399828Y262756D01*
G01X1399863Y261780D02*
X1412326Y259330D01*
G01X1399828Y262756D02*
X1412724Y260220D01*
G01X1411071Y256519D02*
X1399974Y258701D01*
G01X1410673Y255628D02*
X1400009Y257725D01*
G01X1399974Y258701D02*
X1382083Y253819D01*
G01X1400009Y257725D02*
X1382111Y252841D01*
G01X1382083Y253819D02*
X1376534Y254998D01*
G01X1382111Y252841D02*
X1376534Y254026D01*
G01Y254998D02*
X1371826Y253997D01*
G01X1376534Y254026D02*
X1371826Y253025D01*
G01Y253997D02*
X1366936Y255036D01*
G01X1371826Y253025D02*
X1366936Y254064D01*
G01Y255036D02*
X1362227Y254036D01*
G01X1366936Y254064D02*
X1362227Y253064D01*
G01Y254036D02*
X1357335Y255076D01*
G01X1362227Y253064D02*
X1357335Y254104D01*
G01Y255076D02*
X1354191Y254408D01*
G01X1357335Y254104D02*
X1354196Y253437D01*
G01X1354211Y250477D02*
X1357335Y251140D01*
G01X1354216Y249506D02*
X1357335Y250168D01*
G01Y251140D02*
X1362227Y250101D01*
G01X1357335Y250168D02*
X1362227Y249129D01*
G01Y250101D02*
X1366857Y251084D01*
G01X1362227Y249129D02*
X1366857Y250112D01*
G01Y251084D02*
X1371784Y250037D01*
G01X1366857Y250112D02*
X1371784Y249065D01*
G01Y250037D02*
X1376572Y251054D01*
G01X1371784Y249065D02*
X1376572Y250082D01*
G01Y251054D02*
X1382877Y249715D01*
G01X1376572Y250082D02*
X1382899Y248739D01*
G01X1382877Y249715D02*
X1390500Y251700D01*
G01X1382899Y248739D02*
X1390530Y250726D01*
G01X1390500Y251700D02*
X1400200Y249800D01*
G01X1390530Y250726D02*
X1400263Y248819D01*
G01X1400200Y249800D02*
X1405253Y251484D01*
G01X1400263Y248819D02*
X1405300Y250498D01*
G01X1399990Y240801D02*
X1405770Y236973D01*
G01X1406441Y237669D02*
X1400358Y241697D01*
G01X1390734Y242616D02*
X1399990Y240801D01*
G01X1400358Y241697D02*
X1390704Y243590D01*
G01X1383161Y240643D02*
X1390734Y242616D01*
G01X1390704Y243590D02*
X1383138Y241620D01*
G01X1376379Y242084D02*
X1383161Y240643D01*
G01X1383138Y241620D02*
X1376379Y243056D01*
G01X1371762Y241103D02*
X1376379Y242084D01*
G01Y243056D02*
X1371762Y242075D01*
G01X1366824Y242154D02*
X1371762Y241103D01*
G01Y242075D02*
X1366824Y243126D01*
G01X1362195Y241170D02*
X1366824Y242154D01*
G01Y243126D02*
X1362195Y242142D01*
G01X1357354Y242199D02*
X1362195Y241170D01*
G01Y242142D02*
X1357354Y243171D01*
G01X1354238Y241538D02*
X1357354Y242199D01*
G01Y243171D02*
X1354233Y242509D01*
G01X1431333Y199658D02*
X1400559Y220497D01*
G01X1400180Y219606D02*
X1373207Y225343D01*
G01X1400559Y220497D02*
X1373213Y226313D01*
G01X1373207Y225343D02*
X1347973Y220302D01*
G01X1373213Y226313D02*
X1348013Y221279D01*
G01X1385180Y218544D02*
X1369828Y221732D01*
G01X1357354Y243171D02*
X1354233Y242509D01*
G01X1354238Y241538D02*
X1357354Y242199D01*
G01X1362195Y242142D02*
X1357354Y243171D01*
G01Y242199D02*
X1362195Y241170D01*
G01X1366824Y243126D02*
X1362195Y242142D01*
G01Y241170D02*
X1366824Y242154D01*
G01X1371762Y242075D02*
X1366824Y243126D01*
G01Y242154D02*
X1371762Y241103D01*
G01X1376379Y243056D02*
X1371762Y242075D01*
G01Y241103D02*
X1376379Y242084D01*
G01X1383138Y241620D02*
X1376379Y243056D01*
G01Y242084D02*
X1383161Y240643D01*
G01X1390704Y243590D02*
X1383138Y241620D01*
G01X1383161Y240643D02*
X1390734Y242616D01*
G01X1400358Y241697D02*
X1390704Y243590D01*
G01X1390734Y242616D02*
X1399990Y240801D01*
G01X1406441Y237669D02*
X1400358Y241697D01*
G01X1399990Y240801D02*
X1405770Y236973D01*
G01X1431333Y199658D02*
X1400559Y220497D01*
G01X1431333Y199658D02*
X1400559Y220497D01*
G01X1431333Y199658D02*
X1400559Y220497D01*
G01D02*
X1373213Y226313D01*
G01X1400180Y219606D02*
X1373207Y225343D01*
G01X1373213Y226313D02*
X1348013Y221279D01*
G01X1373207Y225343D02*
X1347973Y220302D01*
G01X1385180Y218544D02*
X1369828Y221732D01*
G01X1353949Y261327D02*
X1357336Y261976D01*
G01X1353959Y262297D02*
X1357335Y262944D01*
G01X1357336Y261976D02*
X1362227Y260937D01*
G01X1357335Y262948D02*
X1362227Y261909D01*
G01Y260937D02*
X1366857Y261920D01*
G01X1362227Y261909D02*
X1366857Y262892D01*
G01Y261920D02*
X1371747Y260881D01*
G01X1366857Y262892D02*
X1371747Y261853D01*
G01Y260881D02*
X1376544Y261900D01*
G01X1371747Y261853D02*
X1376544Y262872D01*
G01Y261900D02*
X1381464Y260855D01*
G01X1376544Y262872D02*
X1381441Y261834D01*
G01X1381464Y260855D02*
X1399717Y265834D01*
G01X1381441Y261834D02*
X1399682Y266810D01*
G01X1399717Y265834D02*
X1413979Y263031D01*
G01X1399682Y266810D02*
X1414377Y263921D01*
G01X1354170Y258340D02*
X1357333Y259012D01*
G01X1354175Y257369D02*
X1357333Y258040D01*
G01Y259012D02*
X1362225Y257973D01*
G01X1357333Y258040D02*
X1362225Y257001D01*
G01Y257973D02*
X1366857Y258956D01*
G01X1362225Y257001D02*
X1366857Y257984D01*
G01Y258956D02*
X1371747Y257917D01*
G01Y257918D02*
X1371758Y257916D01*
G01D02*
X1371796Y257907D01*
G01X1366857Y257984D02*
X1371796Y256935D01*
G01Y257907D02*
X1376583Y258924D01*
G01X1371796Y256935D02*
X1376583Y257952D01*
G01Y258924D02*
X1381755Y257825D01*
G01X1376583Y257952D02*
X1381783Y256847D01*
G01X1381755Y257825D02*
X1399828Y262756D01*
G01X1381783Y256847D02*
X1399863Y261780D01*
G01X1399828Y262756D02*
X1412724Y260220D01*
G01X1399863Y261780D02*
X1412326Y259330D01*
G01X1410673Y255628D02*
X1400009Y257725D01*
G01X1411071Y256519D02*
X1399974Y258701D01*
G01X1400009Y257725D02*
X1382111Y252841D01*
G01X1399974Y258701D02*
X1382083Y253819D01*
G01X1382111Y252841D02*
X1376534Y254026D01*
G01X1382083Y253819D02*
X1376534Y254998D01*
G01Y254026D02*
X1371826Y253025D01*
G01X1376534Y254998D02*
X1371826Y253997D01*
G01Y253025D02*
X1366936Y254064D01*
G01X1371826Y253997D02*
X1366936Y255036D01*
G01Y254064D02*
X1362227Y253064D01*
G01X1366936Y255036D02*
X1362227Y254036D01*
G01Y253064D02*
X1357335Y254104D01*
G01X1362227Y254036D02*
X1357335Y255076D01*
G01Y254104D02*
X1354196Y253437D01*
G01X1357335Y255076D02*
X1354191Y254408D01*
G01X1354216Y249506D02*
X1357335Y250168D01*
G01X1354211Y250477D02*
X1357335Y251140D01*
G01Y250168D02*
X1362227Y249129D01*
G01X1357335Y251140D02*
X1362227Y250101D01*
G01Y249129D02*
X1366857Y250112D01*
G01X1362227Y250101D02*
X1366857Y251084D01*
G01Y250112D02*
X1371784Y249065D01*
G01X1366857Y251084D02*
X1371784Y250037D01*
G01Y249065D02*
X1376572Y250082D01*
G01X1371784Y250037D02*
X1376572Y251054D01*
G01Y250082D02*
X1382899Y248739D01*
G01X1376572Y251054D02*
X1382877Y249715D01*
G01X1382899Y248739D02*
X1390530Y250726D01*
G01X1382877Y249715D02*
X1390500Y251700D01*
G01X1390530Y250726D02*
X1400263Y248819D01*
G01X1390500Y251700D02*
X1400200Y249800D01*
G01X1400263Y248819D02*
X1405300Y250498D01*
G01X1400200Y249800D02*
X1405253Y251484D01*
G01X1407903Y241102D02*
X1403201Y244215D01*
G01X1408589Y241788D02*
X1403570Y245111D01*
G01X1403201Y244215D02*
X1390710Y246691D01*
G01X1403570Y245111D02*
X1390681Y247666D01*
G01X1390710Y246691D02*
X1382795Y244629D01*
G01X1390681Y247666D02*
X1382772Y245606D01*
G01X1382795Y244629D02*
X1376074Y246057D01*
G01X1382772Y245606D02*
X1376074Y247029D01*
G01Y246057D02*
X1371763Y245141D01*
G01X1376074Y247029D02*
X1371763Y246113D01*
G01Y245141D02*
X1366876Y246181D01*
G01X1371763Y246113D02*
X1366876Y247153D01*
G01Y246181D02*
X1362246Y245197D01*
G01X1366876Y247153D02*
X1362246Y246169D01*
G01Y245197D02*
X1357355Y246237D01*
G01X1362246Y246169D02*
X1357355Y247209D01*
G01Y246237D02*
X1354190Y245565D01*
G01X1357355Y247209D02*
X1354185Y246536D01*
G01X1353959Y262297D02*
X1357335Y262944D01*
G01X1353949Y261327D02*
X1357336Y261976D01*
G01X1357335Y262948D02*
X1362227Y261909D01*
G01X1357336Y261976D02*
X1362227Y260937D01*
G01Y261909D02*
X1366857Y262892D01*
G01X1362227Y260937D02*
X1366857Y261920D01*
G01Y262892D02*
X1371747Y261853D01*
G01X1366857Y261920D02*
X1371747Y260881D01*
G01Y261853D02*
X1376544Y262872D01*
G01X1371747Y260881D02*
X1376544Y261900D01*
G01Y262872D02*
X1381441Y261834D01*
G01X1376544Y261900D02*
X1381464Y260855D01*
G01X1381441Y261834D02*
X1399682Y266810D01*
G01X1381464Y260855D02*
X1399717Y265834D01*
G01X1399682Y266810D02*
X1414377Y263921D01*
G01X1399717Y265834D02*
X1413979Y263031D01*
G01X1354175Y257369D02*
X1357333Y258040D01*
G01X1354170Y258340D02*
X1357333Y259012D01*
G01Y258040D02*
X1362225Y257001D01*
G01X1357333Y259012D02*
X1362225Y257973D01*
G01Y257001D02*
X1366857Y257984D01*
G01X1362225Y257973D02*
X1366857Y258956D01*
G01Y257984D02*
X1371796Y256935D01*
G01X1366857Y258956D02*
X1371747Y257917D01*
G01X1366857Y257984D02*
X1371796Y256935D01*
G01X1371747Y257918D02*
X1371758Y257916D01*
G01X1366857Y257984D02*
X1371796Y256935D01*
G01X1371758Y257916D02*
X1371796Y257907D01*
G01Y256935D02*
X1376583Y257952D01*
G01X1371796Y257907D02*
X1376583Y258924D01*
G01Y257952D02*
X1381783Y256847D01*
G01X1376583Y258924D02*
X1381755Y257825D01*
G01X1381783Y256847D02*
X1399863Y261780D01*
G01X1381755Y257825D02*
X1399828Y262756D01*
G01X1399863Y261780D02*
X1412326Y259330D01*
G01X1399828Y262756D02*
X1412724Y260220D01*
G01X1411071Y256519D02*
X1399974Y258701D01*
G01X1410673Y255628D02*
X1400009Y257725D01*
G01X1399974Y258701D02*
X1382083Y253819D01*
G01X1400009Y257725D02*
X1382111Y252841D01*
G01X1382083Y253819D02*
X1376534Y254998D01*
G01X1382111Y252841D02*
X1376534Y254026D01*
G01Y254998D02*
X1371826Y253997D01*
G01X1376534Y254026D02*
X1371826Y253025D01*
G01Y253997D02*
X1366936Y255036D01*
G01X1371826Y253025D02*
X1366936Y254064D01*
G01Y255036D02*
X1362227Y254036D01*
G01X1366936Y254064D02*
X1362227Y253064D01*
G01Y254036D02*
X1357335Y255076D01*
G01X1362227Y253064D02*
X1357335Y254104D01*
G01Y255076D02*
X1354191Y254408D01*
G01X1357335Y254104D02*
X1354196Y253437D01*
G01X1354211Y250477D02*
X1357335Y251140D01*
G01X1354216Y249506D02*
X1357335Y250168D01*
G01Y251140D02*
X1362227Y250101D01*
G01X1357335Y250168D02*
X1362227Y249129D01*
G01Y250101D02*
X1366857Y251084D01*
G01X1362227Y249129D02*
X1366857Y250112D01*
G01Y251084D02*
X1371784Y250037D01*
G01X1366857Y250112D02*
X1371784Y249065D01*
G01Y250037D02*
X1376572Y251054D01*
G01X1371784Y249065D02*
X1376572Y250082D01*
G01Y251054D02*
X1382877Y249715D01*
G01X1376572Y250082D02*
X1382899Y248739D01*
G01X1382877Y249715D02*
X1390500Y251700D01*
G01X1382899Y248739D02*
X1390530Y250726D01*
G01X1390500Y251700D02*
X1400200Y249800D01*
G01X1390530Y250726D02*
X1400263Y248819D01*
G01X1400200Y249800D02*
X1405253Y251484D01*
G01X1400263Y248819D02*
X1405300Y250498D01*
G01X1408589Y241788D02*
X1403570Y245111D01*
G01X1407903Y241102D02*
X1403201Y244215D01*
G01X1403570Y245111D02*
X1390681Y247666D01*
G01X1403201Y244215D02*
X1390710Y246691D01*
G01X1390681Y247666D02*
X1382772Y245606D01*
G01X1390710Y246691D02*
X1382795Y244629D01*
G01X1382772Y245606D02*
X1376074Y247029D01*
G01X1382795Y244629D02*
X1376074Y246057D01*
G01Y247029D02*
X1371763Y246113D01*
G01X1376074Y246057D02*
X1371763Y245141D01*
G01Y246113D02*
X1366876Y247153D01*
G01X1371763Y245141D02*
X1366876Y246181D01*
G01Y247153D02*
X1362246Y246169D01*
G01X1366876Y246181D02*
X1362246Y245197D01*
G01Y246169D02*
X1357355Y247209D01*
G01X1362246Y245197D02*
X1357355Y246237D01*
G01Y247209D02*
X1354185Y246536D01*
G01X1357355Y246237D02*
X1354190Y245565D01*
G01X1350028Y307520D02*
Y310700D01*
G01X1350978Y307354D02*
Y311094D01*
G01X1350028Y310700D02*
X1348755Y311973D01*
G01D02*
X1347681D01*
G01X1350978Y311094D02*
X1349149Y312923D01*
G01X1348755Y311973D02*
X1347681D01*
G01X1349149Y312923D02*
X1348076D01*
G01X1347681Y311973D02*
X1346450Y313209D01*
G01X1348076Y312923D02*
X1347316Y313686D01*
G01X1346450Y313209D02*
X1345320Y318171D01*
G01X1347316Y313686D02*
X1346205Y318567D01*
G01X1345320Y318171D02*
X1342969Y321483D01*
G01X1346205Y318567D02*
X1343548Y322309D01*
G01X1342969Y321483D02*
X1342968D01*
G01X1350004Y323987D02*
X1346072Y325078D01*
G01X1343904Y325680D02*
X1342603Y326041D01*
G01X1352911Y316853D02*
X1352402Y318103D01*
G01X1351553Y320187D02*
X1350004Y323987D01*
G01X1350708Y324778D02*
X1353719Y317390D01*
G01X1358113Y311652D02*
X1355539Y314226D01*
G01X1353947Y315817D02*
X1352911Y316853D01*
G01X1353719Y317390D02*
X1358507Y312602D01*
G01X1359860Y311652D02*
X1358113D01*
G01X1358507Y312602D02*
X1360254D01*
G01X1360819Y310693D02*
X1359860Y311652D01*
G01X1360254Y312602D02*
X1361769Y311087D01*
G01X1360819Y307140D02*
Y310693D01*
G01X1361769Y311087D02*
Y307140D01*
G01X1371615Y310835D02*
Y307580D01*
G01X1372565D02*
Y310600D01*
G01X1375017Y317316D02*
X1371615Y310835D01*
G01X1372565Y310600D02*
X1376025Y317192D01*
G01X1373659Y322894D02*
X1375017Y317316D01*
G01X1376025Y317192D02*
X1374495Y323479D01*
G01X1369530Y325647D02*
X1373659Y322894D01*
G01X1374495Y323479D02*
X1369901Y326542D01*
G01X1352783Y329002D02*
X1354106Y328736D01*
G01X1356312Y328295D02*
X1357636Y328030D01*
G01X1359842Y327588D02*
X1361166Y327323D01*
G01X1363372Y326881D02*
X1369530Y325647D01*
G01X1360250Y340181D02*
X1356487Y340933D01*
G01X1349334Y343333D02*
X1360250Y341150D01*
G01X1367286Y341588D02*
X1360250Y340181D01*
G01Y341150D02*
X1367286Y342557D01*
G01X1369601Y341125D02*
X1367286Y341588D01*
G01X1375706Y337053D02*
X1369601Y341125D01*
G01X1369972Y342020D02*
X1376077Y337948D01*
G01X1378258Y336542D02*
X1375706Y337053D01*
G01X1376077Y337948D02*
X1378629Y337438D01*
G01X1381413Y334440D02*
X1378258Y336542D01*
G01X1378629Y337438D02*
X1382099Y335126D01*
G01X1387480Y325338D02*
X1386731Y326462D01*
G01X1385483Y328334D02*
X1384734Y329458D01*
G01X1383486Y331330D02*
X1381413Y334440D01*
G01X1382099Y335126D02*
X1388375Y325710D01*
G01X1387597Y324756D02*
X1387480Y325338D01*
G01X1388375Y325710D02*
X1388566Y324756D01*
G01X1385595Y314750D02*
X1387597Y324756D01*
G01X1388566D02*
X1386490Y314379D01*
G01X1382823Y310592D02*
X1385595Y314750D01*
G01X1386490Y314379D02*
X1383773Y310304D01*
G01X1382823Y307760D02*
Y310592D01*
G01X1383773Y310304D02*
Y307760D01*
G01X1394410Y308080D02*
Y313055D01*
G01X1395360Y308080D02*
Y312848D01*
G01X1394410Y313055D02*
X1395024Y314399D01*
G01X1395360Y312848D02*
X1396027Y314307D01*
G01X1395024Y314399D02*
X1394185Y317751D01*
G01X1396027Y314307D02*
X1395184Y317674D01*
G01X1394185Y317751D02*
X1395219Y320196D01*
G01X1396096Y322268D02*
X1396622Y323512D01*
G01X1397499Y325584D02*
X1398766Y328578D01*
G01X1395184Y317674D02*
X1399770Y328512D01*
G01X1398766Y328578D02*
X1398097Y331005D01*
G01X1399770Y328512D02*
X1398971Y331410D01*
G01X1398097Y331005D02*
X1396356Y333618D01*
G01X1398971Y331410D02*
X1397042Y334304D01*
G01X1396356Y333618D02*
X1389263Y338347D01*
G01X1397042Y334304D02*
X1389634Y339242D01*
G01X1389263Y338347D02*
X1387939Y338612D01*
G01X1385733Y339053D02*
X1384409Y339318D01*
G01X1382203Y339760D02*
X1377123Y340776D01*
G01X1389634Y339242D02*
X1377494Y341671D01*
G01X1377123Y340776D02*
X1374773Y342341D01*
G01X1401049Y338113D02*
X1400784Y339437D01*
G01X1399274Y351815D02*
X1401925Y338582D01*
G01X1402874Y336289D02*
X1401049Y338113D01*
G01X1401925Y338582D02*
X1403824Y336683D01*
G01X1402874Y324844D02*
Y336289D01*
G01X1405312Y322406D02*
X1402874Y324844D01*
G01X1350978Y307354D02*
Y311094D01*
G01X1350028Y307520D02*
Y310700D01*
G01X1350978Y311094D02*
X1349149Y312923D01*
G01X1350028Y310700D02*
X1348755Y311973D01*
G01X1350978Y311094D02*
X1349149Y312923D01*
G01D02*
X1348076D01*
G01X1348755Y311973D02*
X1347681D01*
G01X1348076Y312923D02*
X1347316Y313686D01*
G01X1347681Y311973D02*
X1346450Y313209D01*
G01X1347316Y313686D02*
X1346205Y318567D01*
G01X1346450Y313209D02*
X1345320Y318171D01*
G01X1346205Y318567D02*
X1343548Y322309D01*
G01X1345320Y318171D02*
X1342969Y321483D01*
G01D02*
X1342968D01*
G01X1361769Y311087D02*
Y307140D01*
G01X1360819D02*
Y310693D01*
G01X1360254Y312602D02*
X1361769Y311087D01*
G01X1360819Y310693D02*
X1359860Y311652D01*
G01X1358507Y312602D02*
X1360254D01*
G01X1359860Y311652D02*
X1358113D01*
G01X1353719Y317390D02*
X1358507Y312602D01*
G01X1358113Y311652D02*
X1355539Y314226D01*
G01X1353719Y317390D02*
X1358507Y312602D01*
G01X1353947Y315817D02*
X1352911Y316853D01*
G01X1350708Y324778D02*
X1353719Y317390D01*
G01X1352911Y316853D02*
X1352402Y318103D01*
G01X1350708Y324778D02*
X1353719Y317390D01*
G01X1351553Y320187D02*
X1350004Y323987D01*
G01D02*
X1346072Y325078D01*
G01X1343904Y325680D02*
X1342603Y326041D01*
G01X1352783Y329002D02*
X1354106Y328736D01*
G01X1356312Y328295D02*
X1357636Y328030D01*
G01X1359842Y327588D02*
X1361166Y327323D01*
G01X1363372Y326881D02*
X1369530Y325647D01*
G01X1374495Y323479D02*
X1369901Y326542D01*
G01X1369530Y325647D02*
X1373659Y322894D01*
G01X1376025Y317192D02*
X1374495Y323479D01*
G01X1373659Y322894D02*
X1375017Y317316D01*
G01X1372565Y310600D02*
X1376025Y317192D01*
G01X1375017Y317316D02*
X1371615Y310835D01*
G01X1372565Y307580D02*
Y310600D01*
G01X1371615Y310835D02*
Y307580D01*
G01X1383773Y310304D02*
Y307760D01*
G01X1382823D02*
Y310592D01*
G01X1386490Y314379D02*
X1383773Y310304D01*
G01X1382823Y310592D02*
X1385595Y314750D01*
G01X1388566Y324756D02*
X1386490Y314379D01*
G01X1385595Y314750D02*
X1387597Y324756D01*
G01X1388375Y325710D02*
X1388566Y324756D01*
G01X1387597D02*
X1387480Y325338D01*
G01X1382099Y335126D02*
X1388375Y325710D01*
G01X1387480Y325338D02*
X1386731Y326462D01*
G01X1382099Y335126D02*
X1388375Y325710D01*
G01X1385483Y328334D02*
X1384734Y329458D01*
G01X1382099Y335126D02*
X1388375Y325710D01*
G01X1383486Y331330D02*
X1381413Y334440D01*
G01X1378629Y337438D02*
X1382099Y335126D01*
G01X1381413Y334440D02*
X1378258Y336542D01*
G01X1376077Y337948D02*
X1378629Y337438D01*
G01X1378258Y336542D02*
X1375706Y337053D01*
G01X1369972Y342020D02*
X1376077Y337948D01*
G01X1375706Y337053D02*
X1369601Y341125D01*
G01D02*
X1367286Y341588D01*
G01X1360250Y341150D02*
X1367286Y342557D01*
G01Y341588D02*
X1360250Y340181D01*
G01X1349334Y343333D02*
X1360250Y341150D01*
G01Y340181D02*
X1356487Y340933D01*
G01X1349334Y343333D02*
X1360250Y341150D01*
G01X1349334Y343333D02*
X1360250Y341150D01*
G01X1395360Y308080D02*
Y312848D01*
G01X1394410Y308080D02*
Y313055D01*
G01X1395360Y312848D02*
X1396027Y314307D01*
G01X1394410Y313055D02*
X1395024Y314399D01*
G01X1396027Y314307D02*
X1395184Y317674D01*
G01X1395024Y314399D02*
X1394185Y317751D01*
G01X1395184Y317674D02*
X1399770Y328512D01*
G01X1394185Y317751D02*
X1395219Y320196D01*
G01X1395184Y317674D02*
X1399770Y328512D01*
G01X1396096Y322268D02*
X1396622Y323512D01*
G01X1395184Y317674D02*
X1399770Y328512D01*
G01X1397499Y325584D02*
X1398766Y328578D01*
G01X1399770Y328512D02*
X1398971Y331410D01*
G01X1398766Y328578D02*
X1398097Y331005D01*
G01X1398971Y331410D02*
X1397042Y334304D01*
G01X1398097Y331005D02*
X1396356Y333618D01*
G01X1397042Y334304D02*
X1389634Y339242D01*
G01X1396356Y333618D02*
X1389263Y338347D01*
G01X1389634Y339242D02*
X1377494Y341671D01*
G01X1389263Y338347D02*
X1387939Y338612D01*
G01X1389634Y339242D02*
X1377494Y341671D01*
G01X1385733Y339053D02*
X1384409Y339318D01*
G01X1389634Y339242D02*
X1377494Y341671D01*
G01X1382203Y339760D02*
X1377123Y340776D01*
G01D02*
X1374773Y342341D01*
G01X1405312Y322406D02*
X1402874Y324844D01*
G01D02*
Y336289D01*
G01X1401925Y338582D02*
X1403824Y336683D01*
G01X1402874Y336289D02*
X1401049Y338113D01*
G01X1399274Y351815D02*
X1401925Y338582D01*
G01X1401049Y338113D02*
X1400784Y339437D01*
G01X1399274Y351815D02*
X1401925Y338582D01*
G01X1399274Y351815D02*
X1401925Y338582D01*
G01X1350028Y307520D02*
Y310700D01*
G01X1350978Y307354D02*
Y311094D01*
G01X1350028Y310700D02*
X1348755Y311973D01*
G01D02*
X1347681D01*
G01X1350978Y311094D02*
X1349149Y312923D01*
G01X1348755Y311973D02*
X1347681D01*
G01X1349149Y312923D02*
X1348076D01*
G01X1347681Y311973D02*
X1346450Y313209D01*
G01X1348076Y312923D02*
X1347316Y313686D01*
G01X1346450Y313209D02*
X1345320Y318171D01*
G01X1347316Y313686D02*
X1346205Y318567D01*
G01X1345320Y318171D02*
X1342969Y321483D01*
G01X1346205Y318567D02*
X1343548Y322309D01*
G01X1342969Y321483D02*
X1342968D01*
G01X1350978Y307354D02*
Y311094D01*
G01X1350028Y307520D02*
Y310700D01*
G01X1350978Y311094D02*
X1349149Y312923D01*
G01X1350028Y310700D02*
X1348755Y311973D01*
G01X1350978Y311094D02*
X1349149Y312923D01*
G01D02*
X1348076D01*
G01X1348755Y311973D02*
X1347681D01*
G01X1348076Y312923D02*
X1347316Y313686D01*
G01X1347681Y311973D02*
X1346450Y313209D01*
G01X1347316Y313686D02*
X1346205Y318567D01*
G01X1346450Y313209D02*
X1345320Y318171D01*
G01X1346205Y318567D02*
X1343548Y322309D01*
G01X1345320Y318171D02*
X1342969Y321483D01*
G01D02*
X1342968D01*
G01X1350004Y323987D02*
X1346072Y325078D01*
G01X1343904Y325680D02*
X1342603Y326041D01*
G01X1352911Y316853D02*
X1352402Y318103D01*
G01X1351553Y320187D02*
X1350004Y323987D01*
G01X1350708Y324778D02*
X1353719Y317390D01*
G01X1358113Y311652D02*
X1355539Y314226D01*
G01X1353947Y315817D02*
X1352911Y316853D01*
G01X1353719Y317390D02*
X1358507Y312602D01*
G01X1359860Y311652D02*
X1358113D01*
G01X1358507Y312602D02*
X1360254D01*
G01X1360819Y310693D02*
X1359860Y311652D01*
G01X1360254Y312602D02*
X1361769Y311087D01*
G01X1360819Y307140D02*
Y310693D01*
G01X1361769Y311087D02*
Y307140D01*
G01X1371615Y310835D02*
Y307580D01*
G01X1372565D02*
Y310600D01*
G01X1375017Y317316D02*
X1371615Y310835D01*
G01X1372565Y310600D02*
X1376025Y317192D01*
G01X1373659Y322894D02*
X1375017Y317316D01*
G01X1376025Y317192D02*
X1374495Y323479D01*
G01X1369530Y325647D02*
X1373659Y322894D01*
G01X1374495Y323479D02*
X1369901Y326542D01*
G01X1352783Y329002D02*
X1354106Y328736D01*
G01X1356312Y328295D02*
X1357636Y328030D01*
G01X1359842Y327588D02*
X1361166Y327323D01*
G01X1363372Y326881D02*
X1369530Y325647D01*
G01X1360250Y340181D02*
X1356487Y340933D01*
G01X1349334Y343333D02*
X1360250Y341150D01*
G01X1367286Y341588D02*
X1360250Y340181D01*
G01Y341150D02*
X1367286Y342557D01*
G01X1369601Y341125D02*
X1367286Y341588D01*
G01X1375706Y337053D02*
X1369601Y341125D01*
G01X1369972Y342020D02*
X1376077Y337948D01*
G01X1378258Y336542D02*
X1375706Y337053D01*
G01X1376077Y337948D02*
X1378629Y337438D01*
G01X1381413Y334440D02*
X1378258Y336542D01*
G01X1378629Y337438D02*
X1382099Y335126D01*
G01X1387480Y325338D02*
X1386731Y326462D01*
G01X1385483Y328334D02*
X1384734Y329458D01*
G01X1383486Y331330D02*
X1381413Y334440D01*
G01X1382099Y335126D02*
X1388375Y325710D01*
G01X1387597Y324756D02*
X1387480Y325338D01*
G01X1388375Y325710D02*
X1388566Y324756D01*
G01X1385595Y314750D02*
X1387597Y324756D01*
G01X1388566D02*
X1386490Y314379D01*
G01X1382823Y310592D02*
X1385595Y314750D01*
G01X1386490Y314379D02*
X1383773Y310304D01*
G01X1382823Y307760D02*
Y310592D01*
G01X1383773Y310304D02*
Y307760D01*
G01X1361769Y311087D02*
Y307140D01*
G01X1360819D02*
Y310693D01*
G01X1360254Y312602D02*
X1361769Y311087D01*
G01X1360819Y310693D02*
X1359860Y311652D01*
G01X1358507Y312602D02*
X1360254D01*
G01X1359860Y311652D02*
X1358113D01*
G01X1353719Y317390D02*
X1358507Y312602D01*
G01X1358113Y311652D02*
X1355539Y314226D01*
G01X1353719Y317390D02*
X1358507Y312602D01*
G01X1353947Y315817D02*
X1352911Y316853D01*
G01X1350708Y324778D02*
X1353719Y317390D01*
G01X1352911Y316853D02*
X1352402Y318103D01*
G01X1350708Y324778D02*
X1353719Y317390D01*
G01X1351553Y320187D02*
X1350004Y323987D01*
G01D02*
X1346072Y325078D01*
G01X1343904Y325680D02*
X1342603Y326041D01*
G01X1352783Y329002D02*
X1354106Y328736D01*
G01X1356312Y328295D02*
X1357636Y328030D01*
G01X1359842Y327588D02*
X1361166Y327323D01*
G01X1363372Y326881D02*
X1369530Y325647D01*
G01X1374495Y323479D02*
X1369901Y326542D01*
G01X1369530Y325647D02*
X1373659Y322894D01*
G01X1376025Y317192D02*
X1374495Y323479D01*
G01X1373659Y322894D02*
X1375017Y317316D01*
G01X1372565Y310600D02*
X1376025Y317192D01*
G01X1375017Y317316D02*
X1371615Y310835D01*
G01X1372565Y307580D02*
Y310600D01*
G01X1371615Y310835D02*
Y307580D01*
G01X1383773Y310304D02*
Y307760D01*
G01X1382823D02*
Y310592D01*
G01X1386490Y314379D02*
X1383773Y310304D01*
G01X1382823Y310592D02*
X1385595Y314750D01*
G01X1388566Y324756D02*
X1386490Y314379D01*
G01X1385595Y314750D02*
X1387597Y324756D01*
G01X1388375Y325710D02*
X1388566Y324756D01*
G01X1387597D02*
X1387480Y325338D01*
G01X1382099Y335126D02*
X1388375Y325710D01*
G01X1387480Y325338D02*
X1386731Y326462D01*
G01X1382099Y335126D02*
X1388375Y325710D01*
G01X1385483Y328334D02*
X1384734Y329458D01*
G01X1382099Y335126D02*
X1388375Y325710D01*
G01X1383486Y331330D02*
X1381413Y334440D01*
G01X1378629Y337438D02*
X1382099Y335126D01*
G01X1381413Y334440D02*
X1378258Y336542D01*
G01X1376077Y337948D02*
X1378629Y337438D01*
G01X1378258Y336542D02*
X1375706Y337053D01*
G01X1369972Y342020D02*
X1376077Y337948D01*
G01X1375706Y337053D02*
X1369601Y341125D01*
G01D02*
X1367286Y341588D01*
G01X1360250Y341150D02*
X1367286Y342557D01*
G01Y341588D02*
X1360250Y340181D01*
G01X1349334Y343333D02*
X1360250Y341150D01*
G01Y340181D02*
X1356487Y340933D01*
G01X1349334Y343333D02*
X1360250Y341150D01*
G01X1349334Y343333D02*
X1360250Y341150D01*
G01X1394410Y308080D02*
Y313055D01*
G01X1395360Y308080D02*
Y312848D01*
G01X1394410Y313055D02*
X1395024Y314399D01*
G01X1395360Y312848D02*
X1396027Y314307D01*
G01X1395024Y314399D02*
X1394185Y317751D01*
G01X1396027Y314307D02*
X1395184Y317674D01*
G01X1394185Y317751D02*
X1395219Y320196D01*
G01X1396096Y322268D02*
X1396622Y323512D01*
G01X1397499Y325584D02*
X1398766Y328578D01*
G01X1395184Y317674D02*
X1399770Y328512D01*
G01X1398766Y328578D02*
X1398097Y331005D01*
G01X1399770Y328512D02*
X1398971Y331410D01*
G01X1398097Y331005D02*
X1396356Y333618D01*
G01X1398971Y331410D02*
X1397042Y334304D01*
G01X1396356Y333618D02*
X1389263Y338347D01*
G01X1397042Y334304D02*
X1389634Y339242D01*
G01X1389263Y338347D02*
X1387939Y338612D01*
G01X1385733Y339053D02*
X1384409Y339318D01*
G01X1382203Y339760D02*
X1377123Y340776D01*
G01X1389634Y339242D02*
X1377494Y341671D01*
G01X1377123Y340776D02*
X1374773Y342341D01*
G01X1401049Y338113D02*
X1400784Y339437D01*
G01X1399274Y351815D02*
X1401925Y338582D01*
G01X1402874Y336289D02*
X1401049Y338113D01*
G01X1401925Y338582D02*
X1403824Y336683D01*
G01X1402874Y324844D02*
Y336289D01*
G01X1405312Y322406D02*
X1402874Y324844D01*
G01X1395360Y308080D02*
Y312848D01*
G01X1394410Y308080D02*
Y313055D01*
G01X1395360Y312848D02*
X1396027Y314307D01*
G01X1394410Y313055D02*
X1395024Y314399D01*
G01X1396027Y314307D02*
X1395184Y317674D01*
G01X1395024Y314399D02*
X1394185Y317751D01*
G01X1395184Y317674D02*
X1399770Y328512D01*
G01X1394185Y317751D02*
X1395219Y320196D01*
G01X1395184Y317674D02*
X1399770Y328512D01*
G01X1396096Y322268D02*
X1396622Y323512D01*
G01X1395184Y317674D02*
X1399770Y328512D01*
G01X1397499Y325584D02*
X1398766Y328578D01*
G01X1399770Y328512D02*
X1398971Y331410D01*
G01X1398766Y328578D02*
X1398097Y331005D01*
G01X1398971Y331410D02*
X1397042Y334304D01*
G01X1398097Y331005D02*
X1396356Y333618D01*
G01X1397042Y334304D02*
X1389634Y339242D01*
G01X1396356Y333618D02*
X1389263Y338347D01*
G01X1389634Y339242D02*
X1377494Y341671D01*
G01X1389263Y338347D02*
X1387939Y338612D01*
G01X1389634Y339242D02*
X1377494Y341671D01*
G01X1385733Y339053D02*
X1384409Y339318D01*
G01X1389634Y339242D02*
X1377494Y341671D01*
G01X1382203Y339760D02*
X1377123Y340776D01*
G01D02*
X1374773Y342341D01*
G01X1405312Y322406D02*
X1402874Y324844D01*
G01D02*
Y336289D01*
G01X1401925Y338582D02*
X1403824Y336683D01*
G01X1402874Y336289D02*
X1401049Y338113D01*
G01X1399274Y351815D02*
X1401925Y338582D01*
G01X1401049Y338113D02*
X1400784Y339437D01*
G01X1399274Y351815D02*
X1401925Y338582D01*
G01X1399274Y351815D02*
X1401925Y338582D01*
G01X1354281Y341374D02*
X1352957Y341639D01*
G01X1350751Y342080D02*
X1349427Y342345D01*
G01X1367286Y342557D02*
X1369972Y342020D01*
G01X1377494Y341671D02*
X1375459Y343027D01*
G01X1374773Y342341D02*
X1372730Y345404D01*
G01X1375459Y343027D02*
X1373304Y346258D01*
G01X1372730Y345404D02*
X1362801Y347391D01*
G01X1373304Y346258D02*
X1362801Y348360D01*
G01Y347391D02*
X1357122Y346256D01*
G01X1362801Y348360D02*
X1357122Y347225D01*
G01Y346256D02*
X1349023Y347876D01*
G01X1357122Y347225D02*
X1349394Y348771D01*
G01X1349543Y352995D02*
X1344409Y356418D01*
G01X1344780Y357313D02*
X1349914Y353890D01*
G01X1356343Y351634D02*
X1349543Y352995D01*
G01X1349914Y353890D02*
X1356343Y352603D01*
G01X1372945Y354957D02*
X1356343Y351634D01*
G01Y352603D02*
X1372945Y355926D01*
G01X1386189Y352314D02*
X1372945Y354957D01*
G01Y355926D02*
X1386189Y353283D01*
G01X1394368Y353950D02*
X1386189Y352314D01*
G01Y353283D02*
X1394568Y354959D01*
G01X1398419Y351243D02*
X1394368Y353950D01*
G01X1394568Y354959D02*
X1399274Y351815D01*
G01X1400342Y341643D02*
X1400077Y342967D01*
G01X1399635Y345173D02*
X1398419Y351243D01*
G01X1413117Y338751D02*
X1403704Y348164D01*
G01X1402793Y354464D02*
X1404654Y351673D01*
G01X1403704Y351385D02*
X1402107Y353779D01*
G01X1395759Y359163D02*
X1402793Y354464D01*
G01X1402107Y353779D02*
X1395559Y358154D01*
G01X1386081Y357226D02*
X1395759Y359163D01*
G01X1395559Y358154D02*
X1386081Y356257D01*
G01X1371897Y360057D02*
X1386081Y357226D01*
G01Y356257D02*
X1371897Y359088D01*
G01X1356614Y356997D02*
X1371897Y360057D01*
G01Y359088D02*
X1356614Y356028D01*
G01X1353605Y357598D02*
X1356614Y356997D01*
G01Y356028D02*
X1353235Y356701D01*
G01X1345392Y363069D02*
X1353605Y357598D01*
G01X1353235Y356701D02*
X1345017Y362177D01*
G01X1367286Y342557D02*
X1369972Y342020D01*
G01X1354281Y341374D02*
X1352957Y341639D01*
G01X1350751Y342080D02*
X1349427Y342345D01*
G01X1377494Y341671D02*
X1375459Y343027D01*
G01D02*
X1373304Y346258D01*
G01X1374773Y342341D02*
X1372730Y345404D01*
G01X1373304Y346258D02*
X1362801Y348360D01*
G01X1372730Y345404D02*
X1362801Y347391D01*
G01Y348360D02*
X1357122Y347225D01*
G01X1362801Y347391D02*
X1357122Y346256D01*
G01Y347225D02*
X1349394Y348771D01*
G01X1357122Y346256D02*
X1349023Y347876D01*
G01X1400342Y341643D02*
X1400077Y342967D01*
G01X1399635Y345173D02*
X1398419Y351243D01*
G01X1394568Y354959D02*
X1399274Y351815D01*
G01X1398419Y351243D02*
X1394368Y353950D01*
G01X1386189Y353283D02*
X1394568Y354959D01*
G01X1394368Y353950D02*
X1386189Y352314D01*
G01X1372945Y355926D02*
X1386189Y353283D01*
G01Y352314D02*
X1372945Y354957D01*
G01X1356343Y352603D02*
X1372945Y355926D01*
G01Y354957D02*
X1356343Y351634D01*
G01X1349914Y353890D02*
X1356343Y352603D01*
G01Y351634D02*
X1349543Y352995D01*
G01X1344780Y357313D02*
X1349914Y353890D01*
G01X1349543Y352995D02*
X1344409Y356418D01*
G01X1353235Y356701D02*
X1345017Y362177D01*
G01X1345392Y363069D02*
X1353605Y357598D01*
G01X1356614Y356028D02*
X1353235Y356701D01*
G01X1353605Y357598D02*
X1356614Y356997D01*
G01X1371897Y359088D02*
X1356614Y356028D01*
G01Y356997D02*
X1371897Y360057D01*
G01X1386081Y356257D02*
X1371897Y359088D01*
G01Y360057D02*
X1386081Y357226D01*
G01X1395559Y358154D02*
X1386081Y356257D01*
G01Y357226D02*
X1395759Y359163D01*
G01X1402107Y353779D02*
X1395559Y358154D01*
G01X1395759Y359163D02*
X1402793Y354464D01*
G01X1403704Y351385D02*
X1402107Y353779D01*
G01X1402793Y354464D02*
X1404654Y351673D01*
G01X1413117Y338751D02*
X1403704Y348164D01*
G01X1354281Y341374D02*
X1352957Y341639D01*
G01X1350751Y342080D02*
X1349427Y342345D01*
G01X1367286Y342557D02*
X1369972Y342020D01*
G01X1367286Y342557D02*
X1369972Y342020D01*
G01X1354281Y341374D02*
X1352957Y341639D01*
G01X1350751Y342080D02*
X1349427Y342345D01*
G01X1377494Y341671D02*
X1375459Y343027D01*
G01X1374773Y342341D02*
X1372730Y345404D01*
G01X1375459Y343027D02*
X1373304Y346258D01*
G01X1372730Y345404D02*
X1362801Y347391D01*
G01X1373304Y346258D02*
X1362801Y348360D01*
G01Y347391D02*
X1357122Y346256D01*
G01X1362801Y348360D02*
X1357122Y347225D01*
G01Y346256D02*
X1349023Y347876D01*
G01X1357122Y347225D02*
X1349394Y348771D01*
G01X1349543Y352995D02*
X1344409Y356418D01*
G01X1344780Y357313D02*
X1349914Y353890D01*
G01X1356343Y351634D02*
X1349543Y352995D01*
G01X1349914Y353890D02*
X1356343Y352603D01*
G01X1372945Y354957D02*
X1356343Y351634D01*
G01Y352603D02*
X1372945Y355926D01*
G01X1386189Y352314D02*
X1372945Y354957D01*
G01Y355926D02*
X1386189Y353283D01*
G01X1394368Y353950D02*
X1386189Y352314D01*
G01Y353283D02*
X1394568Y354959D01*
G01X1398419Y351243D02*
X1394368Y353950D01*
G01X1394568Y354959D02*
X1399274Y351815D01*
G01X1400342Y341643D02*
X1400077Y342967D01*
G01X1399635Y345173D02*
X1398419Y351243D01*
G01X1413117Y338751D02*
X1403704Y348164D01*
G01X1402793Y354464D02*
X1404654Y351673D01*
G01X1403704Y351385D02*
X1402107Y353779D01*
G01X1395759Y359163D02*
X1402793Y354464D01*
G01X1402107Y353779D02*
X1395559Y358154D01*
G01X1386081Y357226D02*
X1395759Y359163D01*
G01X1395559Y358154D02*
X1386081Y356257D01*
G01X1371897Y360057D02*
X1386081Y357226D01*
G01Y356257D02*
X1371897Y359088D01*
G01X1356614Y356997D02*
X1371897Y360057D01*
G01Y359088D02*
X1356614Y356028D01*
G01X1353605Y357598D02*
X1356614Y356997D01*
G01Y356028D02*
X1353235Y356701D01*
G01X1345392Y363069D02*
X1353605Y357598D01*
G01X1353235Y356701D02*
X1345017Y362177D01*
G01X1377494Y341671D02*
X1375459Y343027D01*
G01D02*
X1373304Y346258D01*
G01X1374773Y342341D02*
X1372730Y345404D01*
G01X1373304Y346258D02*
X1362801Y348360D01*
G01X1372730Y345404D02*
X1362801Y347391D01*
G01Y348360D02*
X1357122Y347225D01*
G01X1362801Y347391D02*
X1357122Y346256D01*
G01Y347225D02*
X1349394Y348771D01*
G01X1357122Y346256D02*
X1349023Y347876D01*
G01X1400342Y341643D02*
X1400077Y342967D01*
G01X1399635Y345173D02*
X1398419Y351243D01*
G01X1394568Y354959D02*
X1399274Y351815D01*
G01X1398419Y351243D02*
X1394368Y353950D01*
G01X1386189Y353283D02*
X1394568Y354959D01*
G01X1394368Y353950D02*
X1386189Y352314D01*
G01X1372945Y355926D02*
X1386189Y353283D01*
G01Y352314D02*
X1372945Y354957D01*
G01X1356343Y352603D02*
X1372945Y355926D01*
G01Y354957D02*
X1356343Y351634D01*
G01X1349914Y353890D02*
X1356343Y352603D01*
G01Y351634D02*
X1349543Y352995D01*
G01X1344780Y357313D02*
X1349914Y353890D01*
G01X1349543Y352995D02*
X1344409Y356418D01*
G01X1353235Y356701D02*
X1345017Y362177D01*
G01X1345392Y363069D02*
X1353605Y357598D01*
G01X1356614Y356028D02*
X1353235Y356701D01*
G01X1353605Y357598D02*
X1356614Y356997D01*
G01X1371897Y359088D02*
X1356614Y356028D01*
G01Y356997D02*
X1371897Y360057D01*
G01X1386081Y356257D02*
X1371897Y359088D01*
G01Y360057D02*
X1386081Y357226D01*
G01X1395559Y358154D02*
X1386081Y356257D01*
G01Y357226D02*
X1395759Y359163D01*
G01X1402107Y353779D02*
X1395559Y358154D01*
G01X1395759Y359163D02*
X1402793Y354464D01*
G01X1403704Y351385D02*
X1402107Y353779D01*
G01X1402793Y354464D02*
X1404654Y351673D01*
G01X1413117Y338751D02*
X1403704Y348164D01*
G01X1424234Y457534D02*
X1402923Y463294D01*
G01X1424234Y457534D02*
X1402923Y463294D01*
G01X1413572Y459431D02*
X1402935Y462306D01*
G01X1402923Y463294D02*
X1395083Y460977D01*
G01X1402935Y462306D02*
X1395221Y460027D01*
G01X1395083Y460977D02*
X1361148D01*
G01X1395221Y460027D02*
X1360754D01*
G01X1395083Y460977D02*
X1361148D01*
G01D02*
X1360707Y461418D01*
G01X1360754Y460027D02*
X1360313Y460468D01*
G01X1365029Y466077D02*
X1367171Y463935D01*
G01D02*
X1394063D01*
G01D02*
X1403325Y466675D01*
G01X1413572Y459431D02*
X1402935Y462306D01*
G01X1424234Y457534D02*
X1402923Y463294D01*
G01X1402935Y462306D02*
X1395221Y460027D01*
G01X1402923Y463294D02*
X1395083Y460977D01*
G01X1395221Y460027D02*
X1360754D01*
G01D02*
X1360313Y460468D01*
G01X1395083Y460977D02*
X1361148D01*
G01X1360754Y460027D02*
X1360313Y460468D01*
G01X1361148Y460977D02*
X1360707Y461418D01*
G01X1365029Y466077D02*
X1367171Y463935D01*
G01D02*
X1394063D01*
G01D02*
X1403325Y466675D01*
G01X1424234Y457534D02*
X1402923Y463294D01*
G01X1424234Y457534D02*
X1402923Y463294D01*
G01X1413572Y459431D02*
X1402935Y462306D01*
G01X1402923Y463294D02*
X1395083Y460977D01*
G01X1402935Y462306D02*
X1395221Y460027D01*
G01X1395083Y460977D02*
X1361148D01*
G01X1395221Y460027D02*
X1360754D01*
G01X1395083Y460977D02*
X1361148D01*
G01D02*
X1360707Y461418D01*
G01X1360754Y460027D02*
X1360313Y460468D01*
G01X1365029Y466077D02*
X1367171Y463935D01*
G01D02*
X1394063D01*
G01D02*
X1403325Y466675D01*
G01X1413572Y459431D02*
X1402935Y462306D01*
G01X1424234Y457534D02*
X1402923Y463294D01*
G01X1402935Y462306D02*
X1395221Y460027D01*
G01X1402923Y463294D02*
X1395083Y460977D01*
G01X1395221Y460027D02*
X1360754D01*
G01D02*
X1360313Y460468D01*
G01X1395083Y460977D02*
X1361148D01*
G01X1360754Y460027D02*
X1360313Y460468D01*
G01X1361148Y460977D02*
X1360707Y461418D01*
G01X1365029Y466077D02*
X1367171Y463935D01*
G01D02*
X1394063D01*
G01D02*
X1403325Y466675D01*
G01X1349779Y479400D02*
X1351792D01*
G01D02*
X1357242Y473950D01*
G01X1352186Y480350D02*
X1357636Y474900D01*
G01X1357242Y473950D02*
X1370206D01*
G01X1357636Y474900D02*
X1370600D01*
G01X1370206Y473950D02*
X1372251Y471905D01*
G01X1370600Y474900D02*
X1372645Y472855D01*
G01X1372251Y471905D02*
X1391403D01*
G01X1372645Y472855D02*
X1391265D01*
G01X1391403Y471905D02*
X1402956Y475327D01*
G01X1391265Y472855D02*
X1399492Y475292D01*
G01X1391403Y471905D02*
X1402956Y475327D01*
G01X1401650Y475932D02*
X1402944Y476315D01*
G01X1402956Y475327D02*
X1423369Y469811D01*
G01X1402944Y476315D02*
X1423402Y470787D01*
G01X1349779Y479400D02*
X1351792D01*
G01X1352186Y480350D02*
X1357636Y474900D01*
G01X1351792Y479400D02*
X1357242Y473950D01*
G01X1357636Y474900D02*
X1370600D01*
G01X1357242Y473950D02*
X1370206D01*
G01X1370600Y474900D02*
X1372645Y472855D01*
G01X1370206Y473950D02*
X1372251Y471905D01*
G01X1372645Y472855D02*
X1391265D01*
G01X1372251Y471905D02*
X1391403D01*
G01X1391265Y472855D02*
X1399492Y475292D01*
G01X1401650Y475932D02*
X1402944Y476315D01*
G01X1391403Y471905D02*
X1402956Y475327D01*
G01X1402944Y476315D02*
X1423402Y470787D01*
G01X1402956Y475327D02*
X1423369Y469811D01*
G01X1353658Y484300D02*
X1358858Y479100D01*
G01X1353264Y483350D02*
X1358464Y478150D01*
G01X1358858Y479100D02*
X1372190D01*
G01X1358464Y478150D02*
X1371796D01*
G01X1372190Y479100D02*
X1374491Y476799D01*
G01X1371796Y478150D02*
X1374097Y475849D01*
G01X1374491Y476799D02*
X1390576D01*
G01X1374097Y475849D02*
X1390809D01*
G01X1390576Y476799D02*
X1409433Y486600D01*
G01X1390809Y475849D02*
X1409666Y485650D01*
G01X1373261Y495615D02*
X1361172D01*
G01X1371874Y494665D02*
X1373655D01*
G01X1379596Y501950D02*
X1373261Y495615D01*
G01X1373655Y494665D02*
X1379990Y501000D01*
G01X1402511Y501950D02*
X1400050D01*
G01D02*
X1379596D01*
G01X1379990Y501000D02*
X1402799D01*
G01X1407917Y505554D02*
X1402511Y501950D01*
G01X1402799Y501000D02*
X1408288Y504658D01*
G01X1407917Y505554D02*
X1402511Y501950D01*
G01X1361172Y495615D02*
X1360337Y496450D01*
G01X1359943Y495500D02*
X1360778Y494665D01*
G01X1373261Y495615D02*
X1361172D01*
G01X1360778Y494665D02*
X1371874D01*
G01X1353264Y483350D02*
X1358464Y478150D01*
G01X1353658Y484300D02*
X1358858Y479100D01*
G01X1358464Y478150D02*
X1371796D01*
G01X1358858Y479100D02*
X1372190D01*
G01X1371796Y478150D02*
X1374097Y475849D01*
G01X1372190Y479100D02*
X1374491Y476799D01*
G01X1374097Y475849D02*
X1390809D01*
G01X1374491Y476799D02*
X1390576D01*
G01X1390809Y475849D02*
X1409666Y485650D01*
G01X1390576Y476799D02*
X1409433Y486600D01*
G01X1402799Y501000D02*
X1408288Y504658D01*
G01X1407917Y505554D02*
X1402511Y501950D01*
G01X1379990Y501000D02*
X1402799D01*
G01X1402511Y501950D02*
X1400050D01*
G01X1379990Y501000D02*
X1402799D01*
G01X1400050Y501950D02*
X1379596D01*
G01X1373655Y494665D02*
X1379990Y501000D01*
G01X1379596Y501950D02*
X1373261Y495615D01*
G01X1371874Y494665D02*
X1373655D01*
G01X1360778D02*
X1371874D01*
G01X1373261Y495615D02*
X1361172D01*
G01X1359943Y495500D02*
X1360778Y494665D01*
G01X1361172Y495615D02*
X1360337Y496450D01*
G01X1365423Y467027D02*
X1367565Y464885D01*
G01D02*
X1393925D01*
G01D02*
X1403313Y467663D01*
G01D02*
X1409867Y465892D01*
G01X1403325Y466675D02*
X1421619Y461733D01*
G01X1403003Y471739D02*
X1414485Y468635D01*
G01X1417110Y466942D02*
X1403015Y470751D01*
G01X1393645Y468968D02*
X1403003Y471739D01*
G01X1403015Y470751D02*
X1393783Y468018D01*
G01X1370832Y468968D02*
X1393645D01*
G01X1393783Y468018D02*
X1370438D01*
G01X1368900Y470900D02*
X1370832Y468968D01*
G01X1370438Y468018D02*
X1368506Y469950D01*
G01X1346632Y470900D02*
X1368900D01*
G01X1368506Y469950D02*
X1346238D01*
G01X1342101Y475431D02*
X1346632Y470900D01*
G01X1349779Y479400D02*
X1351792D01*
G01D02*
X1357242Y473950D01*
G01X1352186Y480350D02*
X1357636Y474900D01*
G01X1357242Y473950D02*
X1370206D01*
G01X1357636Y474900D02*
X1370600D01*
G01X1370206Y473950D02*
X1372251Y471905D01*
G01X1370600Y474900D02*
X1372645Y472855D01*
G01X1372251Y471905D02*
X1391403D01*
G01X1372645Y472855D02*
X1391265D01*
G01X1391403Y471905D02*
X1402956Y475327D01*
G01X1391265Y472855D02*
X1399492Y475292D01*
G01X1391403Y471905D02*
X1402956Y475327D01*
G01X1401650Y475932D02*
X1402944Y476315D01*
G01X1402956Y475327D02*
X1423369Y469811D01*
G01X1402944Y476315D02*
X1423402Y470787D01*
G01X1404310Y492405D02*
X1387679Y480629D01*
G01X1413526Y497765D02*
X1391987Y482515D01*
G01X1404310Y492405D02*
X1387679Y480629D01*
G01X1391987Y482515D02*
X1387982Y479679D01*
G01X1387679Y480629D02*
X1376078D01*
G01X1387982Y479679D02*
X1375684D01*
G01X1376078Y480629D02*
X1372087Y484620D01*
G01X1375684Y479679D02*
X1371693Y483670D01*
G01X1372087Y484620D02*
X1359021D01*
G01X1371693Y483670D02*
X1358627D01*
G01X1359021Y484620D02*
X1355028Y488613D01*
G01X1358627Y483670D02*
X1354634Y487663D01*
G01X1406128Y499452D02*
X1401128Y496118D01*
G01X1410299Y501091D02*
X1401655Y495326D01*
G01X1401128Y496118D02*
X1398067Y494076D01*
G01X1401655Y495326D02*
X1398594Y493285D01*
G01X1398067Y494076D02*
X1393498Y491029D01*
G01X1398594Y493285D02*
X1393786Y490079D01*
G01X1393498Y491029D02*
X1376375D01*
G01X1393786Y490079D02*
X1376769D01*
G01X1376375Y491029D02*
X1375419Y490073D01*
G01X1376769Y490079D02*
X1375813Y489123D01*
G01X1375419Y490073D02*
X1360963D01*
G01X1375813Y489123D02*
X1360569D01*
G01X1360963Y490073D02*
X1358467Y492569D01*
G01X1360569Y489123D02*
X1358073Y491619D01*
G01D02*
X1351800D01*
G01X1342101Y475431D02*
X1346632Y470900D01*
G01X1368506Y469950D02*
X1346238D01*
G01X1346632Y470900D02*
X1368900D01*
G01X1370438Y468018D02*
X1368506Y469950D01*
G01X1368900Y470900D02*
X1370832Y468968D01*
G01X1393783Y468018D02*
X1370438D01*
G01X1370832Y468968D02*
X1393645D01*
G01X1403015Y470751D02*
X1393783Y468018D01*
G01X1393645Y468968D02*
X1403003Y471739D01*
G01X1417110Y466942D02*
X1403015Y470751D01*
G01X1403003Y471739D02*
X1414485Y468635D01*
G01X1413526Y497765D02*
X1391987Y482515D01*
G01X1413526Y497765D02*
X1391987Y482515D01*
G01D02*
X1387982Y479679D01*
G01X1404310Y492405D02*
X1387679Y480629D01*
G01X1387982Y479679D02*
X1375684D01*
G01X1387679Y480629D02*
X1376078D01*
G01X1375684Y479679D02*
X1371693Y483670D01*
G01X1376078Y480629D02*
X1372087Y484620D01*
G01X1371693Y483670D02*
X1358627D01*
G01X1372087Y484620D02*
X1359021D01*
G01X1358627Y483670D02*
X1354634Y487663D01*
G01X1359021Y484620D02*
X1355028Y488613D01*
G01X1410299Y501091D02*
X1401655Y495326D01*
G01X1410299Y501091D02*
X1401655Y495326D01*
G01X1406128Y499452D02*
X1401128Y496118D01*
G01X1401655Y495326D02*
X1398594Y493285D01*
G01X1401128Y496118D02*
X1398067Y494076D01*
G01X1398594Y493285D02*
X1393786Y490079D01*
G01X1398067Y494076D02*
X1393498Y491029D01*
G01X1393786Y490079D02*
X1376769D01*
G01X1393498Y491029D02*
X1376375D01*
G01X1376769Y490079D02*
X1375813Y489123D01*
G01X1376375Y491029D02*
X1375419Y490073D01*
G01X1375813Y489123D02*
X1360569D01*
G01X1375419Y490073D02*
X1360963D01*
G01X1360569Y489123D02*
X1358073Y491619D01*
G01X1360963Y490073D02*
X1358467Y492569D01*
G01X1358073Y491619D02*
X1351800D01*
G01X1410299Y501091D02*
X1401655Y495326D01*
G01X1410299Y501091D02*
X1401655Y495326D01*
G01X1406128Y499452D02*
X1401128Y496118D01*
G01X1401655Y495326D02*
X1398594Y493285D01*
G01X1401128Y496118D02*
X1398067Y494076D01*
G01X1398594Y493285D02*
X1393786Y490079D01*
G01X1398067Y494076D02*
X1393498Y491029D01*
G01X1393786Y490079D02*
X1376769D01*
G01X1393498Y491029D02*
X1376375D01*
G01X1376769Y490079D02*
X1375813Y489123D01*
G01X1376375Y491029D02*
X1375419Y490073D01*
G01X1375813Y489123D02*
X1360569D01*
G01X1375419Y490073D02*
X1360963D01*
G01X1360569Y489123D02*
X1358073Y491619D01*
G01X1360963Y490073D02*
X1358467Y492569D01*
G01X1358073Y491619D02*
X1351800D01*
G01X1403325Y466675D02*
X1421619Y461733D01*
G01X1365423Y467027D02*
X1367565Y464885D01*
G01D02*
X1393925D01*
G01D02*
X1403313Y467663D01*
G01X1403325Y466675D02*
X1421619Y461733D01*
G01X1403313Y467663D02*
X1409867Y465892D01*
G01X1403325Y466675D02*
X1421619Y461733D01*
G01X1404310Y492405D02*
X1387679Y480629D01*
G01X1413526Y497765D02*
X1391987Y482515D01*
G01X1404310Y492405D02*
X1387679Y480629D01*
G01X1391987Y482515D02*
X1387982Y479679D01*
G01X1387679Y480629D02*
X1376078D01*
G01X1387982Y479679D02*
X1375684D01*
G01X1376078Y480629D02*
X1372087Y484620D01*
G01X1375684Y479679D02*
X1371693Y483670D01*
G01X1372087Y484620D02*
X1359021D01*
G01X1371693Y483670D02*
X1358627D01*
G01X1359021Y484620D02*
X1355028Y488613D01*
G01X1358627Y483670D02*
X1354634Y487663D01*
G01X1406128Y499452D02*
X1401128Y496118D01*
G01X1410299Y501091D02*
X1401655Y495326D01*
G01X1401128Y496118D02*
X1398067Y494076D01*
G01X1401655Y495326D02*
X1398594Y493285D01*
G01X1398067Y494076D02*
X1393498Y491029D01*
G01X1398594Y493285D02*
X1393786Y490079D01*
G01X1393498Y491029D02*
X1376375D01*
G01X1393786Y490079D02*
X1376769D01*
G01X1376375Y491029D02*
X1375419Y490073D01*
G01X1376769Y490079D02*
X1375813Y489123D01*
G01X1375419Y490073D02*
X1360963D01*
G01X1375813Y489123D02*
X1360569D01*
G01X1360963Y490073D02*
X1358467Y492569D01*
G01X1360569Y489123D02*
X1358073Y491619D01*
G01D02*
X1351800D01*
G01X1373261Y495615D02*
X1361172D01*
G01X1371874Y494665D02*
X1373655D01*
G01X1379596Y501950D02*
X1373261Y495615D01*
G01X1373655Y494665D02*
X1379990Y501000D01*
G01X1402511Y501950D02*
X1400050D01*
G01D02*
X1379596D01*
G01X1379990Y501000D02*
X1402799D01*
G01X1407917Y505554D02*
X1402511Y501950D01*
G01X1402799Y501000D02*
X1408288Y504658D01*
G01X1407917Y505554D02*
X1402511Y501950D01*
G01X1361172Y495615D02*
X1360337Y496450D01*
G01X1359943Y495500D02*
X1360778Y494665D01*
G01X1373261Y495615D02*
X1361172D01*
G01X1360778Y494665D02*
X1371874D01*
G01X1349779Y479400D02*
X1351792D01*
G01X1352186Y480350D02*
X1357636Y474900D01*
G01X1351792Y479400D02*
X1357242Y473950D01*
G01X1357636Y474900D02*
X1370600D01*
G01X1357242Y473950D02*
X1370206D01*
G01X1370600Y474900D02*
X1372645Y472855D01*
G01X1370206Y473950D02*
X1372251Y471905D01*
G01X1372645Y472855D02*
X1391265D01*
G01X1372251Y471905D02*
X1391403D01*
G01X1391265Y472855D02*
X1399492Y475292D01*
G01X1401650Y475932D02*
X1402944Y476315D01*
G01X1391403Y471905D02*
X1402956Y475327D01*
G01X1402944Y476315D02*
X1423402Y470787D01*
G01X1402956Y475327D02*
X1423369Y469811D01*
G01X1402799Y501000D02*
X1408288Y504658D01*
G01X1407917Y505554D02*
X1402511Y501950D01*
G01X1379990Y501000D02*
X1402799D01*
G01X1402511Y501950D02*
X1400050D01*
G01X1379990Y501000D02*
X1402799D01*
G01X1400050Y501950D02*
X1379596D01*
G01X1373655Y494665D02*
X1379990Y501000D01*
G01X1379596Y501950D02*
X1373261Y495615D01*
G01X1371874Y494665D02*
X1373655D01*
G01X1360778D02*
X1371874D01*
G01X1373261Y495615D02*
X1361172D01*
G01X1359943Y495500D02*
X1360778Y494665D01*
G01X1361172Y495615D02*
X1360337Y496450D01*
G01X1365423Y467027D02*
X1367565Y464885D01*
G01D02*
X1393925D01*
G01D02*
X1403313Y467663D01*
G01D02*
X1409867Y465892D01*
G01X1403325Y466675D02*
X1421619Y461733D01*
G01X1403325Y466675D02*
X1421619Y461733D01*
G01X1365423Y467027D02*
X1367565Y464885D01*
G01D02*
X1393925D01*
G01D02*
X1403313Y467663D01*
G01X1403325Y466675D02*
X1421619Y461733D01*
G01X1403313Y467663D02*
X1409867Y465892D01*
G01X1403325Y466675D02*
X1421619Y461733D01*
G01X1403003Y471739D02*
X1414485Y468635D01*
G01X1417110Y466942D02*
X1403015Y470751D01*
G01X1393645Y468968D02*
X1403003Y471739D01*
G01X1403015Y470751D02*
X1393783Y468018D01*
G01X1370832Y468968D02*
X1393645D01*
G01X1393783Y468018D02*
X1370438D01*
G01X1368900Y470900D02*
X1370832Y468968D01*
G01X1370438Y468018D02*
X1368506Y469950D01*
G01X1346632Y470900D02*
X1368900D01*
G01X1368506Y469950D02*
X1346238D01*
G01X1342101Y475431D02*
X1346632Y470900D01*
G01X1353658Y484300D02*
X1358858Y479100D01*
G01X1353264Y483350D02*
X1358464Y478150D01*
G01X1358858Y479100D02*
X1372190D01*
G01X1358464Y478150D02*
X1371796D01*
G01X1372190Y479100D02*
X1374491Y476799D01*
G01X1371796Y478150D02*
X1374097Y475849D01*
G01X1374491Y476799D02*
X1390576D01*
G01X1374097Y475849D02*
X1390809D01*
G01X1390576Y476799D02*
X1409433Y486600D01*
G01X1390809Y475849D02*
X1409666Y485650D01*
G01X1342101Y475431D02*
X1346632Y470900D01*
G01X1368506Y469950D02*
X1346238D01*
G01X1346632Y470900D02*
X1368900D01*
G01X1370438Y468018D02*
X1368506Y469950D01*
G01X1368900Y470900D02*
X1370832Y468968D01*
G01X1393783Y468018D02*
X1370438D01*
G01X1370832Y468968D02*
X1393645D01*
G01X1403015Y470751D02*
X1393783Y468018D01*
G01X1393645Y468968D02*
X1403003Y471739D01*
G01X1417110Y466942D02*
X1403015Y470751D01*
G01X1403003Y471739D02*
X1414485Y468635D01*
G01X1353264Y483350D02*
X1358464Y478150D01*
G01X1353658Y484300D02*
X1358858Y479100D01*
G01X1358464Y478150D02*
X1371796D01*
G01X1358858Y479100D02*
X1372190D01*
G01X1371796Y478150D02*
X1374097Y475849D01*
G01X1372190Y479100D02*
X1374491Y476799D01*
G01X1374097Y475849D02*
X1390809D01*
G01X1374491Y476799D02*
X1390576D01*
G01X1390809Y475849D02*
X1409666Y485650D01*
G01X1390576Y476799D02*
X1409433Y486600D01*
G01X1413526Y497765D02*
X1391987Y482515D01*
G01X1413526Y497765D02*
X1391987Y482515D01*
G01D02*
X1387982Y479679D01*
G01X1404310Y492405D02*
X1387679Y480629D01*
G01X1387982Y479679D02*
X1375684D01*
G01X1387679Y480629D02*
X1376078D01*
G01X1375684Y479679D02*
X1371693Y483670D01*
G01X1376078Y480629D02*
X1372087Y484620D01*
G01X1371693Y483670D02*
X1358627D01*
G01X1372087Y484620D02*
X1359021D01*
G01X1358627Y483670D02*
X1354634Y487663D01*
G01X1359021Y484620D02*
X1355028Y488613D01*
G01X1462058Y13506D02*
Y12014D01*
G01X1463008Y13554D02*
Y12108D01*
G01X1452798Y13496D02*
Y10840D01*
G01X1453748Y13612D02*
Y10446D01*
G01X1452798Y10840D02*
X1452016Y10058D01*
G01X1453748Y10446D02*
X1452966Y9664D01*
G01X1452016Y10058D02*
Y6039D01*
G01X1452966Y9664D02*
Y6039D01*
G01X1444111Y13554D02*
Y12108D01*
G01X1443161Y13506D02*
Y12014D01*
G01X1433618Y13576D02*
Y11819D01*
G01X1434568Y13612D02*
Y11425D01*
G01X1433618Y11819D02*
X1432950Y11151D01*
G01X1434568Y11425D02*
X1433900Y10757D01*
G01X1432950Y11151D02*
Y8632D01*
G01X1433900Y10757D02*
Y8700D01*
G01X1424263Y13506D02*
Y12014D01*
G01X1425213Y13554D02*
Y12108D01*
G01X1463008Y13554D02*
Y12108D01*
G01X1462058Y13506D02*
Y12014D01*
G01X1453748Y13612D02*
Y10446D01*
G01X1452798Y13496D02*
Y10840D01*
G01X1453748Y10446D02*
X1452966Y9664D01*
G01X1452798Y10840D02*
X1452016Y10058D01*
G01X1452966Y9664D02*
Y6039D01*
G01X1452016Y10058D02*
Y6039D01*
G01X1443161Y13506D02*
Y12014D01*
G01X1444111Y13554D02*
Y12108D01*
G01X1434568Y13612D02*
Y11425D01*
G01X1433618Y13576D02*
Y11819D01*
G01X1434568Y11425D02*
X1433900Y10757D01*
G01X1433618Y11819D02*
X1432950Y11151D01*
G01X1433900Y10757D02*
Y8700D01*
G01X1432950Y11151D02*
Y8632D01*
G01X1425213Y13554D02*
Y12108D01*
G01X1424263Y13506D02*
Y12014D01*
G01X1462058Y13506D02*
Y12014D01*
G01X1463008Y13554D02*
Y12108D01*
G01X1452798Y13496D02*
Y10840D01*
G01X1453748Y13612D02*
Y10446D01*
G01X1452798Y10840D02*
X1452016Y10058D01*
G01X1453748Y10446D02*
X1452966Y9664D01*
G01X1452016Y10058D02*
Y6039D01*
G01X1452966Y9664D02*
Y6039D01*
G01X1444111Y13554D02*
Y12108D01*
G01X1443161Y13506D02*
Y12014D01*
G01X1433618Y13576D02*
Y11819D01*
G01X1434568Y13612D02*
Y11425D01*
G01X1433618Y11819D02*
X1432950Y11151D01*
G01X1434568Y11425D02*
X1433900Y10757D01*
G01X1432950Y11151D02*
Y8632D01*
G01X1433900Y10757D02*
Y8700D01*
G01X1424263Y13506D02*
Y12014D01*
G01X1425213Y13554D02*
Y12108D01*
G01X1463008Y13554D02*
Y12108D01*
G01X1462058Y13506D02*
Y12014D01*
G01X1453748Y13612D02*
Y10446D01*
G01X1452798Y13496D02*
Y10840D01*
G01X1453748Y10446D02*
X1452966Y9664D01*
G01X1452798Y10840D02*
X1452016Y10058D01*
G01X1452966Y9664D02*
Y6039D01*
G01X1452016Y10058D02*
Y6039D01*
G01X1443161Y13506D02*
Y12014D01*
G01X1444111Y13554D02*
Y12108D01*
G01X1434568Y13612D02*
Y11425D01*
G01X1433618Y13576D02*
Y11819D01*
G01X1434568Y11425D02*
X1433900Y10757D01*
G01X1433618Y11819D02*
X1432950Y11151D01*
G01X1433900Y10757D02*
Y8700D01*
G01X1432950Y11151D02*
Y8632D01*
G01X1425213Y13554D02*
Y12108D01*
G01X1424263Y13506D02*
Y12014D01*
G01X1428511Y44252D02*
Y49856D01*
G01X1427561Y44252D02*
Y49653D01*
G01X1428511Y49856D02*
X1421462Y65633D01*
G01X1427561Y49653D02*
X1427010Y50886D01*
G01X1428511Y49856D02*
X1421462Y65633D01*
G01X1426092Y52940D02*
X1425542Y54172D01*
G01X1428511Y49856D02*
X1421462Y65633D01*
G01X1424624Y56227D02*
X1420553Y65337D01*
G01X1421462Y65634D02*
X1418840Y77990D01*
G01X1420553Y65337D02*
X1417868Y77990D01*
G01X1418840D02*
X1420060Y83733D01*
G01X1417869Y77993D02*
X1419088Y83731D01*
G01X1420060Y83733D02*
X1418911Y89144D01*
G01X1419088Y83731D02*
X1417939Y89145D01*
G01X1418911Y89144D02*
X1419563Y92206D01*
G01D02*
X1420242Y95397D01*
G01X1417939Y89145D02*
X1419262Y95359D01*
G01X1440940Y68045D02*
X1467899Y50201D01*
G01X1474607Y46902D02*
X1441671Y68701D01*
G01X1439630Y70585D02*
X1440940Y68045D01*
G01X1441671Y68701D02*
X1440533Y70907D01*
G01X1438058Y77988D02*
X1439630Y70585D01*
G01X1440533Y70907D02*
X1439030Y77988D01*
G01X1439279Y83732D02*
X1438058Y77988D01*
G01X1439030D02*
X1440251Y83732D01*
G01X1438130Y89143D02*
X1439279Y83732D01*
G01X1440251D02*
X1439102Y89143D01*
G01X1439622Y96166D02*
X1438130Y89143D01*
G01X1439102D02*
X1440602Y96205D01*
G01X1435067Y89157D02*
X1436529Y96042D01*
G01X1435549Y96003D02*
X1434095Y89157D01*
G01X1436216Y83751D02*
X1435067Y89157D01*
G01X1434095D02*
X1435244Y83751D01*
G01X1434992Y77989D02*
X1436216Y83751D01*
G01X1435244D02*
X1434020Y77989D01*
G01X1436716Y69862D02*
X1434992Y77989D01*
G01X1434020D02*
X1435813Y69540D01*
G01X1438864Y65692D02*
X1436716Y69862D01*
G01X1435813Y69540D02*
X1438132Y65036D01*
G01X1463522Y49373D02*
X1438864Y65692D01*
G01X1438132Y65036D02*
X1458437Y51597D01*
G01X1463522Y49373D02*
X1438864Y65692D01*
G01X1458437Y51597D02*
X1458438D01*
G01X1463522Y49373D02*
X1438864Y65692D01*
G01X1460314Y50355D02*
X1462870Y48664D01*
G01X1466311Y45839D02*
X1463522Y49373D01*
G01X1462870Y48664D02*
X1465361Y45509D01*
G01X1431478Y95842D02*
X1430054Y89142D01*
G01X1432458Y95880D02*
X1431026Y89142D01*
G01X1430054D02*
X1431203Y83733D01*
G01X1431026Y89142D02*
X1432175Y83733D01*
G01X1431203D02*
X1429982Y77989D01*
G01X1432175Y83733D02*
X1430954Y77989D01*
G01X1429982D02*
X1431955Y68696D01*
G01X1430954Y77989D02*
X1432858Y69018D01*
G01X1431955Y68696D02*
X1435754Y61312D01*
G01X1432858Y69018D02*
X1436486Y61968D01*
G01X1435754Y61312D02*
X1446270Y54351D01*
G01X1448146Y53109D02*
X1449272Y52364D01*
G01X1451148Y51122D02*
X1453720Y49420D01*
G01X1436486Y61968D02*
X1454440Y50083D01*
G01X1453720Y49420D02*
X1455911Y45434D01*
G01X1454440Y50083D02*
X1456861Y45678D01*
G01X1455911Y45434D02*
Y44252D01*
G01X1456861Y45678D02*
Y44252D01*
G01X1446461D02*
Y47232D01*
G01X1447411Y44252D02*
Y47432D01*
G01X1446461Y47232D02*
X1445453Y49517D01*
G01X1447411Y47432D02*
X1446211Y50156D01*
G01X1445453Y49517D02*
X1441987Y51811D01*
G01X1440111Y53053D02*
X1438985Y53798D01*
G01X1437109Y55040D02*
X1435469Y56125D01*
G01X1446211Y50156D02*
X1436419Y56636D01*
G01X1437109Y55040D02*
X1435469Y56125D01*
G01Y56127D02*
X1433383Y57506D01*
G01X1436419Y56638D02*
X1434114Y58162D01*
G01X1433383Y57506D02*
X1428121Y67726D01*
G01X1434114Y58162D02*
X1429024Y68048D01*
G01X1428121Y67726D02*
X1425944Y77990D01*
G01X1429024Y68048D02*
X1426916Y77990D01*
G01X1425944D02*
X1427165Y83733D01*
G01X1426916Y77990D02*
X1428137Y83733D01*
G01X1427165D02*
X1426016Y89141D01*
G01X1428137Y83733D02*
X1426988Y89142D01*
G01X1426016Y89141D02*
X1427406Y95679D01*
G01X1426988Y89142D02*
X1428386Y95718D01*
G01X1422950Y89143D02*
X1424314Y95556D01*
G01X1423334Y95516D02*
X1421978Y89143D01*
G01X1424099Y83733D02*
X1422950Y89143D01*
G01X1421978D02*
X1423127Y83733D01*
G01X1422879Y77991D02*
X1424099Y83733D01*
G01X1423127D02*
X1421907Y77991D01*
G01X1425330Y66426D02*
X1422879Y77991D01*
G01X1421907D02*
X1424427Y66104D01*
G01X1430545Y56300D02*
X1425330Y66426D01*
G01X1424427Y66104D02*
X1429768Y55733D01*
G01X1436944Y49901D02*
X1430545Y56300D01*
G01X1429768Y55733D02*
X1431633Y53868D01*
G01X1436944Y49901D02*
X1430545Y56300D01*
G01X1432588Y52277D02*
X1433224Y52276D01*
G01X1436944Y49901D02*
X1430545Y56300D01*
G01X1433224Y52276D02*
X1436138Y49362D01*
G01X1437661Y48170D02*
X1436944Y49901D01*
G01X1436138Y49362D02*
X1436711Y47981D01*
G01X1437661Y44252D02*
Y48170D01*
G01X1436711Y47981D02*
Y44252D01*
G01X1427561D02*
Y49653D01*
G01X1428511Y44252D02*
Y49856D01*
G01X1427561Y49653D02*
X1427010Y50886D01*
G01X1426092Y52940D02*
X1425542Y54172D01*
G01X1424624Y56227D02*
X1420553Y65337D01*
G01X1428511Y49856D02*
X1421462Y65633D01*
G01X1420553Y65337D02*
X1417868Y77990D01*
G01X1421462Y65634D02*
X1418840Y77990D01*
G01X1417869Y77993D02*
X1419088Y83731D01*
G01X1418840Y77990D02*
X1420060Y83733D01*
G01X1419088Y83731D02*
X1417939Y89145D01*
G01X1420060Y83733D02*
X1418911Y89144D01*
G01X1417939Y89145D02*
X1419262Y95359D01*
G01X1418911Y89144D02*
X1419563Y92206D01*
G01X1417939Y89145D02*
X1419262Y95359D01*
G01X1419563Y92206D02*
X1420242Y95397D01*
G01X1463406Y73364D02*
X1463996Y71954D01*
G01X1464864Y69878D02*
X1465385Y68633D01*
G01X1469997Y60068D02*
X1464395Y73463D01*
G01X1464814Y80436D02*
X1463406Y73364D01*
G01X1464395Y73463D02*
X1465784Y80438D01*
G01X1463504Y86870D02*
X1464814Y80436D01*
G01X1465784Y80438D02*
X1464474Y86872D01*
G01X1464910Y93894D02*
X1463504Y86870D01*
G01X1464474Y86872D02*
X1465879Y93894D01*
G01X1459940Y118723D02*
X1464910Y93894D01*
G01X1460892Y94104D02*
X1457091Y113099D01*
G01X1457950Y113656D02*
X1461861Y94104D01*
G01X1459529Y87296D02*
X1460892Y94104D01*
G01X1461861D02*
X1460499Y87298D01*
G01X1460855Y80781D02*
X1459529Y87296D01*
G01X1460499Y87298D02*
X1461825Y80783D01*
G01X1459000Y71461D02*
X1460855Y80781D01*
G01X1461825Y80783D02*
X1459989Y71560D01*
G01X1464779Y57646D02*
X1461778Y64819D01*
G01X1460910Y66895D02*
X1460389Y68140D01*
G01X1459521Y70216D02*
X1459000Y71461D01*
G01X1459989Y71560D02*
X1465544Y58279D01*
G01X1465905Y56901D02*
X1464779Y57646D01*
G01X1439102Y89143D02*
X1440602Y96205D01*
G01X1439622Y96166D02*
X1438130Y89143D01*
G01X1440251Y83732D02*
X1439102Y89143D01*
G01X1438130D02*
X1439279Y83732D01*
G01X1439030Y77988D02*
X1440251Y83732D01*
G01X1439279D02*
X1438058Y77988D01*
G01X1440533Y70907D02*
X1439030Y77988D01*
G01X1438058D02*
X1439630Y70585D01*
G01X1441671Y68701D02*
X1440533Y70907D01*
G01X1439630Y70585D02*
X1440940Y68045D01*
G01X1474607Y46902D02*
X1441671Y68701D01*
G01X1440940Y68045D02*
X1467899Y50201D01*
G01X1474607Y46902D02*
X1441671Y68701D01*
G01X1474607Y46902D02*
X1441671Y68701D01*
G01X1462870Y48664D02*
X1465361Y45509D01*
G01X1466311Y45839D02*
X1463522Y49373D01*
G01X1438132Y65036D02*
X1458437Y51597D01*
G01D02*
X1458438D01*
G01X1460314Y50355D02*
X1462870Y48664D01*
G01X1463522Y49373D02*
X1438864Y65692D01*
G01X1435813Y69540D02*
X1438132Y65036D01*
G01X1438864Y65692D02*
X1436716Y69862D01*
G01X1434020Y77989D02*
X1435813Y69540D01*
G01X1436716Y69862D02*
X1434992Y77989D01*
G01X1435244Y83751D02*
X1434020Y77989D01*
G01X1434992D02*
X1436216Y83751D01*
G01X1434095Y89157D02*
X1435244Y83751D01*
G01X1436216D02*
X1435067Y89157D01*
G01X1435549Y96003D02*
X1434095Y89157D01*
G01X1435067D02*
X1436529Y96042D01*
G01X1432458Y95880D02*
X1431026Y89142D01*
G01X1431478Y95842D02*
X1430054Y89142D01*
G01X1431026D02*
X1432175Y83733D01*
G01X1430054Y89142D02*
X1431203Y83733D01*
G01X1432175D02*
X1430954Y77989D01*
G01X1431203Y83733D02*
X1429982Y77989D01*
G01X1430954D02*
X1432858Y69018D01*
G01X1429982Y77989D02*
X1431955Y68696D01*
G01X1432858Y69018D02*
X1436486Y61968D01*
G01X1431955Y68696D02*
X1435754Y61312D01*
G01X1436486Y61968D02*
X1454440Y50083D01*
G01X1435754Y61312D02*
X1446270Y54351D01*
G01X1436486Y61968D02*
X1454440Y50083D01*
G01X1448146Y53109D02*
X1449272Y52364D01*
G01X1436486Y61968D02*
X1454440Y50083D01*
G01X1451148Y51122D02*
X1453720Y49420D01*
G01X1454440Y50083D02*
X1456861Y45678D01*
G01X1453720Y49420D02*
X1455911Y45434D01*
G01X1456861Y45678D02*
Y44252D01*
G01X1455911Y45434D02*
Y44252D01*
G01X1447411D02*
Y47432D01*
G01X1446461Y44252D02*
Y47232D01*
G01X1447411Y47432D02*
X1446211Y50156D01*
G01X1446461Y47232D02*
X1445453Y49517D01*
G01X1446211Y50156D02*
X1436419Y56636D01*
G01X1445453Y49517D02*
X1441987Y51811D01*
G01X1446211Y50156D02*
X1436419Y56636D01*
G01X1440111Y53053D02*
X1438985Y53798D01*
G01X1446211Y50156D02*
X1436419Y56636D01*
G01Y56638D02*
X1434114Y58162D01*
G01X1437109Y55040D02*
X1435469Y56125D01*
G01X1436419Y56638D02*
X1434114Y58162D01*
G01X1435469Y56127D02*
X1433383Y57506D01*
G01X1434114Y58162D02*
X1429024Y68048D01*
G01X1433383Y57506D02*
X1428121Y67726D01*
G01X1429024Y68048D02*
X1426916Y77990D01*
G01X1428121Y67726D02*
X1425944Y77990D01*
G01X1426916D02*
X1428137Y83733D01*
G01X1425944Y77990D02*
X1427165Y83733D01*
G01X1428137D02*
X1426988Y89142D01*
G01X1427165Y83733D02*
X1426016Y89141D01*
G01X1426988Y89142D02*
X1428386Y95718D01*
G01X1426016Y89141D02*
X1427406Y95679D01*
G01X1436711Y47981D02*
Y44252D01*
G01X1437661D02*
Y48170D01*
G01X1436138Y49362D02*
X1436711Y47981D01*
G01X1437661Y48170D02*
X1436944Y49901D01*
G01X1429768Y55733D02*
X1431633Y53868D01*
G01X1432588Y52277D02*
X1433224Y52276D01*
G01D02*
X1436138Y49362D01*
G01X1436944Y49901D02*
X1430545Y56300D01*
G01X1424427Y66104D02*
X1429768Y55733D01*
G01X1430545Y56300D02*
X1425330Y66426D01*
G01X1421907Y77991D02*
X1424427Y66104D01*
G01X1425330Y66426D02*
X1422879Y77991D01*
G01X1423127Y83733D02*
X1421907Y77991D01*
G01X1422879D02*
X1424099Y83733D01*
G01X1421978Y89143D02*
X1423127Y83733D01*
G01X1424099D02*
X1422950Y89143D01*
G01X1423334Y95516D02*
X1421978Y89143D01*
G01X1422950D02*
X1424314Y95556D01*
G01X1459940Y118723D02*
X1464910Y93894D01*
G01X1464474Y86872D02*
X1465879Y93894D01*
G01X1464910D02*
X1463504Y86870D01*
G01X1465784Y80438D02*
X1464474Y86872D01*
G01X1463504Y86870D02*
X1464814Y80436D01*
G01X1464395Y73463D02*
X1465784Y80438D01*
G01X1464814Y80436D02*
X1463406Y73364D01*
G01X1469997Y60068D02*
X1464395Y73463D01*
G01X1463406Y73364D02*
X1463996Y71954D01*
G01X1469997Y60068D02*
X1464395Y73463D01*
G01X1464864Y69878D02*
X1465385Y68633D01*
G01X1469997Y60068D02*
X1464395Y73463D01*
G01X1469997Y60068D02*
X1464395Y73463D01*
G01X1465905Y56901D02*
X1464779Y57646D01*
G01X1459989Y71560D02*
X1465544Y58279D01*
G01X1464779Y57646D02*
X1461778Y64819D01*
G01X1459989Y71560D02*
X1465544Y58279D01*
G01X1460910Y66895D02*
X1460389Y68140D01*
G01X1459989Y71560D02*
X1465544Y58279D01*
G01X1459521Y70216D02*
X1459000Y71461D01*
G01X1461825Y80783D02*
X1459989Y71560D01*
G01X1459000Y71461D02*
X1460855Y80781D01*
G01X1460499Y87298D02*
X1461825Y80783D01*
G01X1460855Y80781D02*
X1459529Y87296D01*
G01X1461861Y94104D02*
X1460499Y87298D01*
G01X1459529Y87296D02*
X1460892Y94104D01*
G01X1457950Y113656D02*
X1461861Y94104D01*
G01X1460892D02*
X1457091Y113099D01*
G01X1427561Y44252D02*
Y49653D01*
G01X1428511Y44252D02*
Y49856D01*
G01X1427561Y49653D02*
X1427010Y50886D01*
G01X1426092Y52940D02*
X1425542Y54172D01*
G01X1424624Y56227D02*
X1420553Y65337D01*
G01X1428511Y49856D02*
X1421462Y65633D01*
G01X1420553Y65337D02*
X1417868Y77990D01*
G01X1421462Y65634D02*
X1418840Y77990D01*
G01X1417869Y77993D02*
X1419088Y83731D01*
G01X1418840Y77990D02*
X1420060Y83733D01*
G01X1419088Y83731D02*
X1417939Y89145D01*
G01X1420060Y83733D02*
X1418911Y89144D01*
G01X1417939Y89145D02*
X1419262Y95359D01*
G01X1418911Y89144D02*
X1419563Y92206D01*
G01X1417939Y89145D02*
X1419262Y95359D01*
G01X1419563Y92206D02*
X1420242Y95397D01*
G01X1431478Y95842D02*
X1430054Y89142D01*
G01X1432458Y95880D02*
X1431026Y89142D01*
G01X1430054D02*
X1431203Y83733D01*
G01X1431026Y89142D02*
X1432175Y83733D01*
G01X1431203D02*
X1429982Y77989D01*
G01X1432175Y83733D02*
X1430954Y77989D01*
G01X1429982D02*
X1431955Y68696D01*
G01X1430954Y77989D02*
X1432858Y69018D01*
G01X1431955Y68696D02*
X1435754Y61312D01*
G01X1432858Y69018D02*
X1436486Y61968D01*
G01X1435754Y61312D02*
X1446270Y54351D01*
G01X1448146Y53109D02*
X1449272Y52364D01*
G01X1451148Y51122D02*
X1453720Y49420D01*
G01X1436486Y61968D02*
X1454440Y50083D01*
G01X1453720Y49420D02*
X1455911Y45434D01*
G01X1454440Y50083D02*
X1456861Y45678D01*
G01X1455911Y45434D02*
Y44252D01*
G01X1456861Y45678D02*
Y44252D01*
G01X1460892Y94104D02*
X1457091Y113099D01*
G01X1457950Y113656D02*
X1461861Y94104D01*
G01X1459529Y87296D02*
X1460892Y94104D01*
G01X1461861D02*
X1460499Y87298D01*
G01X1460855Y80781D02*
X1459529Y87296D01*
G01X1460499Y87298D02*
X1461825Y80783D01*
G01X1459000Y71461D02*
X1460855Y80781D01*
G01X1461825Y80783D02*
X1459989Y71560D01*
G01X1464779Y57646D02*
X1461778Y64819D01*
G01X1460910Y66895D02*
X1460389Y68140D01*
G01X1459521Y70216D02*
X1459000Y71461D01*
G01X1459989Y71560D02*
X1465544Y58279D01*
G01X1465905Y56901D02*
X1464779Y57646D01*
G01X1462870Y48664D02*
X1465361Y45509D01*
G01X1466311Y45839D02*
X1463522Y49373D01*
G01X1438132Y65036D02*
X1458437Y51597D01*
G01D02*
X1458438D01*
G01X1460314Y50355D02*
X1462870Y48664D01*
G01X1463522Y49373D02*
X1438864Y65692D01*
G01X1435813Y69540D02*
X1438132Y65036D01*
G01X1438864Y65692D02*
X1436716Y69862D01*
G01X1434020Y77989D02*
X1435813Y69540D01*
G01X1436716Y69862D02*
X1434992Y77989D01*
G01X1435244Y83751D02*
X1434020Y77989D01*
G01X1434992D02*
X1436216Y83751D01*
G01X1434095Y89157D02*
X1435244Y83751D01*
G01X1436216D02*
X1435067Y89157D01*
G01X1435549Y96003D02*
X1434095Y89157D01*
G01X1435067D02*
X1436529Y96042D01*
G01X1432458Y95880D02*
X1431026Y89142D01*
G01X1431478Y95842D02*
X1430054Y89142D01*
G01X1431026D02*
X1432175Y83733D01*
G01X1430054Y89142D02*
X1431203Y83733D01*
G01X1432175D02*
X1430954Y77989D01*
G01X1431203Y83733D02*
X1429982Y77989D01*
G01X1430954D02*
X1432858Y69018D01*
G01X1429982Y77989D02*
X1431955Y68696D01*
G01X1432858Y69018D02*
X1436486Y61968D01*
G01X1431955Y68696D02*
X1435754Y61312D01*
G01X1436486Y61968D02*
X1454440Y50083D01*
G01X1435754Y61312D02*
X1446270Y54351D01*
G01X1436486Y61968D02*
X1454440Y50083D01*
G01X1448146Y53109D02*
X1449272Y52364D01*
G01X1436486Y61968D02*
X1454440Y50083D01*
G01X1451148Y51122D02*
X1453720Y49420D01*
G01X1454440Y50083D02*
X1456861Y45678D01*
G01X1453720Y49420D02*
X1455911Y45434D01*
G01X1456861Y45678D02*
Y44252D01*
G01X1455911Y45434D02*
Y44252D01*
G01X1465905Y56901D02*
X1464779Y57646D01*
G01X1459989Y71560D02*
X1465544Y58279D01*
G01X1464779Y57646D02*
X1461778Y64819D01*
G01X1459989Y71560D02*
X1465544Y58279D01*
G01X1460910Y66895D02*
X1460389Y68140D01*
G01X1459989Y71560D02*
X1465544Y58279D01*
G01X1459521Y70216D02*
X1459000Y71461D01*
G01X1461825Y80783D02*
X1459989Y71560D01*
G01X1459000Y71461D02*
X1460855Y80781D01*
G01X1460499Y87298D02*
X1461825Y80783D01*
G01X1460855Y80781D02*
X1459529Y87296D01*
G01X1461861Y94104D02*
X1460499Y87298D01*
G01X1459529Y87296D02*
X1460892Y94104D01*
G01X1457950Y113656D02*
X1461861Y94104D01*
G01X1460892D02*
X1457091Y113099D01*
G01X1440940Y68045D02*
X1467899Y50201D01*
G01X1474607Y46902D02*
X1441671Y68701D01*
G01X1439630Y70585D02*
X1440940Y68045D01*
G01X1441671Y68701D02*
X1440533Y70907D01*
G01X1438058Y77988D02*
X1439630Y70585D01*
G01X1440533Y70907D02*
X1439030Y77988D01*
G01X1439279Y83732D02*
X1438058Y77988D01*
G01X1439030D02*
X1440251Y83732D01*
G01X1438130Y89143D02*
X1439279Y83732D01*
G01X1440251D02*
X1439102Y89143D01*
G01X1439622Y96166D02*
X1438130Y89143D01*
G01X1439102D02*
X1440602Y96205D01*
G01X1435067Y89157D02*
X1436529Y96042D01*
G01X1435549Y96003D02*
X1434095Y89157D01*
G01X1436216Y83751D02*
X1435067Y89157D01*
G01X1434095D02*
X1435244Y83751D01*
G01X1434992Y77989D02*
X1436216Y83751D01*
G01X1435244D02*
X1434020Y77989D01*
G01X1436716Y69862D02*
X1434992Y77989D01*
G01X1434020D02*
X1435813Y69540D01*
G01X1438864Y65692D02*
X1436716Y69862D01*
G01X1435813Y69540D02*
X1438132Y65036D01*
G01X1463522Y49373D02*
X1438864Y65692D01*
G01X1438132Y65036D02*
X1458437Y51597D01*
G01X1463522Y49373D02*
X1438864Y65692D01*
G01X1458437Y51597D02*
X1458438D01*
G01X1463522Y49373D02*
X1438864Y65692D01*
G01X1460314Y50355D02*
X1462870Y48664D01*
G01X1466311Y45839D02*
X1463522Y49373D01*
G01X1462870Y48664D02*
X1465361Y45509D01*
G01X1446461Y44252D02*
Y47232D01*
G01X1447411Y44252D02*
Y47432D01*
G01X1446461Y47232D02*
X1445453Y49517D01*
G01X1447411Y47432D02*
X1446211Y50156D01*
G01X1445453Y49517D02*
X1441987Y51811D01*
G01X1440111Y53053D02*
X1438985Y53798D01*
G01X1437109Y55040D02*
X1435469Y56125D01*
G01X1446211Y50156D02*
X1436419Y56636D01*
G01X1437109Y55040D02*
X1435469Y56125D01*
G01Y56127D02*
X1433383Y57506D01*
G01X1436419Y56638D02*
X1434114Y58162D01*
G01X1433383Y57506D02*
X1428121Y67726D01*
G01X1434114Y58162D02*
X1429024Y68048D01*
G01X1428121Y67726D02*
X1425944Y77990D01*
G01X1429024Y68048D02*
X1426916Y77990D01*
G01X1425944D02*
X1427165Y83733D01*
G01X1426916Y77990D02*
X1428137Y83733D01*
G01X1427165D02*
X1426016Y89141D01*
G01X1428137Y83733D02*
X1426988Y89142D01*
G01X1426016Y89141D02*
X1427406Y95679D01*
G01X1426988Y89142D02*
X1428386Y95718D01*
G01X1422950Y89143D02*
X1424314Y95556D01*
G01X1423334Y95516D02*
X1421978Y89143D01*
G01X1424099Y83733D02*
X1422950Y89143D01*
G01X1421978D02*
X1423127Y83733D01*
G01X1422879Y77991D02*
X1424099Y83733D01*
G01X1423127D02*
X1421907Y77991D01*
G01X1425330Y66426D02*
X1422879Y77991D01*
G01X1421907D02*
X1424427Y66104D01*
G01X1430545Y56300D02*
X1425330Y66426D01*
G01X1424427Y66104D02*
X1429768Y55733D01*
G01X1436944Y49901D02*
X1430545Y56300D01*
G01X1429768Y55733D02*
X1431633Y53868D01*
G01X1436944Y49901D02*
X1430545Y56300D01*
G01X1432588Y52277D02*
X1433224Y52276D01*
G01X1436944Y49901D02*
X1430545Y56300D01*
G01X1433224Y52276D02*
X1436138Y49362D01*
G01X1437661Y48170D02*
X1436944Y49901D01*
G01X1436138Y49362D02*
X1436711Y47981D01*
G01X1437661Y44252D02*
Y48170D01*
G01X1436711Y47981D02*
Y44252D01*
G01X1439102Y89143D02*
X1440602Y96205D01*
G01X1439622Y96166D02*
X1438130Y89143D01*
G01X1440251Y83732D02*
X1439102Y89143D01*
G01X1438130D02*
X1439279Y83732D01*
G01X1439030Y77988D02*
X1440251Y83732D01*
G01X1439279D02*
X1438058Y77988D01*
G01X1440533Y70907D02*
X1439030Y77988D01*
G01X1438058D02*
X1439630Y70585D01*
G01X1441671Y68701D02*
X1440533Y70907D01*
G01X1439630Y70585D02*
X1440940Y68045D01*
G01X1474607Y46902D02*
X1441671Y68701D01*
G01X1440940Y68045D02*
X1467899Y50201D01*
G01X1474607Y46902D02*
X1441671Y68701D01*
G01X1474607Y46902D02*
X1441671Y68701D01*
G01X1447411Y44252D02*
Y47432D01*
G01X1446461Y44252D02*
Y47232D01*
G01X1447411Y47432D02*
X1446211Y50156D01*
G01X1446461Y47232D02*
X1445453Y49517D01*
G01X1446211Y50156D02*
X1436419Y56636D01*
G01X1445453Y49517D02*
X1441987Y51811D01*
G01X1446211Y50156D02*
X1436419Y56636D01*
G01X1440111Y53053D02*
X1438985Y53798D01*
G01X1446211Y50156D02*
X1436419Y56636D01*
G01Y56638D02*
X1434114Y58162D01*
G01X1437109Y55040D02*
X1435469Y56125D01*
G01X1436419Y56638D02*
X1434114Y58162D01*
G01X1435469Y56127D02*
X1433383Y57506D01*
G01X1434114Y58162D02*
X1429024Y68048D01*
G01X1433383Y57506D02*
X1428121Y67726D01*
G01X1429024Y68048D02*
X1426916Y77990D01*
G01X1428121Y67726D02*
X1425944Y77990D01*
G01X1426916D02*
X1428137Y83733D01*
G01X1425944Y77990D02*
X1427165Y83733D01*
G01X1428137D02*
X1426988Y89142D01*
G01X1427165Y83733D02*
X1426016Y89141D01*
G01X1426988Y89142D02*
X1428386Y95718D01*
G01X1426016Y89141D02*
X1427406Y95679D01*
G01X1436711Y47981D02*
Y44252D01*
G01X1437661D02*
Y48170D01*
G01X1436138Y49362D02*
X1436711Y47981D01*
G01X1437661Y48170D02*
X1436944Y49901D01*
G01X1429768Y55733D02*
X1431633Y53868D01*
G01X1432588Y52277D02*
X1433224Y52276D01*
G01D02*
X1436138Y49362D01*
G01X1436944Y49901D02*
X1430545Y56300D01*
G01X1424427Y66104D02*
X1429768Y55733D01*
G01X1430545Y56300D02*
X1425330Y66426D01*
G01X1421907Y77991D02*
X1424427Y66104D01*
G01X1425330Y66426D02*
X1422879Y77991D01*
G01X1423127Y83733D02*
X1421907Y77991D01*
G01X1422879D02*
X1424099Y83733D01*
G01X1421978Y89143D02*
X1423127Y83733D01*
G01X1424099D02*
X1422950Y89143D01*
G01X1423334Y95516D02*
X1421978Y89143D01*
G01X1422950D02*
X1424314Y95556D01*
G01X1428511Y44252D02*
Y49856D01*
G01X1427561Y44252D02*
Y49653D01*
G01X1428511Y49856D02*
X1421462Y65633D01*
G01X1427561Y49653D02*
X1427010Y50886D01*
G01X1428511Y49856D02*
X1421462Y65633D01*
G01X1426092Y52940D02*
X1425542Y54172D01*
G01X1428511Y49856D02*
X1421462Y65633D01*
G01X1424624Y56227D02*
X1420553Y65337D01*
G01X1421462Y65634D02*
X1418840Y77990D01*
G01X1420553Y65337D02*
X1417868Y77990D01*
G01X1418840D02*
X1420060Y83733D01*
G01X1417869Y77993D02*
X1419088Y83731D01*
G01X1420060Y83733D02*
X1418911Y89144D01*
G01X1419088Y83731D02*
X1417939Y89145D01*
G01X1418911Y89144D02*
X1419563Y92206D01*
G01D02*
X1420242Y95397D01*
G01X1417939Y89145D02*
X1419262Y95359D01*
G01X1463406Y73364D02*
X1463996Y71954D01*
G01X1464864Y69878D02*
X1465385Y68633D01*
G01X1469997Y60068D02*
X1464395Y73463D01*
G01X1464814Y80436D02*
X1463406Y73364D01*
G01X1464395Y73463D02*
X1465784Y80438D01*
G01X1463504Y86870D02*
X1464814Y80436D01*
G01X1465784Y80438D02*
X1464474Y86872D01*
G01X1464910Y93894D02*
X1463504Y86870D01*
G01X1464474Y86872D02*
X1465879Y93894D01*
G01X1459940Y118723D02*
X1464910Y93894D01*
G01X1459940Y118723D02*
X1464910Y93894D01*
G01X1464474Y86872D02*
X1465879Y93894D01*
G01X1464910D02*
X1463504Y86870D01*
G01X1465784Y80438D02*
X1464474Y86872D01*
G01X1463504Y86870D02*
X1464814Y80436D01*
G01X1464395Y73463D02*
X1465784Y80438D01*
G01X1464814Y80436D02*
X1463406Y73364D01*
G01X1469997Y60068D02*
X1464395Y73463D01*
G01X1463406Y73364D02*
X1463996Y71954D01*
G01X1469997Y60068D02*
X1464395Y73463D01*
G01X1464864Y69878D02*
X1465385Y68633D01*
G01X1469997Y60068D02*
X1464395Y73463D01*
G01X1469997Y60068D02*
X1464395Y73463D01*
G01X1455852Y35037D02*
Y38261D01*
G01X1456802Y34863D02*
Y38143D01*
G01X1446317Y34950D02*
Y38346D01*
G01X1447267Y34950D02*
Y38058D01*
G01X1437698Y35070D02*
Y38239D01*
G01X1436748Y34830D02*
Y38165D01*
G01X1427561Y35092D02*
Y38202D01*
G01X1428511Y34808D02*
Y38202D01*
G01X1456802Y34863D02*
Y38143D01*
G01X1455852Y35037D02*
Y38261D01*
G01X1447267Y34950D02*
Y38058D01*
G01X1446317Y34950D02*
Y38346D01*
G01X1436748Y34830D02*
Y38165D01*
G01X1437698Y35070D02*
Y38239D01*
G01X1428511Y34808D02*
Y38202D01*
G01X1427561Y35092D02*
Y38202D01*
G01X1408573Y34174D02*
Y42627D01*
G01X1409523Y34178D02*
Y42589D01*
G01Y34178D02*
Y42589D01*
G01X1408573Y34174D02*
Y42627D01*
G01Y34174D02*
Y42627D01*
G01X1409523Y34178D02*
Y42589D01*
G01Y34178D02*
Y42589D01*
G01X1408573Y34174D02*
Y42627D01*
G01X1420242Y95397D02*
X1417614Y104265D01*
G01X1419262Y95359D02*
X1411690Y120900D01*
G01X1417613Y104265D02*
X1404648Y148000D01*
G01D02*
X1407383Y159328D01*
G01X1423957Y149007D02*
X1439622Y96166D01*
G01X1440602Y96205D02*
X1424941Y149032D01*
G01X1426383Y159051D02*
X1423957Y149007D01*
G01X1424941Y149032D02*
X1427357Y159034D01*
G01X1420868Y148880D02*
X1423386Y159318D01*
G01X1422412Y159335D02*
X1419884Y148855D01*
G01X1436529Y96042D02*
X1420868Y148880D01*
G01X1419884Y148855D02*
X1435549Y96003D01*
G01X1418408Y159297D02*
X1415833Y148618D01*
G01X1419382Y159280D02*
X1416817Y148643D01*
G01X1415833Y148618D02*
X1431478Y95842D01*
G01X1416817Y148643D02*
X1432458Y95880D01*
G01X1427406Y95679D02*
X1411748Y148499D01*
G01X1428386Y95718D02*
X1412732Y148524D01*
G01X1411748Y148499D02*
X1414393Y159453D01*
G01X1412732Y148524D02*
X1415367Y159436D01*
G01X1408721Y148164D02*
X1411358Y159103D01*
G01X1410384Y159120D02*
X1407737Y148139D01*
G01X1424314Y95556D02*
X1408721Y148164D01*
G01X1407737Y148139D02*
X1423333Y95520D01*
G01X1419262Y95359D02*
X1411690Y120900D01*
G01X1420242Y95397D02*
X1417614Y104265D01*
G01X1417613D02*
X1404648Y148000D01*
G01D02*
X1407383Y159328D01*
G01X1464505Y159531D02*
X1466255Y150778D01*
G01X1467969Y119710D02*
X1463818Y132896D01*
G01X1468891Y119946D02*
X1464740Y133133D01*
G01X1463818Y132896D02*
X1460998Y146993D01*
G01X1464740Y133133D02*
X1461967Y146993D01*
G01X1460998D02*
X1461820Y151101D01*
G01X1461967Y146993D02*
X1462789Y151101D01*
G01X1461820D02*
X1460319Y158604D01*
G01X1462789Y151101D02*
X1461286Y158614D01*
G01X1464338Y118385D02*
X1469069Y94710D01*
G01X1470038D02*
X1465260Y118621D01*
G01X1459457Y133908D02*
X1464338Y118385D01*
G01X1465260Y118621D02*
X1460379Y134144D01*
G01X1456955Y146414D02*
X1459457Y133908D01*
G01X1460379Y134144D02*
X1457924Y146414D01*
G01X1457807Y150672D02*
X1456955Y146414D01*
G01X1457925D02*
X1458776Y150672D01*
G01X1456118Y159112D02*
X1457807Y150672D01*
G01X1458776D02*
X1457085Y159122D01*
G01X1465879Y93894D02*
X1460798Y119278D01*
G01X1436329Y135558D02*
X1459940Y118723D01*
G01X1460798Y119278D02*
X1437147Y136142D01*
G01X1432200Y149479D02*
X1436329Y135558D01*
G01X1437147Y136142D02*
X1433184Y149504D01*
G01X1434564Y159269D02*
X1432200Y149479D01*
G01X1433184Y149504D02*
X1435538Y159251D01*
G01X1428043Y149318D02*
X1430568Y159774D01*
G01X1431542Y159756D02*
X1429027Y149343D01*
G01X1433849Y129665D02*
X1428043Y149318D01*
G01X1429027Y149343D02*
X1434668Y130249D01*
G01X1457091Y113099D02*
X1433849Y129665D01*
G01X1434668Y130249D02*
X1457950Y113656D01*
G01X1424941Y149032D02*
X1427357Y159034D01*
G01X1426383Y159051D02*
X1423957Y149007D01*
G01X1440602Y96205D02*
X1424941Y149032D01*
G01X1423957Y149007D02*
X1439622Y96166D01*
G01X1419884Y148855D02*
X1435549Y96003D01*
G01X1436529Y96042D02*
X1420868Y148880D01*
G01X1422412Y159335D02*
X1419884Y148855D01*
G01X1420868Y148880D02*
X1423386Y159318D01*
G01X1419382Y159280D02*
X1416817Y148643D01*
G01X1418408Y159297D02*
X1415833Y148618D01*
G01X1416817Y148643D02*
X1432458Y95880D01*
G01X1415833Y148618D02*
X1431478Y95842D01*
G01X1428386Y95718D02*
X1412732Y148524D01*
G01X1427406Y95679D02*
X1411748Y148499D01*
G01X1412732Y148524D02*
X1415367Y159436D01*
G01X1411748Y148499D02*
X1414393Y159453D01*
G01X1407737Y148139D02*
X1423333Y95520D01*
G01X1424314Y95556D02*
X1408721Y148164D01*
G01X1410384Y159120D02*
X1407737Y148139D01*
G01X1408721Y148164D02*
X1411358Y159103D01*
G01X1464505Y159531D02*
X1466255Y150778D01*
G01X1468891Y119946D02*
X1464740Y133133D01*
G01X1467969Y119710D02*
X1463818Y132896D01*
G01X1464740Y133133D02*
X1461967Y146993D01*
G01X1463818Y132896D02*
X1460998Y146993D01*
G01X1461967D02*
X1462789Y151101D01*
G01X1460998Y146993D02*
X1461820Y151101D01*
G01X1462789D02*
X1461286Y158614D01*
G01X1461820Y151101D02*
X1460319Y158604D01*
G01X1458776Y150672D02*
X1457085Y159122D01*
G01X1456118Y159112D02*
X1457807Y150672D01*
G01X1457925Y146414D02*
X1458776Y150672D01*
G01X1457807D02*
X1456955Y146414D01*
G01X1460379Y134144D02*
X1457924Y146414D01*
G01X1456955D02*
X1459457Y133908D01*
G01X1465260Y118621D02*
X1460379Y134144D01*
G01X1459457Y133908D02*
X1464338Y118385D01*
G01X1470038Y94710D02*
X1465260Y118621D01*
G01X1464338Y118385D02*
X1469069Y94710D01*
G01X1433184Y149504D02*
X1435538Y159251D01*
G01X1434564Y159269D02*
X1432200Y149479D01*
G01X1437147Y136142D02*
X1433184Y149504D01*
G01X1432200Y149479D02*
X1436329Y135558D01*
G01X1460798Y119278D02*
X1437147Y136142D01*
G01X1436329Y135558D02*
X1459940Y118723D01*
G01X1465879Y93894D02*
X1460798Y119278D01*
G01X1434668Y130249D02*
X1457950Y113656D01*
G01X1457091Y113099D02*
X1433849Y129665D01*
G01X1429027Y149343D02*
X1434668Y130249D01*
G01X1433849Y129665D02*
X1428043Y149318D01*
G01X1431542Y159756D02*
X1429027Y149343D01*
G01X1428043Y149318D02*
X1430568Y159774D01*
G01X1419262Y95359D02*
X1411690Y120900D01*
G01X1420242Y95397D02*
X1417614Y104265D01*
G01X1417613D02*
X1404648Y148000D01*
G01D02*
X1407383Y159328D01*
G01X1418408Y159297D02*
X1415833Y148618D01*
G01X1419382Y159280D02*
X1416817Y148643D01*
G01X1415833Y148618D02*
X1431478Y95842D01*
G01X1416817Y148643D02*
X1432458Y95880D01*
G01X1464505Y159531D02*
X1466255Y150778D01*
G01X1467969Y119710D02*
X1463818Y132896D01*
G01X1468891Y119946D02*
X1464740Y133133D01*
G01X1463818Y132896D02*
X1460998Y146993D01*
G01X1464740Y133133D02*
X1461967Y146993D01*
G01X1460998D02*
X1461820Y151101D01*
G01X1461967Y146993D02*
X1462789Y151101D01*
G01X1461820D02*
X1460319Y158604D01*
G01X1462789Y151101D02*
X1461286Y158614D01*
G01X1464338Y118385D02*
X1469069Y94710D01*
G01X1470038D02*
X1465260Y118621D01*
G01X1459457Y133908D02*
X1464338Y118385D01*
G01X1465260Y118621D02*
X1460379Y134144D01*
G01X1456955Y146414D02*
X1459457Y133908D01*
G01X1460379Y134144D02*
X1457924Y146414D01*
G01X1457807Y150672D02*
X1456955Y146414D01*
G01X1457925D02*
X1458776Y150672D01*
G01X1456118Y159112D02*
X1457807Y150672D01*
G01X1458776D02*
X1457085Y159122D01*
G01X1428043Y149318D02*
X1430568Y159774D01*
G01X1431542Y159756D02*
X1429027Y149343D01*
G01X1433849Y129665D02*
X1428043Y149318D01*
G01X1429027Y149343D02*
X1434668Y130249D01*
G01X1457091Y113099D02*
X1433849Y129665D01*
G01X1434668Y130249D02*
X1457950Y113656D01*
G01X1419884Y148855D02*
X1435549Y96003D01*
G01X1436529Y96042D02*
X1420868Y148880D01*
G01X1422412Y159335D02*
X1419884Y148855D01*
G01X1420868Y148880D02*
X1423386Y159318D01*
G01X1419382Y159280D02*
X1416817Y148643D01*
G01X1418408Y159297D02*
X1415833Y148618D01*
G01X1416817Y148643D02*
X1432458Y95880D01*
G01X1415833Y148618D02*
X1431478Y95842D01*
G01X1464505Y159531D02*
X1466255Y150778D01*
G01X1468891Y119946D02*
X1464740Y133133D01*
G01X1467969Y119710D02*
X1463818Y132896D01*
G01X1464740Y133133D02*
X1461967Y146993D01*
G01X1463818Y132896D02*
X1460998Y146993D01*
G01X1461967D02*
X1462789Y151101D01*
G01X1460998Y146993D02*
X1461820Y151101D01*
G01X1462789D02*
X1461286Y158614D01*
G01X1461820Y151101D02*
X1460319Y158604D01*
G01X1458776Y150672D02*
X1457085Y159122D01*
G01X1456118Y159112D02*
X1457807Y150672D01*
G01X1457925Y146414D02*
X1458776Y150672D01*
G01X1457807D02*
X1456955Y146414D01*
G01X1460379Y134144D02*
X1457924Y146414D01*
G01X1456955D02*
X1459457Y133908D01*
G01X1465260Y118621D02*
X1460379Y134144D01*
G01X1459457Y133908D02*
X1464338Y118385D01*
G01X1470038Y94710D02*
X1465260Y118621D01*
G01X1464338Y118385D02*
X1469069Y94710D01*
G01X1434668Y130249D02*
X1457950Y113656D01*
G01X1457091Y113099D02*
X1433849Y129665D01*
G01X1429027Y149343D02*
X1434668Y130249D01*
G01X1433849Y129665D02*
X1428043Y149318D01*
G01X1431542Y159756D02*
X1429027Y149343D01*
G01X1428043Y149318D02*
X1430568Y159774D01*
G01X1423957Y149007D02*
X1439622Y96166D01*
G01X1440602Y96205D02*
X1424941Y149032D01*
G01X1426383Y159051D02*
X1423957Y149007D01*
G01X1424941Y149032D02*
X1427357Y159034D01*
G01X1420868Y148880D02*
X1423386Y159318D01*
G01X1422412Y159335D02*
X1419884Y148855D01*
G01X1436529Y96042D02*
X1420868Y148880D01*
G01X1419884Y148855D02*
X1435549Y96003D01*
G01X1427406Y95679D02*
X1411748Y148499D01*
G01X1428386Y95718D02*
X1412732Y148524D01*
G01X1411748Y148499D02*
X1414393Y159453D01*
G01X1412732Y148524D02*
X1415367Y159436D01*
G01X1408721Y148164D02*
X1411358Y159103D01*
G01X1410384Y159120D02*
X1407737Y148139D01*
G01X1424314Y95556D02*
X1408721Y148164D01*
G01X1407737Y148139D02*
X1423333Y95520D01*
G01X1424941Y149032D02*
X1427357Y159034D01*
G01X1426383Y159051D02*
X1423957Y149007D01*
G01X1440602Y96205D02*
X1424941Y149032D01*
G01X1423957Y149007D02*
X1439622Y96166D01*
G01X1428386Y95718D02*
X1412732Y148524D01*
G01X1427406Y95679D02*
X1411748Y148499D01*
G01X1412732Y148524D02*
X1415367Y159436D01*
G01X1411748Y148499D02*
X1414393Y159453D01*
G01X1407737Y148139D02*
X1423333Y95520D01*
G01X1424314Y95556D02*
X1408721Y148164D01*
G01X1410384Y159120D02*
X1407737Y148139D01*
G01X1408721Y148164D02*
X1411358Y159103D01*
G01X1420242Y95397D02*
X1417614Y104265D01*
G01X1419262Y95359D02*
X1411690Y120900D01*
G01X1417613Y104265D02*
X1404648Y148000D01*
G01D02*
X1407383Y159328D01*
G01X1465879Y93894D02*
X1460798Y119278D01*
G01X1436329Y135558D02*
X1459940Y118723D01*
G01X1460798Y119278D02*
X1437147Y136142D01*
G01X1432200Y149479D02*
X1436329Y135558D01*
G01X1437147Y136142D02*
X1433184Y149504D01*
G01X1434564Y159269D02*
X1432200Y149479D01*
G01X1433184Y149504D02*
X1435538Y159251D01*
G01X1433184Y149504D02*
X1435538Y159251D01*
G01X1434564Y159269D02*
X1432200Y149479D01*
G01X1437147Y136142D02*
X1433184Y149504D01*
G01X1432200Y149479D02*
X1436329Y135558D01*
G01X1460798Y119278D02*
X1437147Y136142D01*
G01X1436329Y135558D02*
X1459940Y118723D01*
G01X1465879Y93894D02*
X1460798Y119278D01*
G01X1407383Y159328D02*
X1405690Y167289D01*
G01X1406408Y159341D02*
X1404840Y166717D01*
G01X1422467Y178190D02*
X1426383Y159051D01*
G01X1427357Y159034D02*
X1423321Y178761D01*
G01X1423386Y159318D02*
X1419873Y176496D01*
G01X1419019Y175925D02*
X1422412Y159335D01*
G01X1415464Y173711D02*
X1418408Y159297D01*
G01X1416318Y174281D02*
X1419382Y159280D01*
G01X1414393Y159453D02*
X1411935Y171456D01*
G01X1415367Y159436D02*
X1412788Y172030D01*
G01X1411358Y159103D02*
X1409234Y169505D01*
G01X1408380Y168935D02*
X1410384Y159120D01*
G01X1406408Y159341D02*
X1404840Y166717D01*
G01X1407383Y159328D02*
X1405690Y167289D01*
G01X1471335Y163020D02*
X1463376Y186742D01*
G01X1472317Y163082D02*
X1464267Y187075D01*
G01X1463376Y186742D02*
X1461044Y192379D01*
G01X1461043D02*
X1460714Y193178D01*
G01X1464267Y187075D02*
X1461471Y193834D01*
G01X1460714Y193178D02*
X1458717Y194361D01*
G01X1461471Y193834D02*
X1459065Y195260D01*
G01X1458717Y194361D02*
X1455481Y195029D01*
G01X1459065Y195260D02*
X1455457Y196004D01*
G01X1455481Y195029D02*
X1448817Y193311D01*
G01X1455457Y196004D02*
X1448790Y194286D01*
G01X1448817Y193311D02*
X1444765Y194121D01*
G01X1448790Y194286D02*
X1445136Y195016D01*
G01X1444765Y194121D02*
X1441914Y196022D01*
G01X1445136Y195016D02*
X1442600Y196708D01*
G01X1441914Y196022D02*
X1436290Y204456D01*
G01X1442600Y196708D02*
X1436977Y205139D01*
G01X1436290Y204456D02*
X1417280Y217298D01*
G01X1436977Y205139D02*
X1418109Y217885D01*
G01X1417280Y217298D02*
X1413132Y233200D01*
G01X1418109Y217885D02*
X1414012Y233596D01*
G01X1465841Y167011D02*
X1464505Y159531D01*
G01X1460354Y183366D02*
X1465841Y167011D01*
G01X1466819Y167083D02*
X1461153Y183973D01*
G01X1452750Y188514D02*
X1460354Y183366D01*
G01X1461152Y183973D02*
X1453125Y189409D01*
G01X1443390Y190385D02*
X1452750Y188514D01*
G01X1453125Y189409D02*
X1443761Y191280D01*
G01X1439061Y193271D02*
X1443390Y190385D01*
G01X1443761Y191280D02*
X1439747Y193957D01*
G01X1433435Y201709D02*
X1439061Y193271D01*
G01X1439747Y193957D02*
X1434123Y202392D01*
G01X1413794Y215009D02*
X1433435Y201709D01*
G01X1434123Y202392D02*
X1414624Y215595D01*
G01X1413454Y216315D02*
X1413794Y215009D01*
G01X1414624Y215596D02*
X1410263Y232323D01*
G01X1460319Y158604D02*
X1461729Y166485D01*
G01X1461286Y158614D02*
X1462707Y166557D01*
G01X1461729Y166485D02*
X1456799Y181177D01*
G01X1462707Y166557D02*
X1457598Y181784D01*
G01X1456799Y181177D02*
X1451251Y184933D01*
G01X1457598Y181784D02*
X1451625Y185828D01*
G01X1451251Y184933D02*
X1441826Y186818D01*
G01X1451625Y185828D02*
X1442197Y187713D01*
G01X1441826Y186818D02*
X1436290Y190508D01*
G01X1442197Y187713D02*
X1436976Y191194D01*
G01X1436290Y190508D02*
X1435386Y191865D01*
G01X1434138Y193737D02*
X1433389Y194860D01*
G01X1432140Y196732D02*
X1430645Y198975D01*
G01X1436976Y191194D02*
X1431333Y199658D01*
G01X1430645Y198975D02*
X1429527Y199732D01*
G01D02*
X1428902Y199612D01*
G01X1457488Y166774D02*
X1456118Y159112D01*
G01X1457085Y159122D02*
X1458466Y166846D01*
G01X1453435Y178860D02*
X1457488Y166774D01*
G01X1458466Y166846D02*
X1454234Y179467D01*
G01X1449766Y181344D02*
X1453435Y178860D01*
G01X1454234Y179467D02*
X1450140Y182239D01*
G01X1433656Y184563D02*
X1449766Y181344D01*
G01X1450140Y182239D02*
X1434031Y185458D01*
G01X1428893Y187790D02*
X1431272Y186179D01*
G01D02*
X1433656Y184563D01*
G01X1434031Y185458D02*
X1429581Y188473D01*
G01X1419753Y201500D02*
X1428893Y187790D01*
G01X1429581Y188473D02*
X1420441Y202183D01*
G01X1409789Y208240D02*
X1419753Y201500D01*
G01X1420441Y202183D02*
X1410218Y209098D01*
G01X1429825Y182563D02*
X1434564Y159269D01*
G01X1435538Y159251D02*
X1430679Y183133D01*
G01X1430568Y159774D02*
X1426399Y180277D01*
G01X1427253Y180847D02*
X1431542Y159756D01*
G01X1427357Y159034D02*
X1423321Y178761D01*
G01X1422467Y178190D02*
X1426383Y159051D01*
G01X1419019Y175925D02*
X1422412Y159335D01*
G01X1423386Y159318D02*
X1419873Y176496D01*
G01X1416318Y174281D02*
X1419382Y159280D01*
G01X1415464Y173711D02*
X1418408Y159297D01*
G01X1415367Y159436D02*
X1412788Y172030D01*
G01X1414393Y159453D02*
X1411935Y171456D01*
G01X1408380Y168935D02*
X1410384Y159120D01*
G01X1411358Y159103D02*
X1409234Y169505D01*
G01X1472317Y163082D02*
X1464267Y187075D01*
G01X1471335Y163020D02*
X1463376Y186742D01*
G01X1464267Y187075D02*
X1461471Y193834D01*
G01X1463376Y186742D02*
X1461044Y192379D01*
G01X1464267Y187075D02*
X1461471Y193834D01*
G01X1461043Y192379D02*
X1460714Y193178D01*
G01X1461471Y193834D02*
X1459065Y195260D01*
G01X1460714Y193178D02*
X1458717Y194361D01*
G01X1459065Y195260D02*
X1455457Y196004D01*
G01X1458717Y194361D02*
X1455481Y195029D01*
G01X1455457Y196004D02*
X1448790Y194286D01*
G01X1455481Y195029D02*
X1448817Y193311D01*
G01X1448790Y194286D02*
X1445136Y195016D01*
G01X1448817Y193311D02*
X1444765Y194121D01*
G01X1445136Y195016D02*
X1442600Y196708D01*
G01X1444765Y194121D02*
X1441914Y196022D01*
G01X1442600Y196708D02*
X1436977Y205139D01*
G01X1441914Y196022D02*
X1436290Y204456D01*
G01X1436977Y205139D02*
X1418109Y217885D01*
G01X1436290Y204456D02*
X1417280Y217298D01*
G01X1418109Y217885D02*
X1414012Y233596D01*
G01X1417280Y217298D02*
X1413132Y233200D01*
G01X1414624Y215596D02*
X1410263Y232323D01*
G01X1414624Y215596D02*
X1410263Y232323D01*
G01X1414624Y215596D02*
X1410263Y232323D01*
G01X1414624Y215596D02*
X1410263Y232323D01*
G01X1414624Y215596D02*
X1410263Y232323D01*
G01X1413454Y216315D02*
X1413794Y215009D01*
G01X1434123Y202392D02*
X1414624Y215595D01*
G01X1413794Y215009D02*
X1433435Y201709D01*
G01X1439747Y193957D02*
X1434123Y202392D01*
G01X1433435Y201709D02*
X1439061Y193271D01*
G01X1443761Y191280D02*
X1439747Y193957D01*
G01X1439061Y193271D02*
X1443390Y190385D01*
G01X1453125Y189409D02*
X1443761Y191280D01*
G01X1443390Y190385D02*
X1452750Y188514D01*
G01X1461152Y183973D02*
X1453125Y189409D01*
G01X1452750Y188514D02*
X1460354Y183366D01*
G01X1466819Y167083D02*
X1461153Y183973D01*
G01X1460354Y183366D02*
X1465841Y167011D01*
G01D02*
X1464505Y159531D01*
G01X1461286Y158614D02*
X1462707Y166557D01*
G01X1460319Y158604D02*
X1461729Y166485D01*
G01X1462707Y166557D02*
X1457598Y181784D01*
G01X1461729Y166485D02*
X1456799Y181177D01*
G01X1457598Y181784D02*
X1451625Y185828D01*
G01X1456799Y181177D02*
X1451251Y184933D01*
G01X1451625Y185828D02*
X1442197Y187713D01*
G01X1451251Y184933D02*
X1441826Y186818D01*
G01X1442197Y187713D02*
X1436976Y191194D01*
G01X1441826Y186818D02*
X1436290Y190508D01*
G01X1436976Y191194D02*
X1431333Y199658D01*
G01X1436290Y190508D02*
X1435386Y191865D01*
G01X1436976Y191194D02*
X1431333Y199658D01*
G01X1434138Y193737D02*
X1433389Y194860D01*
G01X1436976Y191194D02*
X1431333Y199658D01*
G01X1432140Y196732D02*
X1430645Y198975D01*
G01D02*
X1429527Y199732D01*
G01D02*
X1428902Y199612D01*
G01X1420441Y202183D02*
X1410218Y209098D01*
G01X1409789Y208240D02*
X1419753Y201500D01*
G01X1429581Y188473D02*
X1420441Y202183D01*
G01X1419753Y201500D02*
X1428893Y187790D01*
G01X1434031Y185458D02*
X1429581Y188473D01*
G01X1428893Y187790D02*
X1431272Y186179D01*
G01X1434031Y185458D02*
X1429581Y188473D01*
G01X1431272Y186179D02*
X1433656Y184563D01*
G01X1450140Y182239D02*
X1434031Y185458D01*
G01X1433656Y184563D02*
X1449766Y181344D01*
G01X1454234Y179467D02*
X1450140Y182239D01*
G01X1449766Y181344D02*
X1453435Y178860D01*
G01X1458466Y166846D02*
X1454234Y179467D01*
G01X1453435Y178860D02*
X1457488Y166774D01*
G01X1457085Y159122D02*
X1458466Y166846D01*
G01X1457488Y166774D02*
X1456118Y159112D01*
G01X1435538Y159251D02*
X1430679Y183133D01*
G01X1429825Y182563D02*
X1434564Y159269D01*
G01X1427253Y180847D02*
X1431542Y159756D01*
G01X1430568Y159774D02*
X1426399Y180277D01*
G01X1436024Y229042D02*
X1476368Y201294D01*
G01X1436707Y229726D02*
X1476760Y202178D01*
G01X1434544Y226027D02*
X1474870Y198722D01*
G01X1433867Y225337D02*
X1474472Y197844D01*
G01X1472925Y194222D02*
X1430205Y223153D01*
G01X1473323Y195101D02*
X1430886Y223841D01*
G01X1428984Y218142D02*
X1439308Y211175D01*
G01X1429661Y218832D02*
X1439995Y211858D01*
G01X1439308Y211175D02*
X1446516Y200360D01*
G01X1439995Y211858D02*
X1447202Y201046D01*
G01X1446516Y200360D02*
X1448335Y199150D01*
G01X1447202Y201046D02*
X1448705Y200045D01*
G01X1448335Y199150D02*
X1452220Y198372D01*
G01X1448705Y200045D02*
X1452220Y199341D01*
G01Y198372D02*
X1456787Y199286D01*
G01X1452220Y199341D02*
X1456787Y200255D01*
G01Y199286D02*
X1459447Y198754D01*
G01X1456787Y200255D02*
X1459821Y199649D01*
G01X1459447Y198754D02*
X1471331Y190706D01*
G01X1459821Y199649D02*
X1471731Y191584D01*
G01X1436707Y229726D02*
X1476760Y202178D01*
G01X1436024Y229042D02*
X1476368Y201294D01*
G01X1433867Y225337D02*
X1474472Y197844D01*
G01X1434544Y226027D02*
X1474870Y198722D01*
G01X1473323Y195101D02*
X1430886Y223841D01*
G01X1472925Y194222D02*
X1430205Y223153D01*
G01X1429661Y218832D02*
X1439995Y211858D01*
G01X1428984Y218142D02*
X1439308Y211175D01*
G01X1439995Y211858D02*
X1447202Y201046D01*
G01X1439308Y211175D02*
X1446516Y200360D01*
G01X1447202Y201046D02*
X1448705Y200045D01*
G01X1446516Y200360D02*
X1448335Y199150D01*
G01X1448705Y200045D02*
X1452220Y199341D01*
G01X1448335Y199150D02*
X1452220Y198372D01*
G01Y199341D02*
X1456787Y200255D01*
G01X1452220Y198372D02*
X1456787Y199286D01*
G01Y200255D02*
X1459821Y199649D01*
G01X1456787Y199286D02*
X1459447Y198754D01*
G01X1459821Y199649D02*
X1471731Y191584D01*
G01X1459447Y198754D02*
X1471331Y190706D01*
G01X1406408Y159341D02*
X1404840Y166717D01*
G01X1407383Y159328D02*
X1405690Y167289D01*
G01X1415464Y173711D02*
X1418408Y159297D01*
G01X1416318Y174281D02*
X1419382Y159280D01*
G01X1465841Y167011D02*
X1464505Y159531D01*
G01X1460354Y183366D02*
X1465841Y167011D01*
G01X1466819Y167083D02*
X1461153Y183973D01*
G01X1452750Y188514D02*
X1460354Y183366D01*
G01X1461152Y183973D02*
X1453125Y189409D01*
G01X1443390Y190385D02*
X1452750Y188514D01*
G01X1453125Y189409D02*
X1443761Y191280D01*
G01X1439061Y193271D02*
X1443390Y190385D01*
G01X1443761Y191280D02*
X1439747Y193957D01*
G01X1433435Y201709D02*
X1439061Y193271D01*
G01X1439747Y193957D02*
X1434123Y202392D01*
G01X1413794Y215009D02*
X1433435Y201709D01*
G01X1434123Y202392D02*
X1414624Y215595D01*
G01X1413454Y216315D02*
X1413794Y215009D01*
G01X1414624Y215596D02*
X1410263Y232323D01*
G01X1460319Y158604D02*
X1461729Y166485D01*
G01X1461286Y158614D02*
X1462707Y166557D01*
G01X1461729Y166485D02*
X1456799Y181177D01*
G01X1462707Y166557D02*
X1457598Y181784D01*
G01X1456799Y181177D02*
X1451251Y184933D01*
G01X1457598Y181784D02*
X1451625Y185828D01*
G01X1451251Y184933D02*
X1441826Y186818D01*
G01X1451625Y185828D02*
X1442197Y187713D01*
G01X1441826Y186818D02*
X1436290Y190508D01*
G01X1442197Y187713D02*
X1436976Y191194D01*
G01X1436290Y190508D02*
X1435386Y191865D01*
G01X1434138Y193737D02*
X1433389Y194860D01*
G01X1432140Y196732D02*
X1430645Y198975D01*
G01X1436976Y191194D02*
X1431333Y199658D01*
G01X1430645Y198975D02*
X1429527Y199732D01*
G01D02*
X1428902Y199612D01*
G01X1457488Y166774D02*
X1456118Y159112D01*
G01X1457085Y159122D02*
X1458466Y166846D01*
G01X1453435Y178860D02*
X1457488Y166774D01*
G01X1458466Y166846D02*
X1454234Y179467D01*
G01X1449766Y181344D02*
X1453435Y178860D01*
G01X1454234Y179467D02*
X1450140Y182239D01*
G01X1433656Y184563D02*
X1449766Y181344D01*
G01X1450140Y182239D02*
X1434031Y185458D01*
G01X1428893Y187790D02*
X1431272Y186179D01*
G01D02*
X1433656Y184563D01*
G01X1434031Y185458D02*
X1429581Y188473D01*
G01X1419753Y201500D02*
X1428893Y187790D01*
G01X1429581Y188473D02*
X1420441Y202183D01*
G01X1409789Y208240D02*
X1419753Y201500D01*
G01X1420441Y202183D02*
X1410218Y209098D01*
G01X1430568Y159774D02*
X1426399Y180277D01*
G01X1427253Y180847D02*
X1431542Y159756D01*
G01X1419019Y175925D02*
X1422412Y159335D01*
G01X1423386Y159318D02*
X1419873Y176496D01*
G01X1416318Y174281D02*
X1419382Y159280D01*
G01X1415464Y173711D02*
X1418408Y159297D01*
G01X1414624Y215596D02*
X1410263Y232323D01*
G01X1414624Y215596D02*
X1410263Y232323D01*
G01X1414624Y215596D02*
X1410263Y232323D01*
G01X1414624Y215596D02*
X1410263Y232323D01*
G01X1414624Y215596D02*
X1410263Y232323D01*
G01X1413454Y216315D02*
X1413794Y215009D01*
G01X1434123Y202392D02*
X1414624Y215595D01*
G01X1413794Y215009D02*
X1433435Y201709D01*
G01X1439747Y193957D02*
X1434123Y202392D01*
G01X1433435Y201709D02*
X1439061Y193271D01*
G01X1443761Y191280D02*
X1439747Y193957D01*
G01X1439061Y193271D02*
X1443390Y190385D01*
G01X1453125Y189409D02*
X1443761Y191280D01*
G01X1443390Y190385D02*
X1452750Y188514D01*
G01X1461152Y183973D02*
X1453125Y189409D01*
G01X1452750Y188514D02*
X1460354Y183366D01*
G01X1466819Y167083D02*
X1461153Y183973D01*
G01X1460354Y183366D02*
X1465841Y167011D01*
G01D02*
X1464505Y159531D01*
G01X1461286Y158614D02*
X1462707Y166557D01*
G01X1460319Y158604D02*
X1461729Y166485D01*
G01X1462707Y166557D02*
X1457598Y181784D01*
G01X1461729Y166485D02*
X1456799Y181177D01*
G01X1457598Y181784D02*
X1451625Y185828D01*
G01X1456799Y181177D02*
X1451251Y184933D01*
G01X1451625Y185828D02*
X1442197Y187713D01*
G01X1451251Y184933D02*
X1441826Y186818D01*
G01X1442197Y187713D02*
X1436976Y191194D01*
G01X1441826Y186818D02*
X1436290Y190508D01*
G01X1436976Y191194D02*
X1431333Y199658D01*
G01X1436290Y190508D02*
X1435386Y191865D01*
G01X1436976Y191194D02*
X1431333Y199658D01*
G01X1434138Y193737D02*
X1433389Y194860D01*
G01X1436976Y191194D02*
X1431333Y199658D01*
G01X1432140Y196732D02*
X1430645Y198975D01*
G01D02*
X1429527Y199732D01*
G01D02*
X1428902Y199612D01*
G01X1420441Y202183D02*
X1410218Y209098D01*
G01X1409789Y208240D02*
X1419753Y201500D01*
G01X1429581Y188473D02*
X1420441Y202183D01*
G01X1419753Y201500D02*
X1428893Y187790D01*
G01X1434031Y185458D02*
X1429581Y188473D01*
G01X1428893Y187790D02*
X1431272Y186179D01*
G01X1434031Y185458D02*
X1429581Y188473D01*
G01X1431272Y186179D02*
X1433656Y184563D01*
G01X1450140Y182239D02*
X1434031Y185458D01*
G01X1433656Y184563D02*
X1449766Y181344D01*
G01X1454234Y179467D02*
X1450140Y182239D01*
G01X1449766Y181344D02*
X1453435Y178860D01*
G01X1458466Y166846D02*
X1454234Y179467D01*
G01X1453435Y178860D02*
X1457488Y166774D01*
G01X1457085Y159122D02*
X1458466Y166846D01*
G01X1457488Y166774D02*
X1456118Y159112D01*
G01X1427253Y180847D02*
X1431542Y159756D01*
G01X1430568Y159774D02*
X1426399Y180277D01*
G01X1436024Y229042D02*
X1476368Y201294D01*
G01X1436707Y229726D02*
X1476760Y202178D01*
G01X1434544Y226027D02*
X1474870Y198722D01*
G01X1433867Y225337D02*
X1474472Y197844D01*
G01X1472925Y194222D02*
X1430205Y223153D01*
G01X1473323Y195101D02*
X1430886Y223841D01*
G01X1428984Y218142D02*
X1439308Y211175D01*
G01X1429661Y218832D02*
X1439995Y211858D01*
G01X1439308Y211175D02*
X1446516Y200360D01*
G01X1439995Y211858D02*
X1447202Y201046D01*
G01X1446516Y200360D02*
X1448335Y199150D01*
G01X1447202Y201046D02*
X1448705Y200045D01*
G01X1448335Y199150D02*
X1452220Y198372D01*
G01X1448705Y200045D02*
X1452220Y199341D01*
G01Y198372D02*
X1456787Y199286D01*
G01X1452220Y199341D02*
X1456787Y200255D01*
G01Y199286D02*
X1459447Y198754D01*
G01X1456787Y200255D02*
X1459821Y199649D01*
G01X1459447Y198754D02*
X1471331Y190706D01*
G01X1459821Y199649D02*
X1471731Y191584D01*
G01X1471335Y163020D02*
X1463376Y186742D01*
G01X1472317Y163082D02*
X1464267Y187075D01*
G01X1463376Y186742D02*
X1461044Y192379D01*
G01X1461043D02*
X1460714Y193178D01*
G01X1464267Y187075D02*
X1461471Y193834D01*
G01X1460714Y193178D02*
X1458717Y194361D01*
G01X1461471Y193834D02*
X1459065Y195260D01*
G01X1458717Y194361D02*
X1455481Y195029D01*
G01X1459065Y195260D02*
X1455457Y196004D01*
G01X1455481Y195029D02*
X1448817Y193311D01*
G01X1455457Y196004D02*
X1448790Y194286D01*
G01X1448817Y193311D02*
X1444765Y194121D01*
G01X1448790Y194286D02*
X1445136Y195016D01*
G01X1444765Y194121D02*
X1441914Y196022D01*
G01X1445136Y195016D02*
X1442600Y196708D01*
G01X1441914Y196022D02*
X1436290Y204456D01*
G01X1442600Y196708D02*
X1436977Y205139D01*
G01X1436290Y204456D02*
X1417280Y217298D01*
G01X1436977Y205139D02*
X1418109Y217885D01*
G01X1417280Y217298D02*
X1413132Y233200D01*
G01X1418109Y217885D02*
X1414012Y233596D01*
G01X1436707Y229726D02*
X1476760Y202178D01*
G01X1436024Y229042D02*
X1476368Y201294D01*
G01X1433867Y225337D02*
X1474472Y197844D01*
G01X1434544Y226027D02*
X1474870Y198722D01*
G01X1473323Y195101D02*
X1430886Y223841D01*
G01X1472925Y194222D02*
X1430205Y223153D01*
G01X1429661Y218832D02*
X1439995Y211858D01*
G01X1428984Y218142D02*
X1439308Y211175D01*
G01X1439995Y211858D02*
X1447202Y201046D01*
G01X1439308Y211175D02*
X1446516Y200360D01*
G01X1447202Y201046D02*
X1448705Y200045D01*
G01X1446516Y200360D02*
X1448335Y199150D01*
G01X1448705Y200045D02*
X1452220Y199341D01*
G01X1448335Y199150D02*
X1452220Y198372D01*
G01Y199341D02*
X1456787Y200255D01*
G01X1452220Y198372D02*
X1456787Y199286D01*
G01Y200255D02*
X1459821Y199649D01*
G01X1456787Y199286D02*
X1459447Y198754D01*
G01X1459821Y199649D02*
X1471731Y191584D01*
G01X1459447Y198754D02*
X1471331Y190706D01*
G01X1472317Y163082D02*
X1464267Y187075D01*
G01X1471335Y163020D02*
X1463376Y186742D01*
G01X1464267Y187075D02*
X1461471Y193834D01*
G01X1463376Y186742D02*
X1461044Y192379D01*
G01X1464267Y187075D02*
X1461471Y193834D01*
G01X1461043Y192379D02*
X1460714Y193178D01*
G01X1461471Y193834D02*
X1459065Y195260D01*
G01X1460714Y193178D02*
X1458717Y194361D01*
G01X1459065Y195260D02*
X1455457Y196004D01*
G01X1458717Y194361D02*
X1455481Y195029D01*
G01X1455457Y196004D02*
X1448790Y194286D01*
G01X1455481Y195029D02*
X1448817Y193311D01*
G01X1448790Y194286D02*
X1445136Y195016D01*
G01X1448817Y193311D02*
X1444765Y194121D01*
G01X1445136Y195016D02*
X1442600Y196708D01*
G01X1444765Y194121D02*
X1441914Y196022D01*
G01X1442600Y196708D02*
X1436977Y205139D01*
G01X1441914Y196022D02*
X1436290Y204456D01*
G01X1436977Y205139D02*
X1418109Y217885D01*
G01X1436290Y204456D02*
X1417280Y217298D01*
G01X1418109Y217885D02*
X1414012Y233596D01*
G01X1417280Y217298D02*
X1413132Y233200D01*
G01X1422467Y178190D02*
X1426383Y159051D01*
G01X1427357Y159034D02*
X1423321Y178761D01*
G01X1423386Y159318D02*
X1419873Y176496D01*
G01X1419019Y175925D02*
X1422412Y159335D01*
G01X1414393Y159453D02*
X1411935Y171456D01*
G01X1415367Y159436D02*
X1412788Y172030D01*
G01X1411358Y159103D02*
X1409234Y169505D01*
G01X1408380Y168935D02*
X1410384Y159120D01*
G01X1427357Y159034D02*
X1423321Y178761D01*
G01X1422467Y178190D02*
X1426383Y159051D01*
G01X1415367Y159436D02*
X1412788Y172030D01*
G01X1414393Y159453D02*
X1411935Y171456D01*
G01X1408380Y168935D02*
X1410384Y159120D01*
G01X1411358Y159103D02*
X1409234Y169505D01*
G01X1407383Y159328D02*
X1405690Y167289D01*
G01X1406408Y159341D02*
X1404840Y166717D01*
G01X1429825Y182563D02*
X1434564Y159269D01*
G01X1435538Y159251D02*
X1430679Y183133D01*
G01X1435538Y159251D02*
X1430679Y183133D01*
G01X1429825Y182563D02*
X1434564Y159269D01*
G01X1413134Y233200D02*
X1407903Y241102D01*
G01X1414012Y233596D02*
X1408589Y241788D01*
G01X1409388Y231913D02*
X1410162Y228945D01*
G01X1410729Y226767D02*
X1411070Y225461D01*
G01X1411637Y223283D02*
X1411978Y221977D01*
G01X1412546Y219799D02*
X1412886Y218493D01*
G01X1405770Y236973D02*
X1409388Y231913D01*
G01X1410263Y232323D02*
X1406441Y237669D01*
G01X1414012Y233596D02*
X1408589Y241788D01*
G01X1413134Y233200D02*
X1407903Y241102D01*
G01X1410263Y232323D02*
X1406441Y237669D01*
G01X1405770Y236973D02*
X1409388Y231913D01*
G01D02*
X1410162Y228945D01*
G01X1410729Y226767D02*
X1411070Y225461D01*
G01X1411637Y223283D02*
X1411978Y221977D01*
G01X1412546Y219799D02*
X1412886Y218493D01*
G01X1413979Y263031D02*
X1423294Y256008D01*
G01X1414377Y263921D02*
X1424130Y256568D01*
G01X1423294Y256008D02*
X1426966Y241931D01*
G01X1424130Y256568D02*
X1427842Y242337D01*
G01X1426966Y241931D02*
X1436024Y229042D01*
G01X1427842Y242337D02*
X1436707Y229726D01*
G01X1412724Y260220D02*
X1420812Y254123D01*
G01X1412326Y259330D02*
X1419976Y253563D01*
G01X1420812Y254123D02*
X1424359Y240519D01*
G01X1419976Y253563D02*
X1423483Y240113D01*
G01X1424359Y240519D02*
X1434544Y226027D01*
G01X1423483Y240113D02*
X1433867Y225337D01*
G01X1430205Y223153D02*
X1420213Y237363D01*
G01X1430886Y223841D02*
X1421089Y237769D01*
G01X1420213Y237363D02*
X1416619Y251147D01*
G01X1421089Y237769D02*
X1417455Y251707D01*
G01X1416619Y251147D02*
X1410673Y255628D01*
G01X1417455Y251707D02*
X1411071Y256519D01*
G01X1405300Y250498D02*
X1409200Y249600D01*
G01X1405253Y251484D02*
X1409576Y250489D01*
G01X1409200Y249600D02*
X1413867Y246564D01*
G01X1409576Y250489D02*
X1414694Y247160D01*
G01X1413867Y246564D02*
X1416733Y235568D01*
G01X1414694Y247160D02*
X1417610Y235973D01*
G01X1416734Y235567D02*
X1416832Y235426D01*
G01D02*
X1428984Y218142D01*
G01X1417610Y235973D02*
X1429661Y218832D01*
G01X1414377Y263921D02*
X1424130Y256568D01*
G01X1413979Y263031D02*
X1423294Y256008D01*
G01X1424130Y256568D02*
X1427842Y242337D01*
G01X1423294Y256008D02*
X1426966Y241931D01*
G01X1427842Y242337D02*
X1436707Y229726D01*
G01X1426966Y241931D02*
X1436024Y229042D01*
G01X1412326Y259330D02*
X1419976Y253563D01*
G01X1412724Y260220D02*
X1420812Y254123D01*
G01X1419976Y253563D02*
X1423483Y240113D01*
G01X1420812Y254123D02*
X1424359Y240519D01*
G01X1423483Y240113D02*
X1433867Y225337D01*
G01X1424359Y240519D02*
X1434544Y226027D01*
G01X1430886Y223841D02*
X1421089Y237769D01*
G01X1430205Y223153D02*
X1420213Y237363D01*
G01X1421089Y237769D02*
X1417455Y251707D01*
G01X1420213Y237363D02*
X1416619Y251147D01*
G01X1417455Y251707D02*
X1411071Y256519D01*
G01X1416619Y251147D02*
X1410673Y255628D01*
G01X1405253Y251484D02*
X1409576Y250489D01*
G01X1405300Y250498D02*
X1409200Y249600D01*
G01X1409576Y250489D02*
X1414694Y247160D01*
G01X1409200Y249600D02*
X1413867Y246564D01*
G01X1414694Y247160D02*
X1417610Y235973D01*
G01X1413867Y246564D02*
X1416733Y235568D01*
G01X1417610Y235973D02*
X1429661Y218832D01*
G01X1416734Y235567D02*
X1416832Y235426D01*
G01X1417610Y235973D02*
X1429661Y218832D01*
G01X1416832Y235426D02*
X1428984Y218142D01*
G01X1409388Y231913D02*
X1410162Y228945D01*
G01X1410729Y226767D02*
X1411070Y225461D01*
G01X1411637Y223283D02*
X1411978Y221977D01*
G01X1412546Y219799D02*
X1412886Y218493D01*
G01X1405770Y236973D02*
X1409388Y231913D01*
G01X1410263Y232323D02*
X1406441Y237669D01*
G01X1410263Y232323D02*
X1406441Y237669D01*
G01X1405770Y236973D02*
X1409388Y231913D01*
G01D02*
X1410162Y228945D01*
G01X1410729Y226767D02*
X1411070Y225461D01*
G01X1411637Y223283D02*
X1411978Y221977D01*
G01X1412546Y219799D02*
X1412886Y218493D01*
G01X1413979Y263031D02*
X1423294Y256008D01*
G01X1414377Y263921D02*
X1424130Y256568D01*
G01X1423294Y256008D02*
X1426966Y241931D01*
G01X1424130Y256568D02*
X1427842Y242337D01*
G01X1426966Y241931D02*
X1436024Y229042D01*
G01X1427842Y242337D02*
X1436707Y229726D01*
G01X1412724Y260220D02*
X1420812Y254123D01*
G01X1412326Y259330D02*
X1419976Y253563D01*
G01X1420812Y254123D02*
X1424359Y240519D01*
G01X1419976Y253563D02*
X1423483Y240113D01*
G01X1424359Y240519D02*
X1434544Y226027D01*
G01X1423483Y240113D02*
X1433867Y225337D01*
G01X1430205Y223153D02*
X1420213Y237363D01*
G01X1430886Y223841D02*
X1421089Y237769D01*
G01X1420213Y237363D02*
X1416619Y251147D01*
G01X1421089Y237769D02*
X1417455Y251707D01*
G01X1416619Y251147D02*
X1410673Y255628D01*
G01X1417455Y251707D02*
X1411071Y256519D01*
G01X1405300Y250498D02*
X1409200Y249600D01*
G01X1405253Y251484D02*
X1409576Y250489D01*
G01X1409200Y249600D02*
X1413867Y246564D01*
G01X1409576Y250489D02*
X1414694Y247160D01*
G01X1413867Y246564D02*
X1416733Y235568D01*
G01X1414694Y247160D02*
X1417610Y235973D01*
G01X1416734Y235567D02*
X1416832Y235426D01*
G01D02*
X1428984Y218142D01*
G01X1417610Y235973D02*
X1429661Y218832D01*
G01X1413134Y233200D02*
X1407903Y241102D01*
G01X1414012Y233596D02*
X1408589Y241788D01*
G01X1414377Y263921D02*
X1424130Y256568D01*
G01X1413979Y263031D02*
X1423294Y256008D01*
G01X1424130Y256568D02*
X1427842Y242337D01*
G01X1423294Y256008D02*
X1426966Y241931D01*
G01X1427842Y242337D02*
X1436707Y229726D01*
G01X1426966Y241931D02*
X1436024Y229042D01*
G01X1412326Y259330D02*
X1419976Y253563D01*
G01X1412724Y260220D02*
X1420812Y254123D01*
G01X1419976Y253563D02*
X1423483Y240113D01*
G01X1420812Y254123D02*
X1424359Y240519D01*
G01X1423483Y240113D02*
X1433867Y225337D01*
G01X1424359Y240519D02*
X1434544Y226027D01*
G01X1430886Y223841D02*
X1421089Y237769D01*
G01X1430205Y223153D02*
X1420213Y237363D01*
G01X1421089Y237769D02*
X1417455Y251707D01*
G01X1420213Y237363D02*
X1416619Y251147D01*
G01X1417455Y251707D02*
X1411071Y256519D01*
G01X1416619Y251147D02*
X1410673Y255628D01*
G01X1405253Y251484D02*
X1409576Y250489D01*
G01X1405300Y250498D02*
X1409200Y249600D01*
G01X1409576Y250489D02*
X1414694Y247160D01*
G01X1409200Y249600D02*
X1413867Y246564D01*
G01X1414694Y247160D02*
X1417610Y235973D01*
G01X1413867Y246564D02*
X1416733Y235568D01*
G01X1417610Y235973D02*
X1429661Y218832D01*
G01X1416734Y235567D02*
X1416832Y235426D01*
G01X1417610Y235973D02*
X1429661Y218832D01*
G01X1416832Y235426D02*
X1428984Y218142D01*
G01X1414012Y233596D02*
X1408589Y241788D01*
G01X1413134Y233200D02*
X1407903Y241102D01*
G01X1403824Y336683D02*
Y325238D01*
G01D02*
X1406262Y322800D01*
G01X1405312Y308080D02*
Y312181D01*
G01Y314431D02*
Y315781D01*
G01Y318031D02*
Y322406D01*
G01X1406262Y322800D02*
Y308080D01*
G01X1417009Y321133D02*
Y308703D01*
G01X1416059Y308709D02*
Y320739D01*
G01X1414067Y324075D02*
X1417009Y321133D01*
G01X1416059Y320739D02*
X1413117Y323681D01*
G01X1414067Y339145D02*
Y324075D01*
G01X1413117Y323681D02*
Y338751D01*
G01X1404654Y348558D02*
X1414067Y339145D01*
G01X1406262Y322800D02*
Y308080D01*
G01X1405312D02*
Y312181D01*
G01X1406262Y322800D02*
Y308080D01*
G01X1405312Y314431D02*
Y315781D01*
G01X1406262Y322800D02*
Y308080D01*
G01X1405312Y318031D02*
Y322406D01*
G01X1403824Y325238D02*
X1406262Y322800D01*
G01X1403824Y336683D02*
Y325238D01*
G01X1404654Y348558D02*
X1414067Y339145D01*
G01X1413117Y323681D02*
Y338751D01*
G01X1414067Y339145D02*
Y324075D01*
G01X1416059Y320739D02*
X1413117Y323681D01*
G01X1414067Y324075D02*
X1417009Y321133D01*
G01X1416059Y308709D02*
Y320739D01*
G01X1417009Y321133D02*
Y308703D01*
G01X1403824Y336683D02*
Y325238D01*
G01D02*
X1406262Y322800D01*
G01X1405312Y308080D02*
Y312181D01*
G01Y314431D02*
Y315781D01*
G01Y318031D02*
Y322406D01*
G01X1406262Y322800D02*
Y308080D01*
G01X1417009Y321133D02*
Y308703D01*
G01X1416059Y308709D02*
Y320739D01*
G01X1414067Y324075D02*
X1417009Y321133D01*
G01X1416059Y320739D02*
X1413117Y323681D01*
G01X1414067Y339145D02*
Y324075D01*
G01X1413117Y323681D02*
Y338751D01*
G01X1404654Y348558D02*
X1414067Y339145D01*
G01X1406262Y322800D02*
Y308080D01*
G01X1405312D02*
Y312181D01*
G01X1406262Y322800D02*
Y308080D01*
G01X1405312Y314431D02*
Y315781D01*
G01X1406262Y322800D02*
Y308080D01*
G01X1405312Y318031D02*
Y322406D01*
G01X1403824Y325238D02*
X1406262Y322800D01*
G01X1403824Y336683D02*
Y325238D01*
G01X1404654Y348558D02*
X1414067Y339145D01*
G01X1413117Y323681D02*
Y338751D01*
G01X1414067Y339145D02*
Y324075D01*
G01X1416059Y320739D02*
X1413117Y323681D01*
G01X1414067Y324075D02*
X1417009Y321133D01*
G01X1416059Y308709D02*
Y320739D01*
G01X1417009Y321133D02*
Y308703D01*
G01X1404654Y351673D02*
Y348558D01*
G01X1403704Y348164D02*
Y351385D01*
G01Y348164D02*
Y351385D01*
G01X1404654Y351673D02*
Y348558D01*
G01Y351673D02*
Y348558D01*
G01X1403704Y348164D02*
Y351385D01*
G01Y348164D02*
Y351385D01*
G01X1404654Y351673D02*
Y348558D01*
G01X1440200Y459805D02*
X1437930D01*
G01D02*
X1434508D01*
G01X1440200Y458855D02*
X1434612D01*
G01X1434508Y459805D02*
X1424234Y457534D01*
G01X1434612Y458855D02*
X1430570Y457961D01*
G01X1434508Y459805D02*
X1424234Y457534D01*
G01X1430570Y457961D02*
X1424211Y456556D01*
G01D02*
X1413573Y459430D01*
G01X1432817Y463405D02*
X1425283Y461728D01*
G01X1433023Y462477D02*
X1425261Y460749D01*
G01X1425283Y461728D02*
X1412123Y465283D01*
G01X1425261Y460749D02*
X1421619Y461733D01*
G01X1425283Y461728D02*
X1412123Y465283D01*
G01X1440200Y458855D02*
X1434612D01*
G01X1440200Y459805D02*
X1437930D01*
G01X1440200Y458855D02*
X1434612D01*
G01X1437930Y459805D02*
X1434508D01*
G01X1434612Y458855D02*
X1430570Y457961D01*
G01D02*
X1424211Y456556D01*
G01X1434508Y459805D02*
X1424234Y457534D01*
G01X1424211Y456556D02*
X1413573Y459430D01*
G01X1433023Y462477D02*
X1425261Y460749D01*
G01X1432817Y463405D02*
X1425283Y461728D01*
G01X1425261Y460749D02*
X1421619Y461733D01*
G01X1425283Y461728D02*
X1412123Y465283D01*
G01X1449032Y440125D02*
X1447800D01*
G01X1441375D02*
X1447800D01*
G01X1442800Y439175D02*
X1449032D01*
G01X1441375Y440125D02*
X1447800D01*
G01X1441175Y439175D02*
X1442800D01*
G01X1449032Y440125D02*
X1447800D01*
G01X1441375D02*
X1447800D01*
G01X1442800Y439175D02*
X1449032D01*
G01X1441375Y440125D02*
X1447800D01*
G01X1441175Y439175D02*
X1442800D01*
G01X1448000Y451225D02*
X1441275D01*
G01X1443000Y450275D02*
X1441275D01*
G01X1448000Y451225D02*
X1441275D01*
G01X1449346D02*
X1448000D01*
G01X1449346Y450275D02*
X1443000D01*
G01X1448000Y451225D02*
X1441275D01*
G01X1443000Y450275D02*
X1441275D01*
G01X1448000Y451225D02*
X1441275D01*
G01X1449346D02*
X1448000D01*
G01X1449346Y450275D02*
X1443000D01*
G01X1442800Y439175D02*
X1449032D01*
G01Y440125D02*
X1447800D01*
G01X1442800Y439175D02*
X1449032D01*
G01X1441175D02*
X1442800D01*
G01X1441375Y440125D02*
X1447800D01*
G01X1442800Y439175D02*
X1449032D01*
G01Y440125D02*
X1447800D01*
G01X1442800Y439175D02*
X1449032D01*
G01X1441175D02*
X1442800D01*
G01X1441375Y440125D02*
X1447800D01*
G01X1443000Y450275D02*
X1441275D01*
G01X1449346D02*
X1443000D01*
G01X1448000Y451225D02*
X1441275D01*
G01X1449346Y450275D02*
X1443000D01*
G01X1449346Y451225D02*
X1448000D01*
G01X1443000Y450275D02*
X1441275D01*
G01X1449346D02*
X1443000D01*
G01X1448000Y451225D02*
X1441275D01*
G01X1449346Y450275D02*
X1443000D01*
G01X1449346Y451225D02*
X1448000D01*
G01X1440710Y410319D02*
X1441871D01*
G01X1440848Y411269D02*
X1441477D01*
G01X1441871Y410319D02*
X1442966Y411414D01*
G01X1441477Y411269D02*
X1442572Y412364D01*
G01X1442966Y411414D02*
X1449350D01*
G01X1442572Y412364D02*
X1444550D01*
G01X1442966Y411414D02*
X1449350D01*
G01D02*
X1451613D01*
G01D02*
X1452148Y411949D01*
G01X1444550Y412364D02*
X1451219D01*
G01X1451613Y411414D02*
X1452148Y411949D01*
G01D02*
X1452786D01*
G01X1451219Y412364D02*
X1451754Y412899D01*
G01X1452148Y411949D02*
X1452786D01*
G01X1451754Y412899D02*
X1452802D01*
G01X1440710Y410319D02*
X1441871D01*
G01X1440848Y411269D02*
X1441477D01*
G01X1441871Y410319D02*
X1442966Y411414D01*
G01X1441477Y411269D02*
X1442572Y412364D01*
G01X1442966Y411414D02*
X1449350D01*
G01X1442572Y412364D02*
X1444550D01*
G01X1442966Y411414D02*
X1449350D01*
G01D02*
X1451613D01*
G01D02*
X1452148Y411949D01*
G01X1444550Y412364D02*
X1451219D01*
G01X1451613Y411414D02*
X1452148Y411949D01*
G01D02*
X1452786D01*
G01X1451219Y412364D02*
X1451754Y412899D01*
G01X1452148Y411949D02*
X1452786D01*
G01X1451754Y412899D02*
X1452802D01*
G01X1440848Y411269D02*
X1441477D01*
G01X1440710Y410319D02*
X1441871D01*
G01X1441477Y411269D02*
X1442572Y412364D01*
G01X1441871Y410319D02*
X1442966Y411414D01*
G01X1442572Y412364D02*
X1444550D01*
G01D02*
X1451219D01*
G01X1442966Y411414D02*
X1449350D01*
G01X1444550Y412364D02*
X1451219D01*
G01X1449350Y411414D02*
X1451613D01*
G01X1444550Y412364D02*
X1451219D01*
G01D02*
X1451754Y412899D01*
G01X1451613Y411414D02*
X1452148Y411949D01*
G01X1451219Y412364D02*
X1451754Y412899D01*
G01D02*
X1452802D01*
G01X1452148Y411949D02*
X1452786D01*
G01X1440848Y411269D02*
X1441477D01*
G01X1440710Y410319D02*
X1441871D01*
G01X1441477Y411269D02*
X1442572Y412364D01*
G01X1441871Y410319D02*
X1442966Y411414D01*
G01X1442572Y412364D02*
X1444550D01*
G01D02*
X1451219D01*
G01X1442966Y411414D02*
X1449350D01*
G01X1444550Y412364D02*
X1451219D01*
G01X1449350Y411414D02*
X1451613D01*
G01X1444550Y412364D02*
X1451219D01*
G01D02*
X1451754Y412899D01*
G01X1451613Y411414D02*
X1452148Y411949D01*
G01X1451219Y412364D02*
X1451754Y412899D01*
G01D02*
X1452802D01*
G01X1452148Y411949D02*
X1452786D01*
G01X1440200Y459805D02*
X1437930D01*
G01D02*
X1434508D01*
G01X1440200Y458855D02*
X1434612D01*
G01X1434508Y459805D02*
X1424234Y457534D01*
G01X1434612Y458855D02*
X1430570Y457961D01*
G01X1434508Y459805D02*
X1424234Y457534D01*
G01X1430570Y457961D02*
X1424211Y456556D01*
G01D02*
X1413573Y459430D01*
G01X1432817Y463405D02*
X1425283Y461728D01*
G01X1433023Y462477D02*
X1425261Y460749D01*
G01X1425283Y461728D02*
X1412123Y465283D01*
G01X1425261Y460749D02*
X1421619Y461733D01*
G01X1425283Y461728D02*
X1412123Y465283D01*
G01X1440200Y458855D02*
X1434612D01*
G01X1440200Y459805D02*
X1437930D01*
G01X1440200Y458855D02*
X1434612D01*
G01X1437930Y459805D02*
X1434508D01*
G01X1434612Y458855D02*
X1430570Y457961D01*
G01D02*
X1424211Y456556D01*
G01X1434508Y459805D02*
X1424234Y457534D01*
G01X1424211Y456556D02*
X1413573Y459430D01*
G01X1433023Y462477D02*
X1425261Y460749D01*
G01X1432817Y463405D02*
X1425283Y461728D01*
G01X1425261Y460749D02*
X1421619Y461733D01*
G01X1425283Y461728D02*
X1412123Y465283D01*
G01X1440710Y410319D02*
X1441871D01*
G01X1440848Y411269D02*
X1441477D01*
G01X1441871Y410319D02*
X1442966Y411414D01*
G01X1441477Y411269D02*
X1442572Y412364D01*
G01X1442966Y411414D02*
X1449350D01*
G01X1442572Y412364D02*
X1444550D01*
G01X1442966Y411414D02*
X1449350D01*
G01D02*
X1451613D01*
G01D02*
X1452148Y411949D01*
G01X1444550Y412364D02*
X1451219D01*
G01X1451613Y411414D02*
X1452148Y411949D01*
G01D02*
X1452786D01*
G01X1451219Y412364D02*
X1451754Y412899D01*
G01X1452148Y411949D02*
X1452786D01*
G01X1451754Y412899D02*
X1452802D01*
G01X1440710Y410319D02*
X1441871D01*
G01X1440848Y411269D02*
X1441477D01*
G01X1441871Y410319D02*
X1442966Y411414D01*
G01X1441477Y411269D02*
X1442572Y412364D01*
G01X1442966Y411414D02*
X1449350D01*
G01X1442572Y412364D02*
X1444550D01*
G01X1442966Y411414D02*
X1449350D01*
G01D02*
X1451613D01*
G01D02*
X1452148Y411949D01*
G01X1444550Y412364D02*
X1451219D01*
G01X1451613Y411414D02*
X1452148Y411949D01*
G01D02*
X1452786D01*
G01X1451219Y412364D02*
X1451754Y412899D01*
G01X1452148Y411949D02*
X1452786D01*
G01X1451754Y412899D02*
X1452802D01*
G01X1440848Y411269D02*
X1441477D01*
G01X1440710Y410319D02*
X1441871D01*
G01X1441477Y411269D02*
X1442572Y412364D01*
G01X1441871Y410319D02*
X1442966Y411414D01*
G01X1442572Y412364D02*
X1444550D01*
G01D02*
X1451219D01*
G01X1442966Y411414D02*
X1449350D01*
G01X1444550Y412364D02*
X1451219D01*
G01X1449350Y411414D02*
X1451613D01*
G01X1444550Y412364D02*
X1451219D01*
G01D02*
X1451754Y412899D01*
G01X1451613Y411414D02*
X1452148Y411949D01*
G01X1451219Y412364D02*
X1451754Y412899D01*
G01D02*
X1452802D01*
G01X1452148Y411949D02*
X1452786D01*
G01X1440848Y411269D02*
X1441477D01*
G01X1440710Y410319D02*
X1441871D01*
G01X1441477Y411269D02*
X1442572Y412364D01*
G01X1441871Y410319D02*
X1442966Y411414D01*
G01X1442572Y412364D02*
X1444550D01*
G01D02*
X1451219D01*
G01X1442966Y411414D02*
X1449350D01*
G01X1444550Y412364D02*
X1451219D01*
G01X1449350Y411414D02*
X1451613D01*
G01X1444550Y412364D02*
X1451219D01*
G01D02*
X1451754Y412899D01*
G01X1451613Y411414D02*
X1452148Y411949D01*
G01X1451219Y412364D02*
X1451754Y412899D01*
G01D02*
X1452802D01*
G01X1452148Y411949D02*
X1452786D01*
G01X1423369Y469811D02*
X1425315Y470201D01*
G01X1423402Y470787D02*
X1425130Y471133D01*
G01X1423402Y470787D02*
X1425130Y471133D01*
G01X1423369Y469811D02*
X1425315Y470201D01*
G01X1428642Y486250D02*
X1426993D01*
G01X1418727D02*
X1426993D01*
G01X1428642Y485300D02*
X1421608D01*
G01X1409433Y486600D02*
X1416977D01*
G01X1409666Y485650D02*
X1416882D01*
G01X1416977Y486600D02*
X1418727Y486250D01*
G01X1416882Y485650D02*
X1418632Y485300D01*
G01X1418727Y486250D02*
X1426993D01*
G01X1418632Y485300D02*
X1421608D01*
G01X1408447Y505660D02*
X1407917Y505554D01*
G01X1408288Y504658D02*
X1408447Y504689D01*
G01X1418950Y507759D02*
X1408450Y505661D01*
G01X1408447Y505660D02*
X1407917Y505554D01*
G01X1408450Y504690D02*
X1418950Y506790D01*
G01X1427995Y505950D02*
X1418950Y507759D01*
G01Y506790D02*
X1427900Y505000D01*
G01X1444813Y505950D02*
X1440279D01*
G01X1438029D02*
X1427995D01*
G01X1427900Y505000D02*
X1444813D01*
G01X1428642Y485300D02*
X1421608D01*
G01X1428642Y486250D02*
X1426993D01*
G01X1409666Y485650D02*
X1416882D01*
G01X1409433Y486600D02*
X1416977D01*
G01X1416882Y485650D02*
X1418632Y485300D01*
G01X1416977Y486600D02*
X1418727Y486250D01*
G01X1428642Y485300D02*
X1421608D01*
G01X1418632D02*
X1421608D01*
G01X1418727Y486250D02*
X1426993D01*
G01X1427900Y505000D02*
X1444813D01*
G01Y505950D02*
X1440279D01*
G01X1427900Y505000D02*
X1444813D01*
G01X1438029Y505950D02*
X1427995D01*
G01X1418950Y506790D02*
X1427900Y505000D01*
G01X1427995Y505950D02*
X1418950Y507759D01*
G01X1408450Y504690D02*
X1418950Y506790D01*
G01Y507759D02*
X1408450Y505661D01*
G01X1408288Y504658D02*
X1408447Y504689D01*
G01X1408450Y504690D02*
X1418950Y506790D01*
G01X1408447Y505660D02*
X1407917Y505554D01*
G01X1408288Y504658D02*
X1408447Y504689D01*
G01X1409867Y465892D02*
X1412123Y465283D01*
G01X1432314Y467891D02*
X1430584Y467544D01*
G01X1423664Y466156D02*
X1430584Y467544D01*
G01X1432500Y466959D02*
X1423632Y465180D01*
G01X1414485Y468635D02*
X1422665Y466425D01*
G01D02*
X1423664Y466156D01*
G01X1423632Y465180D02*
X1417112Y466942D01*
G01X1423369Y469811D02*
X1425315Y470201D01*
G01X1423402Y470787D02*
X1425130Y471133D01*
G01X1432813Y497650D02*
X1427489D01*
G01X1432813Y496700D02*
X1427394D01*
G01X1427489Y497650D02*
X1417799Y499589D01*
G01X1427394Y496700D02*
X1417799Y498620D01*
G01Y499589D02*
X1413141Y498658D01*
G01X1417799Y498620D02*
X1413526Y497765D01*
G01X1413141Y498658D02*
X1404310Y492405D01*
G01X1435336Y501750D02*
X1429051D01*
G01X1435336Y500800D02*
X1428956D01*
G01X1429051Y501750D02*
X1418900Y503780D01*
G01X1428956Y500800D02*
X1418900Y502811D01*
G01Y503780D02*
X1409928Y501986D01*
G01X1418900Y502811D02*
X1410299Y501091D01*
G01X1409928Y501986D02*
X1406128Y499452D01*
G01X1432500Y466959D02*
X1423632Y465180D01*
G01X1432314Y467891D02*
X1430584Y467544D01*
G01X1423632Y465180D02*
X1417112Y466942D01*
G01X1414485Y468635D02*
X1422665Y466425D01*
G01X1423632Y465180D02*
X1417112Y466942D01*
G01X1422665Y466425D02*
X1423664Y466156D01*
G01X1432500Y466959D02*
X1423632Y465180D01*
G01X1423664Y466156D02*
X1430584Y467544D01*
G01X1432813Y496700D02*
X1427394D01*
G01X1432813Y497650D02*
X1427489D01*
G01X1427394Y496700D02*
X1417799Y498620D01*
G01X1427489Y497650D02*
X1417799Y499589D01*
G01Y498620D02*
X1413526Y497765D01*
G01X1417799Y499589D02*
X1413141Y498658D01*
G01D02*
X1404310Y492405D01*
G01X1435336Y500800D02*
X1428956D01*
G01X1435336Y501750D02*
X1429051D01*
G01X1428956Y500800D02*
X1418900Y502811D01*
G01X1429051Y501750D02*
X1418900Y503780D01*
G01Y502811D02*
X1410299Y501091D01*
G01X1418900Y503780D02*
X1409928Y501986D01*
G01D02*
X1406128Y499452D01*
G01X1435336Y500800D02*
X1428956D01*
G01X1435336Y501750D02*
X1429051D01*
G01X1428956Y500800D02*
X1418900Y502811D01*
G01X1429051Y501750D02*
X1418900Y503780D01*
G01Y502811D02*
X1410299Y501091D01*
G01X1418900Y503780D02*
X1409928Y501986D01*
G01D02*
X1406128Y499452D01*
G01X1409867Y465892D02*
X1412123Y465283D01*
G01X1432813Y497650D02*
X1427489D01*
G01X1432813Y496700D02*
X1427394D01*
G01X1427489Y497650D02*
X1417799Y499589D01*
G01X1427394Y496700D02*
X1417799Y498620D01*
G01Y499589D02*
X1413141Y498658D01*
G01X1417799Y498620D02*
X1413526Y497765D01*
G01X1413141Y498658D02*
X1404310Y492405D01*
G01X1435336Y501750D02*
X1429051D01*
G01X1435336Y500800D02*
X1428956D01*
G01X1429051Y501750D02*
X1418900Y503780D01*
G01X1428956Y500800D02*
X1418900Y502811D01*
G01Y503780D02*
X1409928Y501986D01*
G01X1418900Y502811D02*
X1410299Y501091D01*
G01X1409928Y501986D02*
X1406128Y499452D01*
G01X1408447Y505660D02*
X1407917Y505554D01*
G01X1408288Y504658D02*
X1408447Y504689D01*
G01X1418950Y507759D02*
X1408450Y505661D01*
G01X1408447Y505660D02*
X1407917Y505554D01*
G01X1408450Y504690D02*
X1418950Y506790D01*
G01X1427995Y505950D02*
X1418950Y507759D01*
G01Y506790D02*
X1427900Y505000D01*
G01X1444813Y505950D02*
X1440279D01*
G01X1438029D02*
X1427995D01*
G01X1427900Y505000D02*
X1444813D01*
G01X1423402Y470787D02*
X1425130Y471133D01*
G01X1423369Y469811D02*
X1425315Y470201D01*
G01X1427900Y505000D02*
X1444813D01*
G01Y505950D02*
X1440279D01*
G01X1427900Y505000D02*
X1444813D01*
G01X1438029Y505950D02*
X1427995D01*
G01X1418950Y506790D02*
X1427900Y505000D01*
G01X1427995Y505950D02*
X1418950Y507759D01*
G01X1408450Y504690D02*
X1418950Y506790D01*
G01Y507759D02*
X1408450Y505661D01*
G01X1408288Y504658D02*
X1408447Y504689D01*
G01X1408450Y504690D02*
X1418950Y506790D01*
G01X1408447Y505660D02*
X1407917Y505554D01*
G01X1408288Y504658D02*
X1408447Y504689D01*
G01X1409867Y465892D02*
X1412123Y465283D01*
G01X1409867Y465892D02*
X1412123Y465283D01*
G01X1432314Y467891D02*
X1430584Y467544D01*
G01X1423664Y466156D02*
X1430584Y467544D01*
G01X1432500Y466959D02*
X1423632Y465180D01*
G01X1414485Y468635D02*
X1422665Y466425D01*
G01D02*
X1423664Y466156D01*
G01X1423632Y465180D02*
X1417112Y466942D01*
G01X1428642Y486250D02*
X1426993D01*
G01X1418727D02*
X1426993D01*
G01X1428642Y485300D02*
X1421608D01*
G01X1409433Y486600D02*
X1416977D01*
G01X1409666Y485650D02*
X1416882D01*
G01X1416977Y486600D02*
X1418727Y486250D01*
G01X1416882Y485650D02*
X1418632Y485300D01*
G01X1418727Y486250D02*
X1426993D01*
G01X1418632Y485300D02*
X1421608D01*
G01X1432500Y466959D02*
X1423632Y465180D01*
G01X1432314Y467891D02*
X1430584Y467544D01*
G01X1423632Y465180D02*
X1417112Y466942D01*
G01X1414485Y468635D02*
X1422665Y466425D01*
G01X1423632Y465180D02*
X1417112Y466942D01*
G01X1422665Y466425D02*
X1423664Y466156D01*
G01X1432500Y466959D02*
X1423632Y465180D01*
G01X1423664Y466156D02*
X1430584Y467544D01*
G01X1428642Y485300D02*
X1421608D01*
G01X1428642Y486250D02*
X1426993D01*
G01X1409666Y485650D02*
X1416882D01*
G01X1409433Y486600D02*
X1416977D01*
G01X1416882Y485650D02*
X1418632Y485300D01*
G01X1416977Y486600D02*
X1418727Y486250D01*
G01X1428642Y485300D02*
X1421608D01*
G01X1418632D02*
X1421608D01*
G01X1418727Y486250D02*
X1426993D01*
G01X1432813Y496700D02*
X1427394D01*
G01X1432813Y497650D02*
X1427489D01*
G01X1427394Y496700D02*
X1417799Y498620D01*
G01X1427489Y497650D02*
X1417799Y499589D01*
G01Y498620D02*
X1413526Y497765D01*
G01X1417799Y499589D02*
X1413141Y498658D01*
G01D02*
X1404310Y492405D01*
G01X1471413Y13576D02*
Y6039D01*
G01X1472363Y13612D02*
Y6039D01*
G01X1490863Y7359D02*
Y10193D01*
G01X1491813Y7359D02*
Y10587D01*
G01X1490863Y10193D02*
X1490511Y10545D01*
G01X1491813Y10587D02*
X1491461Y10939D01*
G01X1490511Y10545D02*
Y13139D01*
G01X1491461Y10939D02*
Y13339D01*
G01X1480956Y13506D02*
Y12014D01*
G01X1481906Y13554D02*
Y12108D01*
G01X1472363Y13612D02*
Y6039D01*
G01X1471413Y13576D02*
Y6039D01*
G01X1491813Y7359D02*
Y10587D01*
G01X1490863Y7359D02*
Y10193D01*
G01X1491813Y10587D02*
X1491461Y10939D01*
G01X1490863Y10193D02*
X1490511Y10545D01*
G01X1491461Y10939D02*
Y13339D01*
G01X1490511Y10545D02*
Y13139D01*
G01X1481906Y13554D02*
Y12108D01*
G01X1480956Y13506D02*
Y12014D01*
G01X1471413Y13576D02*
Y6039D01*
G01X1472363Y13612D02*
Y6039D01*
G01X1490863Y7359D02*
Y10193D01*
G01X1491813Y7359D02*
Y10587D01*
G01X1490863Y10193D02*
X1490511Y10545D01*
G01X1491813Y10587D02*
X1491461Y10939D01*
G01X1490511Y10545D02*
Y13139D01*
G01X1491461Y10939D02*
Y13339D01*
G01X1480956Y13506D02*
Y12014D01*
G01X1481906Y13554D02*
Y12108D01*
G01X1472363Y13612D02*
Y6039D01*
G01X1471413Y13576D02*
Y6039D01*
G01X1491813Y7359D02*
Y10587D01*
G01X1490863Y7359D02*
Y10193D01*
G01X1491813Y10587D02*
X1491461Y10939D01*
G01X1490863Y10193D02*
X1490511Y10545D01*
G01X1491461Y10939D02*
Y13339D01*
G01X1490511Y10545D02*
Y13139D01*
G01X1481906Y13554D02*
Y12108D01*
G01X1480956Y13506D02*
Y12014D01*
G01X1474811Y45422D02*
Y44252D01*
G01X1475761D02*
Y45839D01*
G01X1474019Y46151D02*
X1474811Y45422D01*
G01X1475761Y45839D02*
X1474607Y46902D01*
G01X1469775Y48959D02*
X1470901Y48214D01*
G01X1472778Y46973D02*
X1474019Y46151D01*
G01X1466311Y44252D02*
Y45839D01*
G01X1465361Y45509D02*
Y44252D01*
G01X1544207Y61862D02*
X1526193Y65171D01*
G01X1558730Y60161D02*
X1526422Y66095D01*
G01X1526193Y65171D02*
X1499975Y73402D01*
G01X1526422Y66095D02*
X1500562Y74214D01*
G01X1499975Y73402D02*
X1496650Y78029D01*
G01X1500562Y74214D02*
X1497523Y78444D01*
G01X1496650Y78029D02*
X1494744Y85091D01*
G01X1497523Y78444D02*
X1495731Y85083D01*
G01X1494744Y85091D02*
X1496910Y92614D01*
G01X1495731Y85083D02*
X1497902Y92623D01*
G01X1496910Y92614D02*
X1493956Y102230D01*
G01X1497902Y92623D02*
X1494953Y102220D01*
G01X1481262Y65965D02*
X1562044Y51208D01*
G01X1562434Y52103D02*
X1481624Y66865D01*
G01X1478611Y67720D02*
X1481262Y65965D01*
G01X1481624Y66865D02*
X1479377Y68353D01*
G01X1475735Y74598D02*
X1478611Y67720D01*
G01X1479377Y68353D02*
X1476724Y74697D01*
G01X1476986Y80886D02*
X1475735Y74598D01*
G01X1476724Y74697D02*
X1477955Y80888D01*
G01X1475649Y87495D02*
X1476986Y80886D01*
G01X1477955Y80888D02*
X1476619Y87496D01*
G01X1477080Y94652D02*
X1475649Y87495D01*
G01X1476619Y87496D02*
X1478049Y94652D01*
G01X1553214Y48393D02*
X1479886Y62248D01*
G01X1557265Y48595D02*
X1480251Y63146D01*
G01X1479886Y62248D02*
X1475367Y65240D01*
G01X1480251Y63146D02*
X1476133Y65873D01*
G01X1475367Y65240D02*
X1471626Y74187D01*
G01X1476133Y65873D02*
X1472615Y74286D01*
G01X1471626Y74187D02*
X1472918Y80682D01*
G01X1472615Y74286D02*
X1473887Y80682D01*
G01X1472918D02*
X1471653Y87013D01*
G01X1473887Y80682D02*
X1472622Y87013D01*
G01X1471653D02*
X1473080Y94150D01*
G01X1472622Y87013D02*
X1474049Y94150D01*
G01X1473080D02*
X1467969Y119710D01*
G01X1474049Y94150D02*
X1468891Y119946D01*
G01X1478168Y58551D02*
X1479495Y58302D01*
G01X1481706Y57887D02*
X1483033Y57638D01*
G01X1485244Y57223D02*
X1486571Y56974D01*
G01X1488782Y56559D02*
X1490109Y56310D01*
G01X1492320Y55895D02*
X1548902Y45284D01*
G01X1549414Y46155D02*
X1478533Y59450D01*
G01X1472239Y62479D02*
X1478168Y58551D01*
G01X1478533Y59450D02*
X1473005Y63112D01*
G01X1467516Y73775D02*
X1472239Y62479D01*
G01X1473005Y63112D02*
X1468505Y73874D01*
G01X1468815Y80301D02*
X1467516Y73775D01*
G01X1468505Y73874D02*
X1469785Y80303D01*
G01X1467488Y86811D02*
X1468815Y80301D01*
G01X1469785Y80303D02*
X1468458Y86813D01*
G01X1469069Y94710D02*
X1467488Y86811D01*
G01X1468458Y86813D02*
X1470038Y94710D01*
G01X1493100Y45462D02*
Y44341D01*
G01X1494050Y44363D02*
Y45928D01*
G01X1489714Y48086D02*
X1493100Y45462D01*
G01X1494050Y45928D02*
X1490125Y48970D01*
G01X1484790Y49142D02*
X1489714Y48086D01*
G01X1490125Y48970D02*
X1485165Y50034D01*
G01X1469231Y59434D02*
X1484790Y49142D01*
G01X1485165Y50034D02*
X1469997Y60068D01*
G01X1466253Y66557D02*
X1466774Y65311D01*
G01X1467642Y63236D02*
X1469231Y59434D01*
G01X1484107Y44858D02*
X1473786Y51687D01*
G01X1471910Y52928D02*
X1470784Y53673D01*
G01X1468907Y54915D02*
X1467781Y55660D01*
G01X1465544Y58279D02*
X1484918Y45462D01*
G01X1484261Y44355D02*
X1484107Y44858D01*
G01X1484918Y45462D02*
X1485211Y44496D01*
G01X1484261Y44252D02*
Y44355D01*
G01X1485211Y44496D02*
Y44252D01*
G01X1469775Y48959D02*
X1470901Y48214D01*
G01X1472778Y46973D02*
X1474019Y46151D01*
G01X1475761Y45839D02*
X1474607Y46902D01*
G01X1474019Y46151D02*
X1474811Y45422D01*
G01X1475761Y44252D02*
Y45839D01*
G01X1474811Y45422D02*
Y44252D01*
G01X1465361Y45509D02*
Y44252D01*
G01X1466311D02*
Y45839D01*
G01X1558730Y60161D02*
X1526422Y66095D01*
G01X1558730Y60161D02*
X1526422Y66095D01*
G01X1558730Y60161D02*
X1526422Y66095D01*
G01X1558730Y60161D02*
X1526422Y66095D01*
G01X1558730Y60161D02*
X1526422Y66095D01*
G01X1544207Y61862D02*
X1526193Y65171D01*
G01X1526422Y66095D02*
X1500562Y74214D01*
G01X1526193Y65171D02*
X1499975Y73402D01*
G01X1500562Y74214D02*
X1497523Y78444D01*
G01X1499975Y73402D02*
X1496650Y78029D01*
G01X1497523Y78444D02*
X1495731Y85083D01*
G01X1496650Y78029D02*
X1494744Y85091D01*
G01X1495731Y85083D02*
X1497902Y92623D01*
G01X1494744Y85091D02*
X1496910Y92614D01*
G01X1497902Y92623D02*
X1494953Y102220D01*
G01X1496910Y92614D02*
X1493956Y102230D01*
G01X1476619Y87496D02*
X1478049Y94652D01*
G01X1477080D02*
X1475649Y87495D01*
G01X1477955Y80888D02*
X1476619Y87496D01*
G01X1475649Y87495D02*
X1476986Y80886D01*
G01X1476724Y74697D02*
X1477955Y80888D01*
G01X1476986Y80886D02*
X1475735Y74598D01*
G01X1479377Y68353D02*
X1476724Y74697D01*
G01X1475735Y74598D02*
X1478611Y67720D01*
G01X1481624Y66865D02*
X1479377Y68353D01*
G01X1478611Y67720D02*
X1481262Y65965D01*
G01X1562434Y52103D02*
X1481624Y66865D01*
G01X1481262Y65965D02*
X1562044Y51208D01*
G01X1557265Y48595D02*
X1480251Y63146D01*
G01X1557265Y48595D02*
X1480251Y63146D01*
G01X1553214Y48393D02*
X1479886Y62248D01*
G01X1480251Y63146D02*
X1476133Y65873D01*
G01X1479886Y62248D02*
X1475367Y65240D01*
G01X1476133Y65873D02*
X1472615Y74286D01*
G01X1475367Y65240D02*
X1471626Y74187D01*
G01X1472615Y74286D02*
X1473887Y80682D01*
G01X1471626Y74187D02*
X1472918Y80682D01*
G01X1473887D02*
X1472622Y87013D01*
G01X1472918Y80682D02*
X1471653Y87013D01*
G01X1472622D02*
X1474049Y94150D01*
G01X1471653Y87013D02*
X1473080Y94150D01*
G01X1474049D02*
X1468891Y119946D01*
G01X1473080Y94150D02*
X1467969Y119710D01*
G01X1468458Y86813D02*
X1470038Y94710D01*
G01X1469069D02*
X1467488Y86811D01*
G01X1469785Y80303D02*
X1468458Y86813D01*
G01X1467488Y86811D02*
X1468815Y80301D01*
G01X1468505Y73874D02*
X1469785Y80303D01*
G01X1468815Y80301D02*
X1467516Y73775D01*
G01X1473005Y63112D02*
X1468505Y73874D01*
G01X1467516Y73775D02*
X1472239Y62479D01*
G01X1478533Y59450D02*
X1473005Y63112D01*
G01X1472239Y62479D02*
X1478168Y58551D01*
G01X1549414Y46155D02*
X1478533Y59450D01*
G01X1478168Y58551D02*
X1479495Y58302D01*
G01X1549414Y46155D02*
X1478533Y59450D01*
G01X1481706Y57887D02*
X1483033Y57638D01*
G01X1549414Y46155D02*
X1478533Y59450D01*
G01X1485244Y57223D02*
X1486571Y56974D01*
G01X1549414Y46155D02*
X1478533Y59450D01*
G01X1488782Y56559D02*
X1490109Y56310D01*
G01X1549414Y46155D02*
X1478533Y59450D01*
G01X1492320Y55895D02*
X1548902Y45284D01*
G01X1466253Y66557D02*
X1466774Y65311D01*
G01X1467642Y63236D02*
X1469231Y59434D01*
G01X1485165Y50034D02*
X1469997Y60068D01*
G01X1469231Y59434D02*
X1484790Y49142D01*
G01X1490125Y48970D02*
X1485165Y50034D01*
G01X1484790Y49142D02*
X1489714Y48086D01*
G01X1494050Y45928D02*
X1490125Y48970D01*
G01X1489714Y48086D02*
X1493100Y45462D01*
G01X1494050Y44363D02*
Y45928D01*
G01X1493100Y45462D02*
Y44341D01*
G01X1485211Y44496D02*
Y44252D01*
G01X1484261D02*
Y44355D01*
G01X1484918Y45462D02*
X1485211Y44496D01*
G01X1484261Y44355D02*
X1484107Y44858D01*
G01X1465544Y58279D02*
X1484918Y45462D01*
G01X1484107Y44858D02*
X1473786Y51687D01*
G01X1465544Y58279D02*
X1484918Y45462D01*
G01X1471910Y52928D02*
X1470784Y53673D01*
G01X1465544Y58279D02*
X1484918Y45462D01*
G01X1468907Y54915D02*
X1467781Y55660D01*
G01X1465544Y58279D02*
X1484918Y45462D01*
G01X1519163Y97573D02*
X1523777Y74832D01*
G01X1520158Y97448D02*
X1524672Y75203D01*
G01X1523777Y74832D02*
X1526105Y71317D01*
G01X1524672Y75203D02*
X1526693Y72151D01*
G01X1526105Y71317D02*
X1527241Y71036D01*
G01X1526693Y72151D02*
X1541430Y68511D01*
G01X1520158Y97448D02*
X1524672Y75203D01*
G01X1519163Y97573D02*
X1523777Y74832D01*
G01X1524672Y75203D02*
X1526693Y72151D01*
G01X1523777Y74832D02*
X1526105Y71317D01*
G01X1526693Y72151D02*
X1541430Y68511D01*
G01X1526105Y71317D02*
X1527241Y71036D01*
G01X1526693Y72151D02*
X1541430Y68511D01*
G01X1526693Y72151D02*
X1541430Y68511D01*
G01X1526693Y72151D02*
X1541430Y68511D01*
G01X1526693Y72151D02*
X1541430Y68511D01*
G01X1481262Y65965D02*
X1562044Y51208D01*
G01X1562434Y52103D02*
X1481624Y66865D01*
G01X1478611Y67720D02*
X1481262Y65965D01*
G01X1481624Y66865D02*
X1479377Y68353D01*
G01X1475735Y74598D02*
X1478611Y67720D01*
G01X1479377Y68353D02*
X1476724Y74697D01*
G01X1476986Y80886D02*
X1475735Y74598D01*
G01X1476724Y74697D02*
X1477955Y80888D01*
G01X1475649Y87495D02*
X1476986Y80886D01*
G01X1477955Y80888D02*
X1476619Y87496D01*
G01X1477080Y94652D02*
X1475649Y87495D01*
G01X1476619Y87496D02*
X1478049Y94652D01*
G01X1553214Y48393D02*
X1479886Y62248D01*
G01X1557265Y48595D02*
X1480251Y63146D01*
G01X1479886Y62248D02*
X1475367Y65240D01*
G01X1480251Y63146D02*
X1476133Y65873D01*
G01X1475367Y65240D02*
X1471626Y74187D01*
G01X1476133Y65873D02*
X1472615Y74286D01*
G01X1471626Y74187D02*
X1472918Y80682D01*
G01X1472615Y74286D02*
X1473887Y80682D01*
G01X1472918D02*
X1471653Y87013D01*
G01X1473887Y80682D02*
X1472622Y87013D01*
G01X1471653D02*
X1473080Y94150D01*
G01X1472622Y87013D02*
X1474049Y94150D01*
G01X1473080D02*
X1467969Y119710D01*
G01X1474049Y94150D02*
X1468891Y119946D01*
G01X1478168Y58551D02*
X1479495Y58302D01*
G01X1481706Y57887D02*
X1483033Y57638D01*
G01X1485244Y57223D02*
X1486571Y56974D01*
G01X1488782Y56559D02*
X1490109Y56310D01*
G01X1492320Y55895D02*
X1548902Y45284D01*
G01X1549414Y46155D02*
X1478533Y59450D01*
G01X1472239Y62479D02*
X1478168Y58551D01*
G01X1478533Y59450D02*
X1473005Y63112D01*
G01X1467516Y73775D02*
X1472239Y62479D01*
G01X1473005Y63112D02*
X1468505Y73874D01*
G01X1468815Y80301D02*
X1467516Y73775D01*
G01X1468505Y73874D02*
X1469785Y80303D01*
G01X1467488Y86811D02*
X1468815Y80301D01*
G01X1469785Y80303D02*
X1468458Y86813D01*
G01X1469069Y94710D02*
X1467488Y86811D01*
G01X1468458Y86813D02*
X1470038Y94710D01*
G01X1484107Y44858D02*
X1473786Y51687D01*
G01X1471910Y52928D02*
X1470784Y53673D01*
G01X1468907Y54915D02*
X1467781Y55660D01*
G01X1465544Y58279D02*
X1484918Y45462D01*
G01X1484261Y44355D02*
X1484107Y44858D01*
G01X1484918Y45462D02*
X1485211Y44496D01*
G01X1484261Y44252D02*
Y44355D01*
G01X1485211Y44496D02*
Y44252D01*
G01X1465361Y45509D02*
Y44252D01*
G01X1466311D02*
Y45839D01*
G01X1476619Y87496D02*
X1478049Y94652D01*
G01X1477080D02*
X1475649Y87495D01*
G01X1477955Y80888D02*
X1476619Y87496D01*
G01X1475649Y87495D02*
X1476986Y80886D01*
G01X1476724Y74697D02*
X1477955Y80888D01*
G01X1476986Y80886D02*
X1475735Y74598D01*
G01X1479377Y68353D02*
X1476724Y74697D01*
G01X1475735Y74598D02*
X1478611Y67720D01*
G01X1481624Y66865D02*
X1479377Y68353D01*
G01X1478611Y67720D02*
X1481262Y65965D01*
G01X1562434Y52103D02*
X1481624Y66865D01*
G01X1481262Y65965D02*
X1562044Y51208D01*
G01X1557265Y48595D02*
X1480251Y63146D01*
G01X1557265Y48595D02*
X1480251Y63146D01*
G01X1553214Y48393D02*
X1479886Y62248D01*
G01X1480251Y63146D02*
X1476133Y65873D01*
G01X1479886Y62248D02*
X1475367Y65240D01*
G01X1476133Y65873D02*
X1472615Y74286D01*
G01X1475367Y65240D02*
X1471626Y74187D01*
G01X1472615Y74286D02*
X1473887Y80682D01*
G01X1471626Y74187D02*
X1472918Y80682D01*
G01X1473887D02*
X1472622Y87013D01*
G01X1472918Y80682D02*
X1471653Y87013D01*
G01X1472622D02*
X1474049Y94150D01*
G01X1471653Y87013D02*
X1473080Y94150D01*
G01X1474049D02*
X1468891Y119946D01*
G01X1473080Y94150D02*
X1467969Y119710D01*
G01X1468458Y86813D02*
X1470038Y94710D01*
G01X1469069D02*
X1467488Y86811D01*
G01X1469785Y80303D02*
X1468458Y86813D01*
G01X1467488Y86811D02*
X1468815Y80301D01*
G01X1468505Y73874D02*
X1469785Y80303D01*
G01X1468815Y80301D02*
X1467516Y73775D01*
G01X1473005Y63112D02*
X1468505Y73874D01*
G01X1467516Y73775D02*
X1472239Y62479D01*
G01X1478533Y59450D02*
X1473005Y63112D01*
G01X1472239Y62479D02*
X1478168Y58551D01*
G01X1549414Y46155D02*
X1478533Y59450D01*
G01X1478168Y58551D02*
X1479495Y58302D01*
G01X1549414Y46155D02*
X1478533Y59450D01*
G01X1481706Y57887D02*
X1483033Y57638D01*
G01X1549414Y46155D02*
X1478533Y59450D01*
G01X1485244Y57223D02*
X1486571Y56974D01*
G01X1549414Y46155D02*
X1478533Y59450D01*
G01X1488782Y56559D02*
X1490109Y56310D01*
G01X1549414Y46155D02*
X1478533Y59450D01*
G01X1492320Y55895D02*
X1548902Y45284D01*
G01X1485211Y44496D02*
Y44252D01*
G01X1484261D02*
Y44355D01*
G01X1484918Y45462D02*
X1485211Y44496D01*
G01X1484261Y44355D02*
X1484107Y44858D01*
G01X1465544Y58279D02*
X1484918Y45462D01*
G01X1484107Y44858D02*
X1473786Y51687D01*
G01X1465544Y58279D02*
X1484918Y45462D01*
G01X1471910Y52928D02*
X1470784Y53673D01*
G01X1465544Y58279D02*
X1484918Y45462D01*
G01X1468907Y54915D02*
X1467781Y55660D01*
G01X1465544Y58279D02*
X1484918Y45462D01*
G01X1519163Y97573D02*
X1523777Y74832D01*
G01X1520158Y97448D02*
X1524672Y75203D01*
G01X1523777Y74832D02*
X1526105Y71317D01*
G01X1524672Y75203D02*
X1526693Y72151D01*
G01X1526105Y71317D02*
X1527241Y71036D01*
G01X1526693Y72151D02*
X1541430Y68511D01*
G01X1544207Y61862D02*
X1526193Y65171D01*
G01X1558730Y60161D02*
X1526422Y66095D01*
G01X1526193Y65171D02*
X1499975Y73402D01*
G01X1526422Y66095D02*
X1500562Y74214D01*
G01X1499975Y73402D02*
X1496650Y78029D01*
G01X1500562Y74214D02*
X1497523Y78444D01*
G01X1496650Y78029D02*
X1494744Y85091D01*
G01X1497523Y78444D02*
X1495731Y85083D01*
G01X1494744Y85091D02*
X1496910Y92614D01*
G01X1495731Y85083D02*
X1497902Y92623D01*
G01X1496910Y92614D02*
X1493956Y102230D01*
G01X1497902Y92623D02*
X1494953Y102220D01*
G01X1520158Y97448D02*
X1524672Y75203D01*
G01X1519163Y97573D02*
X1523777Y74832D01*
G01X1524672Y75203D02*
X1526693Y72151D01*
G01X1523777Y74832D02*
X1526105Y71317D01*
G01X1526693Y72151D02*
X1541430Y68511D01*
G01X1526105Y71317D02*
X1527241Y71036D01*
G01X1526693Y72151D02*
X1541430Y68511D01*
G01X1526693Y72151D02*
X1541430Y68511D01*
G01X1526693Y72151D02*
X1541430Y68511D01*
G01X1526693Y72151D02*
X1541430Y68511D01*
G01X1558730Y60161D02*
X1526422Y66095D01*
G01X1558730Y60161D02*
X1526422Y66095D01*
G01X1558730Y60161D02*
X1526422Y66095D01*
G01X1558730Y60161D02*
X1526422Y66095D01*
G01X1558730Y60161D02*
X1526422Y66095D01*
G01X1544207Y61862D02*
X1526193Y65171D01*
G01X1526422Y66095D02*
X1500562Y74214D01*
G01X1526193Y65171D02*
X1499975Y73402D01*
G01X1500562Y74214D02*
X1497523Y78444D01*
G01X1499975Y73402D02*
X1496650Y78029D01*
G01X1497523Y78444D02*
X1495731Y85083D01*
G01X1496650Y78029D02*
X1494744Y85091D01*
G01X1495731Y85083D02*
X1497902Y92623D01*
G01X1494744Y85091D02*
X1496910Y92614D01*
G01X1497902Y92623D02*
X1494953Y102220D01*
G01X1496910Y92614D02*
X1493956Y102230D01*
G01X1474811Y45422D02*
Y44252D01*
G01X1475761D02*
Y45839D01*
G01X1474019Y46151D02*
X1474811Y45422D01*
G01X1475761Y45839D02*
X1474607Y46902D01*
G01X1469775Y48959D02*
X1470901Y48214D01*
G01X1472778Y46973D02*
X1474019Y46151D01*
G01X1466311Y44252D02*
Y45839D01*
G01X1465361Y45509D02*
Y44252D01*
G01X1469775Y48959D02*
X1470901Y48214D01*
G01X1472778Y46973D02*
X1474019Y46151D01*
G01X1475761Y45839D02*
X1474607Y46902D01*
G01X1474019Y46151D02*
X1474811Y45422D01*
G01X1475761Y44252D02*
Y45839D01*
G01X1474811Y45422D02*
Y44252D01*
G01X1493100Y45462D02*
Y44341D01*
G01X1494050Y44363D02*
Y45928D01*
G01X1489714Y48086D02*
X1493100Y45462D01*
G01X1494050Y45928D02*
X1490125Y48970D01*
G01X1484790Y49142D02*
X1489714Y48086D01*
G01X1490125Y48970D02*
X1485165Y50034D01*
G01X1469231Y59434D02*
X1484790Y49142D01*
G01X1485165Y50034D02*
X1469997Y60068D01*
G01X1466253Y66557D02*
X1466774Y65311D01*
G01X1467642Y63236D02*
X1469231Y59434D01*
G01X1466253Y66557D02*
X1466774Y65311D01*
G01X1467642Y63236D02*
X1469231Y59434D01*
G01X1485165Y50034D02*
X1469997Y60068D01*
G01X1469231Y59434D02*
X1484790Y49142D01*
G01X1490125Y48970D02*
X1485165Y50034D01*
G01X1484790Y49142D02*
X1489714Y48086D01*
G01X1494050Y45928D02*
X1490125Y48970D01*
G01X1489714Y48086D02*
X1493100Y45462D01*
G01X1494050Y44363D02*
Y45928D01*
G01X1493100Y45462D02*
Y44341D01*
G01X1466318Y34796D02*
Y38209D01*
G01X1465368Y35104D02*
Y38195D01*
G01X1474808Y35095D02*
Y38205D01*
G01X1475758Y34805D02*
Y38199D01*
G01X1494461Y35000D02*
Y36494D01*
G01X1493511Y34900D02*
Y36100D01*
G01X1494461Y36494D02*
X1494050Y36905D01*
G01X1493511Y36100D02*
X1493100Y36511D01*
G01X1494050Y36905D02*
Y38291D01*
G01X1493100Y36511D02*
Y38313D01*
G01X1484289Y35127D02*
Y38174D01*
G01X1485239Y34773D02*
Y38230D01*
G01X1475758Y34805D02*
Y38199D01*
G01X1474808Y35095D02*
Y38205D01*
G01X1465368Y35104D02*
Y38195D01*
G01X1466318Y34796D02*
Y38209D01*
G01X1493511Y34900D02*
Y36100D01*
G01X1494461Y35000D02*
Y36494D01*
G01X1493511Y36100D02*
X1493100Y36511D01*
G01X1494461Y36494D02*
X1494050Y36905D01*
G01X1493100Y36511D02*
Y38313D01*
G01X1494050Y36905D02*
Y38291D01*
G01X1485239Y34773D02*
Y38230D01*
G01X1484289Y35127D02*
Y38174D01*
G01X1502768Y89170D02*
X1501186D01*
G01X1502768Y88220D02*
X1501414D01*
G01X1502768D02*
X1501414D01*
G01X1502768Y89170D02*
X1501186D01*
G01X1511992Y94264D02*
X1510524D01*
G01X1511992D02*
X1510524D01*
G01X1493956Y102230D02*
X1495251Y106160D01*
G01X1494953Y102220D02*
X1495036Y102472D01*
G01X1493956Y102230D02*
X1495251Y106160D01*
G01X1495037Y102472D02*
X1496234Y106106D01*
G01X1495251Y106160D02*
X1494853Y108046D01*
G01X1496234Y106106D02*
X1495692Y108672D01*
G01X1494853Y108046D02*
X1491707Y109754D01*
G01X1495692Y108672D02*
X1491851Y110758D01*
G01X1491707Y109754D02*
X1487122Y108761D01*
G01X1491851Y110758D02*
X1487141Y109738D01*
G01X1487122Y108761D02*
X1485750Y109114D01*
G01Y109115D02*
X1484274Y109495D01*
G01X1487141Y109738D02*
X1484832Y110333D01*
G01X1484274Y109495D02*
X1480036Y115078D01*
G01X1484832Y110333D02*
X1480925Y115479D01*
G01X1480036Y115078D02*
X1478524Y122618D01*
G01X1480925Y115479D02*
X1479495Y122611D01*
G01X1478524Y122618D02*
X1479742Y128243D01*
G01X1479495Y122611D02*
X1480692Y128141D01*
G01X1479742Y128243D02*
Y132186D01*
G01X1480692Y128141D02*
Y132377D01*
G01X1479742Y132186D02*
X1478210Y135843D01*
G01X1480692Y132377D02*
X1478983Y136457D01*
G01X1478210Y135843D02*
X1471587Y140622D01*
G01X1478983Y136457D02*
X1472393Y141213D01*
G01X1471587Y140622D02*
X1470749Y143153D01*
G01X1472393Y141213D02*
X1471731Y143210D01*
G01X1470749Y143153D02*
X1471635Y147436D01*
G01X1471731Y143210D02*
X1472605Y147433D01*
G01X1471635Y147436D02*
X1469928Y155985D01*
G01X1472605Y147433D02*
X1470897Y155985D01*
G01X1469928D02*
X1471335Y163020D01*
G01X1470897Y155985D02*
X1472317Y163082D01*
G01X1475416Y102984D02*
X1477080Y94652D01*
G01X1478049D02*
X1476385Y102984D01*
G01X1476991Y110864D02*
X1475416Y102984D01*
G01X1476385D02*
X1477960Y110864D01*
G01X1474450Y123536D02*
X1476991Y110864D01*
G01X1477960D02*
X1475425Y123510D01*
G01X1475939Y129325D02*
X1474450Y123536D01*
G01X1475425Y123510D02*
X1476889Y129204D01*
G01X1475939Y130823D02*
Y129325D01*
G01X1476889Y129204D02*
Y131018D01*
G01X1474967Y133098D02*
X1475939Y130823D01*
G01X1476889Y131018D02*
X1475746Y133696D01*
G01X1473321Y134390D02*
X1474967Y133098D01*
G01X1475746Y133696D02*
X1473723Y135282D01*
G01X1468822Y135218D02*
X1473321Y134390D01*
G01X1473723Y135282D02*
X1469390Y136080D01*
G01X1467229Y137611D02*
X1468822Y135218D01*
G01X1469390Y136080D02*
X1468124Y137981D01*
G01X1465425Y146630D02*
X1467229Y137611D01*
G01X1468124Y137981D02*
X1466394Y146630D01*
G01X1466255Y150778D02*
X1465425Y146630D01*
G01X1466394D02*
X1467224Y150778D01*
G01D02*
X1465472Y159541D01*
G01X1494953Y102220D02*
X1495036Y102472D01*
G01X1495037D02*
X1496234Y106106D01*
G01X1493956Y102230D02*
X1495251Y106160D01*
G01X1496234Y106106D02*
X1495692Y108672D01*
G01X1495251Y106160D02*
X1494853Y108046D01*
G01X1495692Y108672D02*
X1491851Y110758D01*
G01X1494853Y108046D02*
X1491707Y109754D01*
G01X1491851Y110758D02*
X1487141Y109738D01*
G01X1491707Y109754D02*
X1487122Y108761D01*
G01X1487141Y109738D02*
X1484832Y110333D01*
G01X1487122Y108761D02*
X1485750Y109114D01*
G01X1487141Y109738D02*
X1484832Y110333D01*
G01X1485750Y109115D02*
X1484274Y109495D01*
G01X1484832Y110333D02*
X1480925Y115479D01*
G01X1484274Y109495D02*
X1480036Y115078D01*
G01X1480925Y115479D02*
X1479495Y122611D01*
G01X1480036Y115078D02*
X1478524Y122618D01*
G01X1479495Y122611D02*
X1480692Y128141D01*
G01X1478524Y122618D02*
X1479742Y128243D01*
G01X1480692Y128141D02*
Y132377D01*
G01X1479742Y128243D02*
Y132186D01*
G01X1480692Y132377D02*
X1478983Y136457D01*
G01X1479742Y132186D02*
X1478210Y135843D01*
G01X1478983Y136457D02*
X1472393Y141213D01*
G01X1478210Y135843D02*
X1471587Y140622D01*
G01X1472393Y141213D02*
X1471731Y143210D01*
G01X1471587Y140622D02*
X1470749Y143153D01*
G01X1471731Y143210D02*
X1472605Y147433D01*
G01X1470749Y143153D02*
X1471635Y147436D01*
G01X1472605Y147433D02*
X1470897Y155985D01*
G01X1471635Y147436D02*
X1469928Y155985D01*
G01X1470897D02*
X1472317Y163082D01*
G01X1469928Y155985D02*
X1471335Y163020D01*
G01X1467224Y150778D02*
X1465472Y159541D01*
G01X1466394Y146630D02*
X1467224Y150778D01*
G01X1466255D02*
X1465425Y146630D01*
G01X1468124Y137981D02*
X1466394Y146630D01*
G01X1465425D02*
X1467229Y137611D01*
G01X1469390Y136080D02*
X1468124Y137981D01*
G01X1467229Y137611D02*
X1468822Y135218D01*
G01X1473723Y135282D02*
X1469390Y136080D01*
G01X1468822Y135218D02*
X1473321Y134390D01*
G01X1475746Y133696D02*
X1473723Y135282D01*
G01X1473321Y134390D02*
X1474967Y133098D01*
G01X1476889Y131018D02*
X1475746Y133696D01*
G01X1474967Y133098D02*
X1475939Y130823D01*
G01X1476889Y129204D02*
Y131018D01*
G01X1475939Y130823D02*
Y129325D01*
G01X1475425Y123510D02*
X1476889Y129204D01*
G01X1475939Y129325D02*
X1474450Y123536D01*
G01X1477960Y110864D02*
X1475425Y123510D01*
G01X1474450Y123536D02*
X1476991Y110864D01*
G01X1476385Y102984D02*
X1477960Y110864D01*
G01X1476991D02*
X1475416Y102984D01*
G01X1478049Y94652D02*
X1476385Y102984D01*
G01X1475416D02*
X1477080Y94652D01*
G01X1528076Y126505D02*
X1522805Y129994D01*
G01X1528681Y127245D02*
X1523492Y130680D01*
G01X1522805Y129994D02*
X1522487Y130475D01*
G01X1522488D02*
X1522176Y130947D01*
G01X1523492Y130680D02*
X1523071Y131317D01*
G01X1522176Y130947D02*
X1522139Y131127D01*
G01X1522140D02*
X1521488Y134324D01*
G01X1523071Y131317D02*
X1522458Y134324D01*
G01X1521488D02*
X1522146Y137558D01*
G01X1522458Y134324D02*
X1523116Y137558D01*
G01X1522146D02*
X1520252Y146869D01*
G01X1523116Y137558D02*
X1521222Y146869D01*
G01X1520252D02*
X1522407Y157459D01*
G01X1521222Y146869D02*
X1523375Y157451D01*
G01X1517479Y161025D02*
X1516346Y156112D01*
G01X1518455Y161026D02*
X1517321Y156112D01*
G01X1516346D02*
X1517353Y151743D01*
G01X1517321Y156112D02*
X1518326Y151756D01*
G01X1517353Y151743D02*
X1516081Y145483D01*
G01X1518326Y151756D02*
X1517051Y145483D01*
G01X1516081D02*
X1517522Y138398D01*
G01X1517051Y145483D02*
X1518492Y138398D01*
G01X1517522D02*
X1516422Y132988D01*
G01X1518492Y138398D02*
X1517317Y132617D01*
G01X1516422Y132988D02*
X1515006Y130848D01*
G01X1517317Y132617D02*
X1516016Y130652D01*
G01X1515006Y130848D02*
X1515427Y128777D01*
G01X1516016Y130652D02*
X1516322Y129148D01*
G01X1515427Y128777D02*
X1517536Y125591D01*
G01X1516322Y129148D02*
X1518431Y125962D01*
G01X1517536Y125591D02*
X1520692Y110069D01*
G01X1518431Y125962D02*
X1521662Y110070D01*
G01X1520692Y110069D02*
X1520029Y106759D01*
G01X1521662Y110070D02*
X1521005Y106791D01*
G01X1520029Y106759D02*
X1521057Y102957D01*
G01D02*
X1521310Y102023D01*
G01X1521005Y106791D02*
X1522320Y101929D01*
G01X1521310Y102023D02*
X1519163Y97573D01*
G01X1522320Y101929D02*
X1520158Y97448D01*
G01X1528681Y127245D02*
X1523492Y130680D01*
G01X1528076Y126505D02*
X1522805Y129994D01*
G01X1523492Y130680D02*
X1523071Y131317D01*
G01X1522805Y129994D02*
X1522487Y130475D01*
G01X1523492Y130680D02*
X1523071Y131317D01*
G01X1522488Y130475D02*
X1522176Y130947D01*
G01X1523071Y131317D02*
X1522458Y134324D01*
G01X1522176Y130947D02*
X1522139Y131127D01*
G01X1523071Y131317D02*
X1522458Y134324D01*
G01X1522140Y131127D02*
X1521488Y134324D01*
G01X1522458D02*
X1523116Y137558D01*
G01X1521488Y134324D02*
X1522146Y137558D01*
G01X1523116D02*
X1521222Y146869D01*
G01X1522146Y137558D02*
X1520252Y146869D01*
G01X1521222D02*
X1523375Y157451D01*
G01X1520252Y146869D02*
X1522407Y157459D01*
G01X1518455Y161026D02*
X1517321Y156112D01*
G01X1517479Y161025D02*
X1516346Y156112D01*
G01X1517321D02*
X1518326Y151756D01*
G01X1516346Y156112D02*
X1517353Y151743D01*
G01X1518326Y151756D02*
X1517051Y145483D01*
G01X1517353Y151743D02*
X1516081Y145483D01*
G01X1517051D02*
X1518492Y138398D01*
G01X1516081Y145483D02*
X1517522Y138398D01*
G01X1518492D02*
X1517317Y132617D01*
G01X1517522Y138398D02*
X1516422Y132988D01*
G01X1517317Y132617D02*
X1516016Y130652D01*
G01X1516422Y132988D02*
X1515006Y130848D01*
G01X1516016Y130652D02*
X1516322Y129148D01*
G01X1515006Y130848D02*
X1515427Y128777D01*
G01X1516322Y129148D02*
X1518431Y125962D01*
G01X1515427Y128777D02*
X1517536Y125591D01*
G01X1518431Y125962D02*
X1521662Y110070D01*
G01X1517536Y125591D02*
X1520692Y110069D01*
G01X1521662Y110070D02*
X1521005Y106791D01*
G01X1520692Y110069D02*
X1520029Y106759D01*
G01X1521005Y106791D02*
X1522320Y101929D01*
G01X1520029Y106759D02*
X1521057Y102957D01*
G01X1521005Y106791D02*
X1522320Y101929D01*
G01X1521057Y102957D02*
X1521310Y102023D01*
G01X1522320Y101929D02*
X1520158Y97448D01*
G01X1521310Y102023D02*
X1519163Y97573D01*
G01X1475416Y102984D02*
X1477080Y94652D01*
G01X1478049D02*
X1476385Y102984D01*
G01X1476991Y110864D02*
X1475416Y102984D01*
G01X1476385D02*
X1477960Y110864D01*
G01X1474450Y123536D02*
X1476991Y110864D01*
G01X1477960D02*
X1475425Y123510D01*
G01X1475939Y129325D02*
X1474450Y123536D01*
G01X1475425Y123510D02*
X1476889Y129204D01*
G01X1475939Y130823D02*
Y129325D01*
G01X1476889Y129204D02*
Y131018D01*
G01X1474967Y133098D02*
X1475939Y130823D01*
G01X1476889Y131018D02*
X1475746Y133696D01*
G01X1473321Y134390D02*
X1474967Y133098D01*
G01X1475746Y133696D02*
X1473723Y135282D01*
G01X1468822Y135218D02*
X1473321Y134390D01*
G01X1473723Y135282D02*
X1469390Y136080D01*
G01X1467229Y137611D02*
X1468822Y135218D01*
G01X1469390Y136080D02*
X1468124Y137981D01*
G01X1465425Y146630D02*
X1467229Y137611D01*
G01X1468124Y137981D02*
X1466394Y146630D01*
G01X1466255Y150778D02*
X1465425Y146630D01*
G01X1466394D02*
X1467224Y150778D01*
G01D02*
X1465472Y159541D01*
G01X1467224Y150778D02*
X1465472Y159541D01*
G01X1466394Y146630D02*
X1467224Y150778D01*
G01X1466255D02*
X1465425Y146630D01*
G01X1468124Y137981D02*
X1466394Y146630D01*
G01X1465425D02*
X1467229Y137611D01*
G01X1469390Y136080D02*
X1468124Y137981D01*
G01X1467229Y137611D02*
X1468822Y135218D01*
G01X1473723Y135282D02*
X1469390Y136080D01*
G01X1468822Y135218D02*
X1473321Y134390D01*
G01X1475746Y133696D02*
X1473723Y135282D01*
G01X1473321Y134390D02*
X1474967Y133098D01*
G01X1476889Y131018D02*
X1475746Y133696D01*
G01X1474967Y133098D02*
X1475939Y130823D01*
G01X1476889Y129204D02*
Y131018D01*
G01X1475939Y130823D02*
Y129325D01*
G01X1475425Y123510D02*
X1476889Y129204D01*
G01X1475939Y129325D02*
X1474450Y123536D01*
G01X1477960Y110864D02*
X1475425Y123510D01*
G01X1474450Y123536D02*
X1476991Y110864D01*
G01X1476385Y102984D02*
X1477960Y110864D01*
G01X1476991D02*
X1475416Y102984D01*
G01X1478049Y94652D02*
X1476385Y102984D01*
G01X1475416D02*
X1477080Y94652D01*
G01X1528076Y126505D02*
X1522805Y129994D01*
G01X1528681Y127245D02*
X1523492Y130680D01*
G01X1522805Y129994D02*
X1522487Y130475D01*
G01X1522488D02*
X1522176Y130947D01*
G01X1523492Y130680D02*
X1523071Y131317D01*
G01X1522176Y130947D02*
X1522139Y131127D01*
G01X1522140D02*
X1521488Y134324D01*
G01X1523071Y131317D02*
X1522458Y134324D01*
G01X1521488D02*
X1522146Y137558D01*
G01X1522458Y134324D02*
X1523116Y137558D01*
G01X1522146D02*
X1520252Y146869D01*
G01X1523116Y137558D02*
X1521222Y146869D01*
G01X1520252D02*
X1522407Y157459D01*
G01X1521222Y146869D02*
X1523375Y157451D01*
G01X1517479Y161025D02*
X1516346Y156112D01*
G01X1518455Y161026D02*
X1517321Y156112D01*
G01X1516346D02*
X1517353Y151743D01*
G01X1517321Y156112D02*
X1518326Y151756D01*
G01X1517353Y151743D02*
X1516081Y145483D01*
G01X1518326Y151756D02*
X1517051Y145483D01*
G01X1516081D02*
X1517522Y138398D01*
G01X1517051Y145483D02*
X1518492Y138398D01*
G01X1517522D02*
X1516422Y132988D01*
G01X1518492Y138398D02*
X1517317Y132617D01*
G01X1516422Y132988D02*
X1515006Y130848D01*
G01X1517317Y132617D02*
X1516016Y130652D01*
G01X1515006Y130848D02*
X1515427Y128777D01*
G01X1516016Y130652D02*
X1516322Y129148D01*
G01X1515427Y128777D02*
X1517536Y125591D01*
G01X1516322Y129148D02*
X1518431Y125962D01*
G01X1517536Y125591D02*
X1520692Y110069D01*
G01X1518431Y125962D02*
X1521662Y110070D01*
G01X1520692Y110069D02*
X1520029Y106759D01*
G01X1521662Y110070D02*
X1521005Y106791D01*
G01X1520029Y106759D02*
X1521057Y102957D01*
G01D02*
X1521310Y102023D01*
G01X1521005Y106791D02*
X1522320Y101929D01*
G01X1521310Y102023D02*
X1519163Y97573D01*
G01X1522320Y101929D02*
X1520158Y97448D01*
G01X1493956Y102230D02*
X1495251Y106160D01*
G01X1494953Y102220D02*
X1495036Y102472D01*
G01X1493956Y102230D02*
X1495251Y106160D01*
G01X1495037Y102472D02*
X1496234Y106106D01*
G01X1495251Y106160D02*
X1494853Y108046D01*
G01X1496234Y106106D02*
X1495692Y108672D01*
G01X1494853Y108046D02*
X1491707Y109754D01*
G01X1495692Y108672D02*
X1491851Y110758D01*
G01X1491707Y109754D02*
X1487122Y108761D01*
G01X1491851Y110758D02*
X1487141Y109738D01*
G01X1487122Y108761D02*
X1485750Y109114D01*
G01Y109115D02*
X1484274Y109495D01*
G01X1487141Y109738D02*
X1484832Y110333D01*
G01X1484274Y109495D02*
X1480036Y115078D01*
G01X1484832Y110333D02*
X1480925Y115479D01*
G01X1480036Y115078D02*
X1478524Y122618D01*
G01X1480925Y115479D02*
X1479495Y122611D01*
G01X1478524Y122618D02*
X1479742Y128243D01*
G01X1479495Y122611D02*
X1480692Y128141D01*
G01X1479742Y128243D02*
Y132186D01*
G01X1480692Y128141D02*
Y132377D01*
G01X1479742Y132186D02*
X1478210Y135843D01*
G01X1480692Y132377D02*
X1478983Y136457D01*
G01X1478210Y135843D02*
X1471587Y140622D01*
G01X1478983Y136457D02*
X1472393Y141213D01*
G01X1471587Y140622D02*
X1470749Y143153D01*
G01X1472393Y141213D02*
X1471731Y143210D01*
G01X1470749Y143153D02*
X1471635Y147436D01*
G01X1471731Y143210D02*
X1472605Y147433D01*
G01X1471635Y147436D02*
X1469928Y155985D01*
G01X1472605Y147433D02*
X1470897Y155985D01*
G01X1469928D02*
X1471335Y163020D01*
G01X1470897Y155985D02*
X1472317Y163082D01*
G01X1528681Y127245D02*
X1523492Y130680D01*
G01X1528076Y126505D02*
X1522805Y129994D01*
G01X1523492Y130680D02*
X1523071Y131317D01*
G01X1522805Y129994D02*
X1522487Y130475D01*
G01X1523492Y130680D02*
X1523071Y131317D01*
G01X1522488Y130475D02*
X1522176Y130947D01*
G01X1523071Y131317D02*
X1522458Y134324D01*
G01X1522176Y130947D02*
X1522139Y131127D01*
G01X1523071Y131317D02*
X1522458Y134324D01*
G01X1522140Y131127D02*
X1521488Y134324D01*
G01X1522458D02*
X1523116Y137558D01*
G01X1521488Y134324D02*
X1522146Y137558D01*
G01X1523116D02*
X1521222Y146869D01*
G01X1522146Y137558D02*
X1520252Y146869D01*
G01X1521222D02*
X1523375Y157451D01*
G01X1520252Y146869D02*
X1522407Y157459D01*
G01X1518455Y161026D02*
X1517321Y156112D01*
G01X1517479Y161025D02*
X1516346Y156112D01*
G01X1517321D02*
X1518326Y151756D01*
G01X1516346Y156112D02*
X1517353Y151743D01*
G01X1518326Y151756D02*
X1517051Y145483D01*
G01X1517353Y151743D02*
X1516081Y145483D01*
G01X1517051D02*
X1518492Y138398D01*
G01X1516081Y145483D02*
X1517522Y138398D01*
G01X1518492D02*
X1517317Y132617D01*
G01X1517522Y138398D02*
X1516422Y132988D01*
G01X1517317Y132617D02*
X1516016Y130652D01*
G01X1516422Y132988D02*
X1515006Y130848D01*
G01X1516016Y130652D02*
X1516322Y129148D01*
G01X1515006Y130848D02*
X1515427Y128777D01*
G01X1516322Y129148D02*
X1518431Y125962D01*
G01X1515427Y128777D02*
X1517536Y125591D01*
G01X1518431Y125962D02*
X1521662Y110070D01*
G01X1517536Y125591D02*
X1520692Y110069D01*
G01X1521662Y110070D02*
X1521005Y106791D01*
G01X1520692Y110069D02*
X1520029Y106759D01*
G01X1521005Y106791D02*
X1522320Y101929D01*
G01X1520029Y106759D02*
X1521057Y102957D01*
G01X1521005Y106791D02*
X1522320Y101929D01*
G01X1521057Y102957D02*
X1521310Y102023D01*
G01X1522320Y101929D02*
X1520158Y97448D01*
G01X1521310Y102023D02*
X1519163Y97573D01*
G01X1494953Y102220D02*
X1495036Y102472D01*
G01X1495037D02*
X1496234Y106106D01*
G01X1493956Y102230D02*
X1495251Y106160D01*
G01X1496234Y106106D02*
X1495692Y108672D01*
G01X1495251Y106160D02*
X1494853Y108046D01*
G01X1495692Y108672D02*
X1491851Y110758D01*
G01X1494853Y108046D02*
X1491707Y109754D01*
G01X1491851Y110758D02*
X1487141Y109738D01*
G01X1491707Y109754D02*
X1487122Y108761D01*
G01X1487141Y109738D02*
X1484832Y110333D01*
G01X1487122Y108761D02*
X1485750Y109114D01*
G01X1487141Y109738D02*
X1484832Y110333D01*
G01X1485750Y109115D02*
X1484274Y109495D01*
G01X1484832Y110333D02*
X1480925Y115479D01*
G01X1484274Y109495D02*
X1480036Y115078D01*
G01X1480925Y115479D02*
X1479495Y122611D01*
G01X1480036Y115078D02*
X1478524Y122618D01*
G01X1479495Y122611D02*
X1480692Y128141D01*
G01X1478524Y122618D02*
X1479742Y128243D01*
G01X1480692Y128141D02*
Y132377D01*
G01X1479742Y128243D02*
Y132186D01*
G01X1480692Y132377D02*
X1478983Y136457D01*
G01X1479742Y132186D02*
X1478210Y135843D01*
G01X1478983Y136457D02*
X1472393Y141213D01*
G01X1478210Y135843D02*
X1471587Y140622D01*
G01X1472393Y141213D02*
X1471731Y143210D01*
G01X1471587Y140622D02*
X1470749Y143153D01*
G01X1471731Y143210D02*
X1472605Y147433D01*
G01X1470749Y143153D02*
X1471635Y147436D01*
G01X1472605Y147433D02*
X1470897Y155985D01*
G01X1471635Y147436D02*
X1469928Y155985D01*
G01X1470897D02*
X1472317Y163082D01*
G01X1469928Y155985D02*
X1471335Y163020D01*
G01X1511681Y95214D02*
X1510188D01*
G01X1501957Y112886D02*
X1502862D01*
G01X1502712Y111936D02*
X1501458D01*
G01X1503069Y101282D02*
X1500375D01*
G01X1502467Y100332D02*
X1499515D01*
G01X1502712Y111936D02*
X1501458D01*
G01X1501957Y112886D02*
X1502862D01*
G01X1502467Y100332D02*
X1499515D01*
G01X1503069Y101282D02*
X1500375D01*
G01X1503042Y123114D02*
X1501518Y121590D01*
G01X1503666Y125082D02*
X1500568Y121984D01*
G01X1501518Y121590D02*
Y119685D01*
G01X1500568Y121984D02*
Y120079D01*
G01X1501518Y119685D02*
X1499422Y117589D01*
G01X1500568Y120079D02*
X1499028Y118539D01*
G01X1499422Y117589D02*
X1490442D01*
G01X1499028Y118539D02*
X1490322D01*
G01X1503666Y125082D02*
X1500568Y121984D01*
G01X1503042Y123114D02*
X1501518Y121590D01*
G01X1500568Y121984D02*
Y120079D01*
G01X1501518Y121590D02*
Y119685D01*
G01X1500568Y120079D02*
X1499028Y118539D01*
G01X1501518Y119685D02*
X1499422Y117589D01*
G01X1499028Y118539D02*
X1490322D01*
G01X1499422Y117589D02*
X1490442D01*
G01X1502050Y130479D02*
X1493607D01*
G01X1502050Y129529D02*
X1493607D01*
G01X1502050D02*
X1493607D01*
G01X1502050Y130479D02*
X1493607D01*
G01X1512460Y118668D02*
X1510356D01*
G01Y117718D02*
X1512560D01*
G01X1512534Y106931D02*
X1510282D01*
G01X1512486Y105981D02*
X1510430D01*
G01X1510356Y117718D02*
X1512560D01*
G01X1512460Y118668D02*
X1510356D01*
G01X1512486Y105981D02*
X1510430D01*
G01X1512534Y106931D02*
X1510282D01*
G01X1511681Y95214D02*
X1510188D01*
G01X1465472Y159541D02*
X1466819Y167083D01*
G01X1465472Y159541D02*
X1466819Y167083D01*
G01X1476368Y201294D02*
X1485379Y199158D01*
G01X1476760Y202178D02*
X1485357Y200140D01*
G01X1485379Y199158D02*
X1496060Y202204D01*
G01X1485357Y200140D02*
X1496065Y203194D01*
G01X1496060Y202204D02*
X1501798Y200508D01*
G01X1496065Y203194D02*
X1502406Y201319D01*
G01X1501798Y200508D02*
X1508263Y190460D01*
G01X1502406Y201319D02*
X1508896Y191232D01*
G01X1508263Y190460D02*
X1511491Y189188D01*
G01X1508896Y191232D02*
X1512085Y189976D01*
G01X1511491Y189188D02*
X1517256Y181669D01*
G01X1512085Y189976D02*
X1517914Y182374D01*
G01X1517256Y181669D02*
X1528163Y174451D01*
G01X1517914Y182374D02*
X1528534Y175346D01*
G01X1474870Y198722D02*
X1485070Y196039D01*
G01X1474472Y197844D02*
X1485065Y195057D01*
G01X1485070Y196039D02*
X1490540Y197421D01*
G01X1485065Y195057D02*
X1490549Y196443D01*
G01X1490540Y197421D02*
X1501278Y194923D01*
G01X1490549Y196443D02*
X1500723Y194076D01*
G01X1501278Y194923D02*
X1510167Y182985D01*
G01X1500723Y194076D02*
X1509476Y182321D01*
G01X1510167Y182985D02*
X1523297Y172319D01*
G01X1509476Y182321D02*
X1522879Y171433D01*
G01X1523297Y172319D02*
X1532068Y170555D01*
G01X1522879Y171433D02*
X1531694Y169661D01*
G01X1522407Y157459D02*
X1521835Y160528D01*
G01X1523375Y157451D02*
X1522766Y160722D01*
G01X1521835Y160528D02*
X1520053Y168245D01*
G01X1522766Y160722D02*
X1520891Y168843D01*
G01X1520053Y168245D02*
X1509412Y174894D01*
G01X1520891Y168843D02*
X1510063Y175609D01*
G01X1509412Y174894D02*
X1497676Y190289D01*
G01X1510063Y175609D02*
X1498242Y191114D01*
G01X1497676Y190289D02*
X1490295Y192430D01*
G01X1498242Y191114D02*
X1490310Y193415D01*
G01X1490295Y192430D02*
X1485012Y191076D01*
G01X1490310Y193415D02*
X1485014Y192058D01*
G01X1485012Y191076D02*
X1472925Y194222D01*
G01X1485014Y192058D02*
X1473323Y195101D01*
G01X1471395Y190689D02*
X1471914Y190339D01*
G01X1471795Y191567D02*
X1472305Y191222D01*
G01X1471914Y190339D02*
X1485499Y187023D01*
G01X1472305Y191222D02*
X1485513Y187998D01*
G01X1485499Y187023D02*
X1490511Y188099D01*
G01X1485513Y187998D02*
X1490601Y189091D01*
G01X1490511Y188099D02*
X1493141Y187013D01*
G01X1490601Y189091D02*
X1493744Y187792D01*
G01X1493141Y187013D02*
X1501554Y175816D01*
G01X1493744Y187792D02*
X1502241Y176485D01*
G01X1501554Y175816D02*
X1516868Y163660D01*
G01X1502241Y176485D02*
X1517719Y164198D01*
G01X1516868Y163660D02*
X1517479Y161025D01*
G01X1517719Y164198D02*
X1518455Y161026D01*
G01X1476760Y202178D02*
X1485357Y200140D01*
G01X1476368Y201294D02*
X1485379Y199158D01*
G01X1485357Y200140D02*
X1496065Y203194D01*
G01X1485379Y199158D02*
X1496060Y202204D01*
G01X1496065Y203194D02*
X1502406Y201319D01*
G01X1496060Y202204D02*
X1501798Y200508D01*
G01X1502406Y201319D02*
X1508896Y191232D01*
G01X1501798Y200508D02*
X1508263Y190460D01*
G01X1508896Y191232D02*
X1512085Y189976D01*
G01X1508263Y190460D02*
X1511491Y189188D01*
G01X1512085Y189976D02*
X1517914Y182374D01*
G01X1511491Y189188D02*
X1517256Y181669D01*
G01X1517914Y182374D02*
X1528534Y175346D01*
G01X1517256Y181669D02*
X1528163Y174451D01*
G01X1474472Y197844D02*
X1485065Y195057D01*
G01X1474870Y198722D02*
X1485070Y196039D01*
G01X1485065Y195057D02*
X1490549Y196443D01*
G01X1485070Y196039D02*
X1490540Y197421D01*
G01X1490549Y196443D02*
X1500723Y194076D01*
G01X1490540Y197421D02*
X1501278Y194923D01*
G01X1500723Y194076D02*
X1509476Y182321D01*
G01X1501278Y194923D02*
X1510167Y182985D01*
G01X1509476Y182321D02*
X1522879Y171433D01*
G01X1510167Y182985D02*
X1523297Y172319D01*
G01X1522879Y171433D02*
X1531694Y169661D01*
G01X1523297Y172319D02*
X1532068Y170555D01*
G01X1523375Y157451D02*
X1522766Y160722D01*
G01X1522407Y157459D02*
X1521835Y160528D01*
G01X1522766Y160722D02*
X1520891Y168843D01*
G01X1521835Y160528D02*
X1520053Y168245D01*
G01X1520891Y168843D02*
X1510063Y175609D01*
G01X1520053Y168245D02*
X1509412Y174894D01*
G01X1510063Y175609D02*
X1498242Y191114D01*
G01X1509412Y174894D02*
X1497676Y190289D01*
G01X1498242Y191114D02*
X1490310Y193415D01*
G01X1497676Y190289D02*
X1490295Y192430D01*
G01X1490310Y193415D02*
X1485014Y192058D01*
G01X1490295Y192430D02*
X1485012Y191076D01*
G01X1485014Y192058D02*
X1473323Y195101D01*
G01X1485012Y191076D02*
X1472925Y194222D01*
G01X1471795Y191567D02*
X1472305Y191222D01*
G01X1471395Y190689D02*
X1471914Y190339D01*
G01X1472305Y191222D02*
X1485513Y187998D01*
G01X1471914Y190339D02*
X1485499Y187023D01*
G01X1485513Y187998D02*
X1490601Y189091D01*
G01X1485499Y187023D02*
X1490511Y188099D01*
G01X1490601Y189091D02*
X1493744Y187792D01*
G01X1490511Y188099D02*
X1493141Y187013D01*
G01X1493744Y187792D02*
X1502241Y176485D01*
G01X1493141Y187013D02*
X1501554Y175816D01*
G01X1502241Y176485D02*
X1517719Y164198D01*
G01X1501554Y175816D02*
X1516868Y163660D01*
G01X1517719Y164198D02*
X1518455Y161026D01*
G01X1516868Y163660D02*
X1517479Y161025D01*
G01X1465472Y159541D02*
X1466819Y167083D01*
G01X1465472Y159541D02*
X1466819Y167083D01*
G01X1476368Y201294D02*
X1485379Y199158D01*
G01X1476760Y202178D02*
X1485357Y200140D01*
G01X1485379Y199158D02*
X1496060Y202204D01*
G01X1485357Y200140D02*
X1496065Y203194D01*
G01X1496060Y202204D02*
X1501798Y200508D01*
G01X1496065Y203194D02*
X1502406Y201319D01*
G01X1501798Y200508D02*
X1508263Y190460D01*
G01X1502406Y201319D02*
X1508896Y191232D01*
G01X1508263Y190460D02*
X1511491Y189188D01*
G01X1508896Y191232D02*
X1512085Y189976D01*
G01X1511491Y189188D02*
X1517256Y181669D01*
G01X1512085Y189976D02*
X1517914Y182374D01*
G01X1517256Y181669D02*
X1528163Y174451D01*
G01X1517914Y182374D02*
X1528534Y175346D01*
G01X1474870Y198722D02*
X1485070Y196039D01*
G01X1474472Y197844D02*
X1485065Y195057D01*
G01X1485070Y196039D02*
X1490540Y197421D01*
G01X1485065Y195057D02*
X1490549Y196443D01*
G01X1490540Y197421D02*
X1501278Y194923D01*
G01X1490549Y196443D02*
X1500723Y194076D01*
G01X1501278Y194923D02*
X1510167Y182985D01*
G01X1500723Y194076D02*
X1509476Y182321D01*
G01X1510167Y182985D02*
X1523297Y172319D01*
G01X1509476Y182321D02*
X1522879Y171433D01*
G01X1523297Y172319D02*
X1532068Y170555D01*
G01X1522879Y171433D02*
X1531694Y169661D01*
G01X1522407Y157459D02*
X1521835Y160528D01*
G01X1523375Y157451D02*
X1522766Y160722D01*
G01X1521835Y160528D02*
X1520053Y168245D01*
G01X1522766Y160722D02*
X1520891Y168843D01*
G01X1520053Y168245D02*
X1509412Y174894D01*
G01X1520891Y168843D02*
X1510063Y175609D01*
G01X1509412Y174894D02*
X1497676Y190289D01*
G01X1510063Y175609D02*
X1498242Y191114D01*
G01X1497676Y190289D02*
X1490295Y192430D01*
G01X1498242Y191114D02*
X1490310Y193415D01*
G01X1490295Y192430D02*
X1485012Y191076D01*
G01X1490310Y193415D02*
X1485014Y192058D01*
G01X1485012Y191076D02*
X1472925Y194222D01*
G01X1485014Y192058D02*
X1473323Y195101D01*
G01X1471395Y190689D02*
X1471914Y190339D01*
G01X1471795Y191567D02*
X1472305Y191222D01*
G01X1471914Y190339D02*
X1485499Y187023D01*
G01X1472305Y191222D02*
X1485513Y187998D01*
G01X1485499Y187023D02*
X1490511Y188099D01*
G01X1485513Y187998D02*
X1490601Y189091D01*
G01X1490511Y188099D02*
X1493141Y187013D01*
G01X1490601Y189091D02*
X1493744Y187792D01*
G01X1493141Y187013D02*
X1501554Y175816D01*
G01X1493744Y187792D02*
X1502241Y176485D01*
G01X1501554Y175816D02*
X1516868Y163660D01*
G01X1502241Y176485D02*
X1517719Y164198D01*
G01X1516868Y163660D02*
X1517479Y161025D01*
G01X1517719Y164198D02*
X1518455Y161026D01*
G01X1476760Y202178D02*
X1485357Y200140D01*
G01X1476368Y201294D02*
X1485379Y199158D01*
G01X1485357Y200140D02*
X1496065Y203194D01*
G01X1485379Y199158D02*
X1496060Y202204D01*
G01X1496065Y203194D02*
X1502406Y201319D01*
G01X1496060Y202204D02*
X1501798Y200508D01*
G01X1502406Y201319D02*
X1508896Y191232D01*
G01X1501798Y200508D02*
X1508263Y190460D01*
G01X1508896Y191232D02*
X1512085Y189976D01*
G01X1508263Y190460D02*
X1511491Y189188D01*
G01X1512085Y189976D02*
X1517914Y182374D01*
G01X1511491Y189188D02*
X1517256Y181669D01*
G01X1517914Y182374D02*
X1528534Y175346D01*
G01X1517256Y181669D02*
X1528163Y174451D01*
G01X1474472Y197844D02*
X1485065Y195057D01*
G01X1474870Y198722D02*
X1485070Y196039D01*
G01X1485065Y195057D02*
X1490549Y196443D01*
G01X1485070Y196039D02*
X1490540Y197421D01*
G01X1490549Y196443D02*
X1500723Y194076D01*
G01X1490540Y197421D02*
X1501278Y194923D01*
G01X1500723Y194076D02*
X1509476Y182321D01*
G01X1501278Y194923D02*
X1510167Y182985D01*
G01X1509476Y182321D02*
X1522879Y171433D01*
G01X1510167Y182985D02*
X1523297Y172319D01*
G01X1522879Y171433D02*
X1531694Y169661D01*
G01X1523297Y172319D02*
X1532068Y170555D01*
G01X1523375Y157451D02*
X1522766Y160722D01*
G01X1522407Y157459D02*
X1521835Y160528D01*
G01X1522766Y160722D02*
X1520891Y168843D01*
G01X1521835Y160528D02*
X1520053Y168245D01*
G01X1520891Y168843D02*
X1510063Y175609D01*
G01X1520053Y168245D02*
X1509412Y174894D01*
G01X1510063Y175609D02*
X1498242Y191114D01*
G01X1509412Y174894D02*
X1497676Y190289D01*
G01X1498242Y191114D02*
X1490310Y193415D01*
G01X1497676Y190289D02*
X1490295Y192430D01*
G01X1490310Y193415D02*
X1485014Y192058D01*
G01X1490295Y192430D02*
X1485012Y191076D01*
G01X1485014Y192058D02*
X1473323Y195101D01*
G01X1485012Y191076D02*
X1472925Y194222D01*
G01X1471795Y191567D02*
X1472305Y191222D01*
G01X1471395Y190689D02*
X1471914Y190339D01*
G01X1472305Y191222D02*
X1485513Y187998D01*
G01X1471914Y190339D02*
X1485499Y187023D01*
G01X1485513Y187998D02*
X1490601Y189091D01*
G01X1485499Y187023D02*
X1490511Y188099D01*
G01X1490601Y189091D02*
X1493744Y187792D01*
G01X1490511Y188099D02*
X1493141Y187013D01*
G01X1493744Y187792D02*
X1502241Y176485D01*
G01X1493141Y187013D02*
X1501554Y175816D01*
G01X1502241Y176485D02*
X1517719Y164198D01*
G01X1501554Y175816D02*
X1516868Y163660D01*
G01X1517719Y164198D02*
X1518455Y161026D01*
G01X1516868Y163660D02*
X1517479Y161025D01*
G01X1584059Y13696D02*
Y11978D01*
G01X1585009Y13696D02*
Y12064D01*
G01X1574609Y12809D02*
Y13696D01*
G01X1575559Y12741D02*
Y13696D01*
G01X1565059Y12959D02*
Y13796D01*
G01X1566009Y12891D02*
Y13596D01*
G01X1556659Y13696D02*
Y12841D01*
G01X1555709Y13696D02*
Y12809D01*
G01X1546259Y13059D02*
Y13696D01*
G01X1547209Y13059D02*
Y13696D01*
G01X1585009D02*
Y12064D01*
G01X1584059Y13696D02*
Y11978D01*
G01X1575559Y12741D02*
Y13696D01*
G01X1574609Y12809D02*
Y13696D01*
G01X1566009Y12891D02*
Y13596D01*
G01X1565059Y12959D02*
Y13796D01*
G01X1555709Y13696D02*
Y12809D01*
G01X1556659Y13696D02*
Y12841D01*
G01X1547209Y13059D02*
Y13696D01*
G01X1546259Y13059D02*
Y13696D01*
G01X1584059D02*
Y11978D01*
G01X1585009Y13696D02*
Y12064D01*
G01X1574609Y12809D02*
Y13696D01*
G01X1575559Y12741D02*
Y13696D01*
G01X1565059Y12959D02*
Y13796D01*
G01X1566009Y12891D02*
Y13596D01*
G01X1556659Y13696D02*
Y12841D01*
G01X1555709Y13696D02*
Y12809D01*
G01X1546259Y13059D02*
Y13696D01*
G01X1547209Y13059D02*
Y13696D01*
G01X1585009D02*
Y12064D01*
G01X1584059Y13696D02*
Y11978D01*
G01X1575559Y12741D02*
Y13696D01*
G01X1574609Y12809D02*
Y13696D01*
G01X1566009Y12891D02*
Y13596D01*
G01X1565059Y12959D02*
Y13796D01*
G01X1555709Y13696D02*
Y12809D01*
G01X1556659Y13696D02*
Y12841D01*
G01X1547209Y13059D02*
Y13696D01*
G01X1546259Y13059D02*
Y13696D01*
G01X1577773Y44259D02*
Y45200D01*
G01X1578723Y44259D02*
Y45542D01*
G01X1577773Y45200D02*
X1575551Y47887D01*
G01X1578723Y45542D02*
X1576196Y48600D01*
G01X1575551Y47887D02*
X1558370Y59260D01*
G01X1576196Y48600D02*
X1558730Y60161D01*
G01X1558370Y59260D02*
X1557042Y59504D01*
G01X1554829Y59910D02*
X1553501Y60154D01*
G01X1551289Y60561D02*
X1549961Y60805D01*
G01X1547748Y61211D02*
X1546420Y61455D01*
G01X1568323Y45200D02*
Y44259D01*
G01X1569273D02*
Y45542D01*
G01X1565474Y48645D02*
X1568323Y45200D01*
G01X1569273Y45542D02*
X1566134Y49338D01*
G01X1562044Y51208D02*
X1565192Y48856D01*
G01D02*
X1565474Y48645D01*
G01X1566134Y49338D02*
X1562434Y52103D01*
G01X1558673Y44459D02*
Y45400D01*
G01X1559623Y44459D02*
Y45742D01*
G01X1558673Y45400D02*
X1556751Y47725D01*
G01X1559623Y45742D02*
X1557265Y48595D01*
G01X1556751Y47725D02*
X1555424Y47976D01*
G01X1549523Y44536D02*
Y44259D01*
G01X1550473D02*
Y44879D01*
G01X1548902Y45284D02*
X1549523Y44536D01*
G01X1550473Y44879D02*
X1549414Y46155D01*
G01X1578723Y44259D02*
Y45542D01*
G01X1577773Y44259D02*
Y45200D01*
G01X1578723Y45542D02*
X1576196Y48600D01*
G01X1577773Y45200D02*
X1575551Y47887D01*
G01X1576196Y48600D02*
X1558730Y60161D01*
G01X1575551Y47887D02*
X1558370Y59260D01*
G01D02*
X1557042Y59504D01*
G01X1554829Y59910D02*
X1553501Y60154D01*
G01X1551289Y60561D02*
X1549961Y60805D01*
G01X1547748Y61211D02*
X1546420Y61455D01*
G01X1566134Y49338D02*
X1562434Y52103D01*
G01X1562044Y51208D02*
X1565192Y48856D01*
G01X1566134Y49338D02*
X1562434Y52103D01*
G01X1565192Y48856D02*
X1565474Y48645D01*
G01X1569273Y45542D02*
X1566134Y49338D01*
G01X1565474Y48645D02*
X1568323Y45200D01*
G01X1569273Y44259D02*
Y45542D01*
G01X1568323Y45200D02*
Y44259D01*
G01X1559623Y44459D02*
Y45742D01*
G01X1558673Y44459D02*
Y45400D01*
G01X1559623Y45742D02*
X1557265Y48595D01*
G01X1558673Y45400D02*
X1556751Y47725D01*
G01D02*
X1555424Y47976D01*
G01X1550473Y44879D02*
X1549414Y46155D01*
G01X1548902Y45284D02*
X1549523Y44536D01*
G01X1550473Y44259D02*
Y44879D01*
G01X1549523Y44536D02*
Y44259D01*
G01X1550573Y100432D02*
X1554633Y87192D01*
G01X1551563Y100447D02*
X1555505Y87593D01*
G01X1554633Y87192D02*
X1558800Y80601D01*
G01X1555505Y87593D02*
X1559478Y81307D01*
G01X1558800Y80601D02*
X1566825Y75973D01*
G01X1559478Y81307D02*
X1567641Y76600D01*
G01X1566825Y75973D02*
X1568031Y71488D01*
G01X1567641Y76600D02*
X1568856Y72082D01*
G01X1568031Y71488D02*
X1586199Y59460D01*
G01X1568856Y72082D02*
X1586568Y60356D01*
G01X1586199Y59460D02*
X1595194Y57662D01*
G01X1586568Y60356D02*
X1595565Y58558D01*
G01X1546406Y103958D02*
X1551854Y85883D01*
G01X1545418Y103942D02*
X1550983Y85478D01*
G01X1551854Y85883D02*
X1560387Y72980D01*
G01X1550982Y85478D02*
X1559701Y72294D01*
G01X1560387Y72980D02*
X1585477Y56376D01*
G01X1559701Y72294D02*
X1585108Y55480D01*
G01X1585477Y56376D02*
X1594492Y54574D01*
G01X1585108Y55480D02*
X1594121Y53679D01*
G01X1589262Y50599D02*
X1583978Y51655D01*
G01X1593311Y50758D02*
X1584347Y52551D01*
G01X1583978Y51655D02*
X1559697Y67727D01*
G01X1584347Y52551D02*
X1560067Y68622D01*
G01X1559697Y67727D02*
X1554196Y68842D01*
G01X1560067Y68622D02*
X1554757Y69699D01*
G01X1554196Y68842D02*
X1551817Y72236D01*
G01X1550526Y74078D02*
X1549751Y75184D01*
G01X1548460Y77026D02*
X1547407Y78529D01*
G01X1554757Y69699D02*
X1548082Y79222D01*
G01X1547407Y78529D02*
X1542677Y81662D01*
G01X1548082Y79222D02*
X1543048Y82557D01*
G01X1542677Y81662D02*
X1541263Y81949D01*
G01X1543048Y82557D02*
X1541263Y82919D01*
G01Y81949D02*
X1536150Y80907D01*
G01X1541263Y82919D02*
X1536272Y81902D01*
G01X1536150Y80907D02*
X1531617Y83068D01*
G01X1536272Y81902D02*
X1532277Y83807D01*
G01X1531617Y83068D02*
X1529788Y85998D01*
G01X1532277Y83807D02*
X1530678Y86367D01*
G01X1529788Y85998D02*
X1528945Y89650D01*
G01X1530678Y86367D02*
X1529920Y89650D01*
G01X1528945D02*
X1530274Y95419D01*
G01X1529920Y89650D02*
X1531250Y95419D01*
G01X1529425Y70497D02*
X1530736Y70173D01*
G01X1532920Y69634D02*
X1534231Y69310D01*
G01X1536415Y68771D02*
X1537726Y68447D01*
G01X1539910Y67908D02*
X1541221Y67584D01*
G01D02*
X1558156Y64139D01*
G01X1541430Y68511D02*
X1558527Y65034D01*
G01X1558156Y64139D02*
X1582768Y47846D01*
G01X1558527Y65034D02*
X1583125Y48750D01*
G01X1582768Y47846D02*
X1585599Y47369D01*
G01X1583125Y48750D02*
X1586132Y48243D01*
G01X1585599Y47369D02*
X1587223Y45200D01*
G01X1586132Y48243D02*
X1588173Y45517D01*
G01X1587223Y45200D02*
Y44259D01*
G01X1588173Y45517D02*
Y44259D01*
G01X1551563Y100447D02*
X1555505Y87593D01*
G01X1550573Y100432D02*
X1554633Y87192D01*
G01X1555505Y87593D02*
X1559478Y81307D01*
G01X1554633Y87192D02*
X1558800Y80601D01*
G01X1559478Y81307D02*
X1567641Y76600D01*
G01X1558800Y80601D02*
X1566825Y75973D01*
G01X1567641Y76600D02*
X1568856Y72082D01*
G01X1566825Y75973D02*
X1568031Y71488D01*
G01X1568856Y72082D02*
X1586568Y60356D01*
G01X1568031Y71488D02*
X1586199Y59460D01*
G01X1586568Y60356D02*
X1595565Y58558D01*
G01X1586199Y59460D02*
X1595194Y57662D01*
G01X1545418Y103942D02*
X1550983Y85478D01*
G01X1546406Y103958D02*
X1551854Y85883D01*
G01X1550982Y85478D02*
X1559701Y72294D01*
G01X1551854Y85883D02*
X1560387Y72980D01*
G01X1559701Y72294D02*
X1585108Y55480D01*
G01X1560387Y72980D02*
X1585477Y56376D01*
G01X1585108Y55480D02*
X1594121Y53679D01*
G01X1585477Y56376D02*
X1594492Y54574D01*
G01X1593311Y50758D02*
X1584347Y52551D01*
G01X1593311Y50758D02*
X1584347Y52551D01*
G01X1589262Y50599D02*
X1583978Y51655D01*
G01X1584347Y52551D02*
X1560067Y68622D01*
G01X1583978Y51655D02*
X1559697Y67727D01*
G01X1560067Y68622D02*
X1554757Y69699D01*
G01X1559697Y67727D02*
X1554196Y68842D01*
G01X1554757Y69699D02*
X1548082Y79222D01*
G01X1554196Y68842D02*
X1551817Y72236D01*
G01X1554757Y69699D02*
X1548082Y79222D01*
G01X1550526Y74078D02*
X1549751Y75184D01*
G01X1554757Y69699D02*
X1548082Y79222D01*
G01X1548460Y77026D02*
X1547407Y78529D01*
G01X1548082Y79222D02*
X1543048Y82557D01*
G01X1547407Y78529D02*
X1542677Y81662D01*
G01X1543048Y82557D02*
X1541263Y82919D01*
G01X1542677Y81662D02*
X1541263Y81949D01*
G01Y82919D02*
X1536272Y81902D01*
G01X1541263Y81949D02*
X1536150Y80907D01*
G01X1536272Y81902D02*
X1532277Y83807D01*
G01X1536150Y80907D02*
X1531617Y83068D01*
G01X1532277Y83807D02*
X1530678Y86367D01*
G01X1531617Y83068D02*
X1529788Y85998D01*
G01X1530678Y86367D02*
X1529920Y89650D01*
G01X1529788Y85998D02*
X1528945Y89650D01*
G01X1529920D02*
X1531250Y95419D01*
G01X1528945Y89650D02*
X1530274Y95419D01*
G01X1529425Y70497D02*
X1530736Y70173D01*
G01X1532920Y69634D02*
X1534231Y69310D01*
G01X1536415Y68771D02*
X1537726Y68447D01*
G01X1539910Y67908D02*
X1541221Y67584D01*
G01X1541430Y68511D02*
X1558527Y65034D01*
G01X1541221Y67584D02*
X1558156Y64139D01*
G01X1558527Y65034D02*
X1583125Y48750D01*
G01X1558156Y64139D02*
X1582768Y47846D01*
G01X1583125Y48750D02*
X1586132Y48243D01*
G01X1582768Y47846D02*
X1585599Y47369D01*
G01X1586132Y48243D02*
X1588173Y45517D01*
G01X1585599Y47369D02*
X1587223Y45200D01*
G01X1588173Y45517D02*
Y44259D01*
G01X1587223Y45200D02*
Y44259D01*
G01X1568323Y45200D02*
Y44259D01*
G01X1569273D02*
Y45542D01*
G01X1565474Y48645D02*
X1568323Y45200D01*
G01X1569273Y45542D02*
X1566134Y49338D01*
G01X1562044Y51208D02*
X1565192Y48856D01*
G01D02*
X1565474Y48645D01*
G01X1566134Y49338D02*
X1562434Y52103D01*
G01X1558673Y44459D02*
Y45400D01*
G01X1559623Y44459D02*
Y45742D01*
G01X1558673Y45400D02*
X1556751Y47725D01*
G01X1559623Y45742D02*
X1557265Y48595D01*
G01X1556751Y47725D02*
X1555424Y47976D01*
G01X1549523Y44536D02*
Y44259D01*
G01X1550473D02*
Y44879D01*
G01X1548902Y45284D02*
X1549523Y44536D01*
G01X1550473Y44879D02*
X1549414Y46155D01*
G01X1566134Y49338D02*
X1562434Y52103D01*
G01X1562044Y51208D02*
X1565192Y48856D01*
G01X1566134Y49338D02*
X1562434Y52103D01*
G01X1565192Y48856D02*
X1565474Y48645D01*
G01X1569273Y45542D02*
X1566134Y49338D01*
G01X1565474Y48645D02*
X1568323Y45200D01*
G01X1569273Y44259D02*
Y45542D01*
G01X1568323Y45200D02*
Y44259D01*
G01X1559623Y44459D02*
Y45742D01*
G01X1558673Y44459D02*
Y45400D01*
G01X1559623Y45742D02*
X1557265Y48595D01*
G01X1558673Y45400D02*
X1556751Y47725D01*
G01D02*
X1555424Y47976D01*
G01X1550473Y44879D02*
X1549414Y46155D01*
G01X1548902Y45284D02*
X1549523Y44536D01*
G01X1550473Y44259D02*
Y44879D01*
G01X1549523Y44536D02*
Y44259D01*
G01X1550573Y100432D02*
X1554633Y87192D01*
G01X1551563Y100447D02*
X1555505Y87593D01*
G01X1554633Y87192D02*
X1558800Y80601D01*
G01X1555505Y87593D02*
X1559478Y81307D01*
G01X1558800Y80601D02*
X1566825Y75973D01*
G01X1559478Y81307D02*
X1567641Y76600D01*
G01X1566825Y75973D02*
X1568031Y71488D01*
G01X1567641Y76600D02*
X1568856Y72082D01*
G01X1568031Y71488D02*
X1586199Y59460D01*
G01X1568856Y72082D02*
X1586568Y60356D01*
G01X1586199Y59460D02*
X1595194Y57662D01*
G01X1586568Y60356D02*
X1595565Y58558D01*
G01X1546406Y103958D02*
X1551854Y85883D01*
G01X1545418Y103942D02*
X1550983Y85478D01*
G01X1551854Y85883D02*
X1560387Y72980D01*
G01X1550982Y85478D02*
X1559701Y72294D01*
G01X1560387Y72980D02*
X1585477Y56376D01*
G01X1559701Y72294D02*
X1585108Y55480D01*
G01X1585477Y56376D02*
X1594492Y54574D01*
G01X1585108Y55480D02*
X1594121Y53679D01*
G01X1589262Y50599D02*
X1583978Y51655D01*
G01X1593311Y50758D02*
X1584347Y52551D01*
G01X1583978Y51655D02*
X1559697Y67727D01*
G01X1584347Y52551D02*
X1560067Y68622D01*
G01X1559697Y67727D02*
X1554196Y68842D01*
G01X1560067Y68622D02*
X1554757Y69699D01*
G01X1554196Y68842D02*
X1551817Y72236D01*
G01X1550526Y74078D02*
X1549751Y75184D01*
G01X1548460Y77026D02*
X1547407Y78529D01*
G01X1554757Y69699D02*
X1548082Y79222D01*
G01X1547407Y78529D02*
X1542677Y81662D01*
G01X1548082Y79222D02*
X1543048Y82557D01*
G01X1542677Y81662D02*
X1541263Y81949D01*
G01X1543048Y82557D02*
X1541263Y82919D01*
G01Y81949D02*
X1536150Y80907D01*
G01X1541263Y82919D02*
X1536272Y81902D01*
G01X1536150Y80907D02*
X1531617Y83068D01*
G01X1536272Y81902D02*
X1532277Y83807D01*
G01X1531617Y83068D02*
X1529788Y85998D01*
G01X1532277Y83807D02*
X1530678Y86367D01*
G01X1529788Y85998D02*
X1528945Y89650D01*
G01X1530678Y86367D02*
X1529920Y89650D01*
G01X1528945D02*
X1530274Y95419D01*
G01X1529920Y89650D02*
X1531250Y95419D01*
G01X1529425Y70497D02*
X1530736Y70173D01*
G01X1532920Y69634D02*
X1534231Y69310D01*
G01X1536415Y68771D02*
X1537726Y68447D01*
G01X1539910Y67908D02*
X1541221Y67584D01*
G01D02*
X1558156Y64139D01*
G01X1541430Y68511D02*
X1558527Y65034D01*
G01X1558156Y64139D02*
X1582768Y47846D01*
G01X1558527Y65034D02*
X1583125Y48750D01*
G01X1582768Y47846D02*
X1585599Y47369D01*
G01X1583125Y48750D02*
X1586132Y48243D01*
G01X1585599Y47369D02*
X1587223Y45200D01*
G01X1586132Y48243D02*
X1588173Y45517D01*
G01X1587223Y45200D02*
Y44259D01*
G01X1588173Y45517D02*
Y44259D01*
G01X1577773D02*
Y45200D01*
G01X1578723Y44259D02*
Y45542D01*
G01X1577773Y45200D02*
X1575551Y47887D01*
G01X1578723Y45542D02*
X1576196Y48600D01*
G01X1575551Y47887D02*
X1558370Y59260D01*
G01X1576196Y48600D02*
X1558730Y60161D01*
G01X1558370Y59260D02*
X1557042Y59504D01*
G01X1554829Y59910D02*
X1553501Y60154D01*
G01X1551289Y60561D02*
X1549961Y60805D01*
G01X1547748Y61211D02*
X1546420Y61455D01*
G01X1551563Y100447D02*
X1555505Y87593D01*
G01X1550573Y100432D02*
X1554633Y87192D01*
G01X1555505Y87593D02*
X1559478Y81307D01*
G01X1554633Y87192D02*
X1558800Y80601D01*
G01X1559478Y81307D02*
X1567641Y76600D01*
G01X1558800Y80601D02*
X1566825Y75973D01*
G01X1567641Y76600D02*
X1568856Y72082D01*
G01X1566825Y75973D02*
X1568031Y71488D01*
G01X1568856Y72082D02*
X1586568Y60356D01*
G01X1568031Y71488D02*
X1586199Y59460D01*
G01X1586568Y60356D02*
X1595565Y58558D01*
G01X1586199Y59460D02*
X1595194Y57662D01*
G01X1545418Y103942D02*
X1550983Y85478D01*
G01X1546406Y103958D02*
X1551854Y85883D01*
G01X1550982Y85478D02*
X1559701Y72294D01*
G01X1551854Y85883D02*
X1560387Y72980D01*
G01X1559701Y72294D02*
X1585108Y55480D01*
G01X1560387Y72980D02*
X1585477Y56376D01*
G01X1585108Y55480D02*
X1594121Y53679D01*
G01X1585477Y56376D02*
X1594492Y54574D01*
G01X1593311Y50758D02*
X1584347Y52551D01*
G01X1593311Y50758D02*
X1584347Y52551D01*
G01X1589262Y50599D02*
X1583978Y51655D01*
G01X1584347Y52551D02*
X1560067Y68622D01*
G01X1583978Y51655D02*
X1559697Y67727D01*
G01X1560067Y68622D02*
X1554757Y69699D01*
G01X1559697Y67727D02*
X1554196Y68842D01*
G01X1554757Y69699D02*
X1548082Y79222D01*
G01X1554196Y68842D02*
X1551817Y72236D01*
G01X1554757Y69699D02*
X1548082Y79222D01*
G01X1550526Y74078D02*
X1549751Y75184D01*
G01X1554757Y69699D02*
X1548082Y79222D01*
G01X1548460Y77026D02*
X1547407Y78529D01*
G01X1548082Y79222D02*
X1543048Y82557D01*
G01X1547407Y78529D02*
X1542677Y81662D01*
G01X1543048Y82557D02*
X1541263Y82919D01*
G01X1542677Y81662D02*
X1541263Y81949D01*
G01Y82919D02*
X1536272Y81902D01*
G01X1541263Y81949D02*
X1536150Y80907D01*
G01X1536272Y81902D02*
X1532277Y83807D01*
G01X1536150Y80907D02*
X1531617Y83068D01*
G01X1532277Y83807D02*
X1530678Y86367D01*
G01X1531617Y83068D02*
X1529788Y85998D01*
G01X1530678Y86367D02*
X1529920Y89650D01*
G01X1529788Y85998D02*
X1528945Y89650D01*
G01X1529920D02*
X1531250Y95419D01*
G01X1528945Y89650D02*
X1530274Y95419D01*
G01X1529425Y70497D02*
X1530736Y70173D01*
G01X1532920Y69634D02*
X1534231Y69310D01*
G01X1536415Y68771D02*
X1537726Y68447D01*
G01X1539910Y67908D02*
X1541221Y67584D01*
G01X1541430Y68511D02*
X1558527Y65034D01*
G01X1541221Y67584D02*
X1558156Y64139D01*
G01X1558527Y65034D02*
X1583125Y48750D01*
G01X1558156Y64139D02*
X1582768Y47846D01*
G01X1583125Y48750D02*
X1586132Y48243D01*
G01X1582768Y47846D02*
X1585599Y47369D01*
G01X1586132Y48243D02*
X1588173Y45517D01*
G01X1585599Y47369D02*
X1587223Y45200D01*
G01X1588173Y45517D02*
Y44259D01*
G01X1587223Y45200D02*
Y44259D01*
G01X1578723D02*
Y45542D01*
G01X1577773Y44259D02*
Y45200D01*
G01X1578723Y45542D02*
X1576196Y48600D01*
G01X1577773Y45200D02*
X1575551Y47887D01*
G01X1576196Y48600D02*
X1558730Y60161D01*
G01X1575551Y47887D02*
X1558370Y59260D01*
G01D02*
X1557042Y59504D01*
G01X1554829Y59910D02*
X1553501Y60154D01*
G01X1551289Y60561D02*
X1549961Y60805D01*
G01X1547748Y61211D02*
X1546420Y61455D01*
G01X1577773Y38209D02*
Y34962D01*
G01X1578723Y38209D02*
Y34934D01*
G01X1568323Y38209D02*
Y34962D01*
G01X1569273Y38209D02*
Y34934D01*
G01X1558673Y38409D02*
Y34762D01*
G01X1559623Y38409D02*
Y35134D01*
G01X1549523Y38209D02*
Y35062D01*
G01X1550473Y38209D02*
Y34834D01*
G01X1588173Y38209D02*
Y34934D01*
G01X1587223Y38209D02*
Y34962D01*
G01X1578723Y38209D02*
Y34934D01*
G01X1577773Y38209D02*
Y34962D01*
G01X1569273Y38209D02*
Y34934D01*
G01X1568323Y38209D02*
Y34962D01*
G01X1559623Y38409D02*
Y35134D01*
G01X1558673Y38409D02*
Y34762D01*
G01X1550473Y38209D02*
Y34834D01*
G01X1549523Y38209D02*
Y35062D01*
G01X1587223Y38209D02*
Y34962D01*
G01X1588173Y38209D02*
Y34934D01*
G01X1547343Y162421D02*
X1548945Y154547D01*
G01X1548238Y162792D02*
X1549915Y154547D01*
G01X1548945D02*
X1546937Y144673D01*
G01X1549915Y154547D02*
X1547907Y144673D01*
G01X1546937D02*
X1550600Y126678D01*
G01X1547907Y144673D02*
X1551571Y126675D01*
G01X1550600Y126678D02*
X1549972Y123673D01*
G01X1551571Y126675D02*
X1550943Y123670D01*
G01X1549972Y123673D02*
X1550241Y122350D01*
G01X1550689Y120145D02*
X1551891Y114230D01*
G01X1552339Y112025D02*
X1552939Y109075D01*
G01X1550943Y123670D02*
X1553916Y109042D01*
G01X1552939Y109075D02*
X1552583Y107773D01*
G01X1551988Y105603D02*
X1550573Y100432D01*
G01X1553916Y109042D02*
X1551563Y100447D01*
G01X1544503Y157769D02*
X1545522Y152756D01*
G01X1543608Y157398D02*
X1544552Y152756D01*
G01X1545522D02*
X1543952Y145033D01*
G01X1544552Y152756D02*
X1542982Y145033D01*
G01X1543952Y145032D02*
X1547617Y126746D01*
G01X1542982Y145033D02*
X1546647Y126747D01*
G01X1547617Y126746D02*
X1545896Y118288D01*
G01X1546647Y126747D02*
X1544926Y118288D01*
G01X1545896D02*
X1547780Y109033D01*
G01X1544926Y118288D02*
X1546803Y109064D01*
G01X1547780Y109033D02*
X1546406Y103958D01*
G01X1546804Y109064D02*
X1545417Y103942D01*
G01X1530274Y95419D02*
X1529042Y100754D01*
G01X1531250Y95419D02*
X1530018Y100754D01*
G01X1529042D02*
X1530196Y105751D01*
G01X1530018Y100754D02*
X1531172Y105751D01*
G01X1530196D02*
X1529093Y110533D01*
G01X1531172Y105751D02*
X1530069Y110533D01*
G01X1529093D02*
X1530463Y116464D01*
G01X1530069Y110533D02*
X1531439Y116464D01*
G01X1530463D02*
X1528164Y126417D01*
G01X1531439Y116464D02*
X1529082Y126666D01*
G01X1528164Y126417D02*
X1528076Y126505D01*
G01X1529082Y126844D02*
X1528681Y127245D01*
G01X1548238Y162792D02*
X1549915Y154547D01*
G01X1547343Y162421D02*
X1548945Y154547D01*
G01X1549915D02*
X1547907Y144673D01*
G01X1548945Y154547D02*
X1546937Y144673D01*
G01X1547907D02*
X1551571Y126675D01*
G01X1546937Y144673D02*
X1550600Y126678D01*
G01X1551571Y126675D02*
X1550943Y123670D01*
G01X1550600Y126678D02*
X1549972Y123673D01*
G01X1550943Y123670D02*
X1553916Y109042D01*
G01X1549972Y123673D02*
X1550241Y122350D01*
G01X1550943Y123670D02*
X1553916Y109042D01*
G01X1550689Y120145D02*
X1551891Y114230D01*
G01X1550943Y123670D02*
X1553916Y109042D01*
G01X1552339Y112025D02*
X1552939Y109075D01*
G01X1553916Y109042D02*
X1551563Y100447D01*
G01X1552939Y109075D02*
X1552583Y107773D01*
G01X1553916Y109042D02*
X1551563Y100447D01*
G01X1551988Y105603D02*
X1550573Y100432D01*
G01X1543608Y157398D02*
X1544552Y152756D01*
G01X1544503Y157769D02*
X1545522Y152756D01*
G01X1544552D02*
X1542982Y145033D01*
G01X1545522Y152756D02*
X1543952Y145033D01*
G01X1542982D02*
X1546647Y126747D01*
G01X1543952Y145032D02*
X1547617Y126746D01*
G01X1546647Y126747D02*
X1544926Y118288D01*
G01X1547617Y126746D02*
X1545896Y118288D01*
G01X1544926D02*
X1546803Y109064D01*
G01X1545896Y118288D02*
X1547780Y109033D01*
G01X1546804Y109064D02*
X1545417Y103942D01*
G01X1547780Y109033D02*
X1546406Y103958D01*
G01X1531250Y95419D02*
X1530018Y100754D01*
G01X1530274Y95419D02*
X1529042Y100754D01*
G01X1530018D02*
X1531172Y105751D01*
G01X1529042Y100754D02*
X1530196Y105751D01*
G01X1531172D02*
X1530069Y110533D01*
G01X1530196Y105751D02*
X1529093Y110533D01*
G01X1530069D02*
X1531439Y116464D01*
G01X1529093Y110533D02*
X1530463Y116464D01*
G01X1531439D02*
X1529082Y126666D01*
G01X1530463Y116464D02*
X1528164Y126417D01*
G01X1529082Y126844D02*
X1528681Y127245D01*
G01X1528164Y126417D02*
X1528076Y126505D01*
G01X1547343Y162421D02*
X1548945Y154547D01*
G01X1548238Y162792D02*
X1549915Y154547D01*
G01X1548945D02*
X1546937Y144673D01*
G01X1549915Y154547D02*
X1547907Y144673D01*
G01X1546937D02*
X1550600Y126678D01*
G01X1547907Y144673D02*
X1551571Y126675D01*
G01X1550600Y126678D02*
X1549972Y123673D01*
G01X1551571Y126675D02*
X1550943Y123670D01*
G01X1549972Y123673D02*
X1550241Y122350D01*
G01X1550689Y120145D02*
X1551891Y114230D01*
G01X1552339Y112025D02*
X1552939Y109075D01*
G01X1550943Y123670D02*
X1553916Y109042D01*
G01X1552939Y109075D02*
X1552583Y107773D01*
G01X1551988Y105603D02*
X1550573Y100432D01*
G01X1553916Y109042D02*
X1551563Y100447D01*
G01X1544503Y157769D02*
X1545522Y152756D01*
G01X1543608Y157398D02*
X1544552Y152756D01*
G01X1545522D02*
X1543952Y145033D01*
G01X1544552Y152756D02*
X1542982Y145033D01*
G01X1543952Y145032D02*
X1547617Y126746D01*
G01X1542982Y145033D02*
X1546647Y126747D01*
G01X1547617Y126746D02*
X1545896Y118288D01*
G01X1546647Y126747D02*
X1544926Y118288D01*
G01X1545896D02*
X1547780Y109033D01*
G01X1544926Y118288D02*
X1546803Y109064D01*
G01X1547780Y109033D02*
X1546406Y103958D01*
G01X1546804Y109064D02*
X1545417Y103942D01*
G01X1530274Y95419D02*
X1529042Y100754D01*
G01X1531250Y95419D02*
X1530018Y100754D01*
G01X1529042D02*
X1530196Y105751D01*
G01X1530018Y100754D02*
X1531172Y105751D01*
G01X1530196D02*
X1529093Y110533D01*
G01X1531172Y105751D02*
X1530069Y110533D01*
G01X1529093D02*
X1530463Y116464D01*
G01X1530069Y110533D02*
X1531439Y116464D01*
G01X1530463D02*
X1528164Y126417D01*
G01X1531439Y116464D02*
X1529082Y126666D01*
G01X1528164Y126417D02*
X1528076Y126505D01*
G01X1529082Y126844D02*
X1528681Y127245D01*
G01X1548238Y162792D02*
X1549915Y154547D01*
G01X1547343Y162421D02*
X1548945Y154547D01*
G01X1549915D02*
X1547907Y144673D01*
G01X1548945Y154547D02*
X1546937Y144673D01*
G01X1547907D02*
X1551571Y126675D01*
G01X1546937Y144673D02*
X1550600Y126678D01*
G01X1551571Y126675D02*
X1550943Y123670D01*
G01X1550600Y126678D02*
X1549972Y123673D01*
G01X1550943Y123670D02*
X1553916Y109042D01*
G01X1549972Y123673D02*
X1550241Y122350D01*
G01X1550943Y123670D02*
X1553916Y109042D01*
G01X1550689Y120145D02*
X1551891Y114230D01*
G01X1550943Y123670D02*
X1553916Y109042D01*
G01X1552339Y112025D02*
X1552939Y109075D01*
G01X1553916Y109042D02*
X1551563Y100447D01*
G01X1552939Y109075D02*
X1552583Y107773D01*
G01X1553916Y109042D02*
X1551563Y100447D01*
G01X1551988Y105603D02*
X1550573Y100432D01*
G01X1543608Y157398D02*
X1544552Y152756D01*
G01X1544503Y157769D02*
X1545522Y152756D01*
G01X1544552D02*
X1542982Y145033D01*
G01X1545522Y152756D02*
X1543952Y145033D01*
G01X1542982D02*
X1546647Y126747D01*
G01X1543952Y145032D02*
X1547617Y126746D01*
G01X1546647Y126747D02*
X1544926Y118288D01*
G01X1547617Y126746D02*
X1545896Y118288D01*
G01X1544926D02*
X1546803Y109064D01*
G01X1545896Y118288D02*
X1547780Y109033D01*
G01X1546804Y109064D02*
X1545417Y103942D01*
G01X1547780Y109033D02*
X1546406Y103958D01*
G01X1531250Y95419D02*
X1530018Y100754D01*
G01X1530274Y95419D02*
X1529042Y100754D01*
G01X1530018D02*
X1531172Y105751D01*
G01X1529042Y100754D02*
X1530196Y105751D01*
G01X1531172D02*
X1530069Y110533D01*
G01X1530196Y105751D02*
X1529093Y110533D01*
G01X1530069D02*
X1531439Y116464D01*
G01X1529093Y110533D02*
X1530463Y116464D01*
G01X1531439D02*
X1529082Y126666D01*
G01X1530463Y116464D02*
X1528164Y126417D01*
G01X1529082Y126844D02*
X1528681Y127245D01*
G01X1528164Y126417D02*
X1528076Y126505D01*
G01X1560100Y126300D02*
X1559250D01*
G01X1558856Y127250D02*
X1559706D01*
G01X1562225Y128425D02*
X1560100Y126300D01*
G01X1559706Y127250D02*
X1561831Y129375D01*
G01X1566789Y128425D02*
X1562225D01*
G01X1561831Y129375D02*
X1565079D01*
G01X1588582Y125229D02*
X1593427D01*
G01X1593821Y126179D02*
X1588188D01*
G01X1586879Y123526D02*
X1588582Y125229D01*
G01X1588188Y126179D02*
X1586485Y124476D01*
G01X1571688Y123526D02*
X1586879D01*
G01X1586485Y124476D02*
X1572082D01*
G01X1569492Y125722D02*
X1566789Y128425D01*
G01X1569492Y125722D02*
X1571688Y123526D01*
G01X1572082Y124476D02*
X1567183Y129375D01*
G01X1566789Y128425D02*
X1562225D01*
G01X1567183Y129375D02*
X1565079D01*
G01X1560100Y126300D02*
X1559250D01*
G01X1558856Y127250D02*
X1559706D01*
G01X1562225Y128425D02*
X1560100Y126300D01*
G01X1559706Y127250D02*
X1561831Y129375D01*
G01X1566789Y128425D02*
X1562225D01*
G01X1561831Y129375D02*
X1565079D01*
G01X1588582Y125229D02*
X1593427D01*
G01X1593821Y126179D02*
X1588188D01*
G01X1586879Y123526D02*
X1588582Y125229D01*
G01X1588188Y126179D02*
X1586485Y124476D01*
G01X1571688Y123526D02*
X1586879D01*
G01X1586485Y124476D02*
X1572082D01*
G01X1569492Y125722D02*
X1566789Y128425D01*
G01X1569492Y125722D02*
X1571688Y123526D01*
G01X1572082Y124476D02*
X1567183Y129375D01*
G01X1566789Y128425D02*
X1562225D01*
G01X1567183Y129375D02*
X1565079D01*
G01X1572082Y124476D02*
X1567183Y129375D01*
G01X1569492Y125722D02*
X1566789Y128425D01*
G01X1561831Y129375D02*
X1565079D01*
G01X1567183D02*
X1565079D01*
G01X1566789Y128425D02*
X1562225D01*
G01X1559706Y127250D02*
X1561831Y129375D01*
G01X1562225Y128425D02*
X1560100Y126300D01*
G01X1558856Y127250D02*
X1559706D01*
G01X1560100Y126300D02*
X1559250D01*
G01X1572082Y124476D02*
X1567183Y129375D01*
G01X1569492Y125722D02*
X1571688Y123526D01*
G01X1586485Y124476D02*
X1572082D01*
G01X1571688Y123526D02*
X1586879D01*
G01X1588188Y126179D02*
X1586485Y124476D01*
G01X1586879Y123526D02*
X1588582Y125229D01*
G01X1593821Y126179D02*
X1588188D01*
G01X1588582Y125229D02*
X1593427D01*
G01X1572082Y124476D02*
X1567183Y129375D01*
G01X1569492Y125722D02*
X1566789Y128425D01*
G01X1561831Y129375D02*
X1565079D01*
G01X1567183D02*
X1565079D01*
G01X1566789Y128425D02*
X1562225D01*
G01X1559706Y127250D02*
X1561831Y129375D01*
G01X1562225Y128425D02*
X1560100Y126300D01*
G01X1558856Y127250D02*
X1559706D01*
G01X1560100Y126300D02*
X1559250D01*
G01X1572082Y124476D02*
X1567183Y129375D01*
G01X1569492Y125722D02*
X1571688Y123526D01*
G01X1586485Y124476D02*
X1572082D01*
G01X1571688Y123526D02*
X1586879D01*
G01X1588188Y126179D02*
X1586485Y124476D01*
G01X1586879Y123526D02*
X1588582Y125229D01*
G01X1593821Y126179D02*
X1588188D01*
G01X1588582Y125229D02*
X1593427D01*
G01X1562380Y104280D02*
X1571075Y112975D01*
G01X1563032Y106276D02*
X1565133Y108377D01*
G01X1562380Y104280D02*
X1571075Y112975D01*
G01X1566087Y109968D02*
X1566724D01*
G01X1562380Y104280D02*
X1571075Y112975D01*
G01X1566724Y109968D02*
X1570681Y113925D01*
G01X1571075Y112975D02*
X1574085D01*
G01X1570681Y113925D02*
X1573691D01*
G01X1576148Y115038D02*
X1579236Y118126D01*
G01X1574085Y112975D02*
X1576148Y115038D01*
G01X1573691Y113925D02*
X1578842Y119076D01*
G01X1579236Y118126D02*
X1599567D01*
G01X1578842Y119076D02*
X1584542D01*
G01X1579236Y118126D02*
X1599567D01*
G01X1586792Y119076D02*
X1588142D01*
G01X1579236Y118126D02*
X1599567D01*
G01X1579236D02*
X1599567D01*
G01X1579236D02*
X1599567D01*
G01X1557075Y102575D02*
X1558780Y104280D01*
G01X1556050Y102894D02*
X1558386Y105230D01*
G01X1558780Y104280D02*
X1562380D01*
G01X1558386Y105230D02*
X1561986D01*
G01X1562380Y104280D02*
X1571075Y112975D01*
G01X1561986Y105230D02*
X1563032Y106276D01*
G01X1562380Y104280D02*
X1571075Y112975D01*
G01X1563032Y106276D02*
X1565133Y108377D01*
G01X1562380Y104280D02*
X1571075Y112975D01*
G01X1566087Y109968D02*
X1566724D01*
G01X1562380Y104280D02*
X1571075Y112975D01*
G01X1566724Y109968D02*
X1570681Y113925D01*
G01X1571075Y112975D02*
X1574085D01*
G01X1570681Y113925D02*
X1573691D01*
G01X1576148Y115038D02*
X1579236Y118126D01*
G01X1574085Y112975D02*
X1576148Y115038D01*
G01X1573691Y113925D02*
X1578842Y119076D01*
G01X1579236Y118126D02*
X1599567D01*
G01X1578842Y119076D02*
X1584542D01*
G01X1579236Y118126D02*
X1599567D01*
G01X1586792Y119076D02*
X1588142D01*
G01X1579236Y118126D02*
X1599567D01*
G01X1579236D02*
X1599567D01*
G01X1579236D02*
X1599567D01*
G01X1557075Y102575D02*
X1558780Y104280D01*
G01X1556050Y102894D02*
X1558386Y105230D01*
G01X1558780Y104280D02*
X1562380D01*
G01X1558386Y105230D02*
X1561986D01*
G01X1562380Y104280D02*
X1571075Y112975D01*
G01X1561986Y105230D02*
X1563032Y106276D01*
G01X1573691Y113925D02*
X1578842Y119076D01*
G01X1576148Y115038D02*
X1579236Y118126D01*
G01X1578842Y119076D02*
X1584542D01*
G01X1586792D02*
X1588142D01*
G01X1579236Y118126D02*
X1599567D01*
G01X1556050Y102894D02*
X1558386Y105230D01*
G01X1557075Y102575D02*
X1558780Y104280D01*
G01X1558386Y105230D02*
X1561986D01*
G01X1558780Y104280D02*
X1562380D01*
G01X1563032Y106276D02*
X1565133Y108377D01*
G01X1566087Y109968D02*
X1566724D01*
G01D02*
X1570681Y113925D01*
G01X1561986Y105230D02*
X1563032Y106276D01*
G01X1562380Y104280D02*
X1571075Y112975D01*
G01X1570681Y113925D02*
X1573691D01*
G01X1571075Y112975D02*
X1574085D01*
G01X1573691Y113925D02*
X1578842Y119076D01*
G01X1574085Y112975D02*
X1576148Y115038D01*
G01X1573691Y113925D02*
X1578842Y119076D01*
G01X1576148Y115038D02*
X1579236Y118126D01*
G01X1578842Y119076D02*
X1584542D01*
G01X1586792D02*
X1588142D01*
G01X1579236Y118126D02*
X1599567D01*
G01X1556050Y102894D02*
X1558386Y105230D01*
G01X1557075Y102575D02*
X1558780Y104280D01*
G01X1558386Y105230D02*
X1561986D01*
G01X1558780Y104280D02*
X1562380D01*
G01X1563032Y106276D02*
X1565133Y108377D01*
G01X1566087Y109968D02*
X1566724D01*
G01D02*
X1570681Y113925D01*
G01X1561986Y105230D02*
X1563032Y106276D01*
G01X1562380Y104280D02*
X1571075Y112975D01*
G01X1570681Y113925D02*
X1573691D01*
G01X1571075Y112975D02*
X1574085D01*
G01X1573691Y113925D02*
X1578842Y119076D01*
G01X1574085Y112975D02*
X1576148Y115038D01*
G01X1562380Y104280D02*
X1571075Y112975D01*
G01X1563032Y106276D02*
X1565133Y108377D01*
G01X1562380Y104280D02*
X1571075Y112975D01*
G01X1566087Y109968D02*
X1566724D01*
G01X1562380Y104280D02*
X1571075Y112975D01*
G01X1566724Y109968D02*
X1570681Y113925D01*
G01X1571075Y112975D02*
X1574085D01*
G01X1570681Y113925D02*
X1573691D01*
G01X1576148Y115038D02*
X1579236Y118126D01*
G01X1574085Y112975D02*
X1576148Y115038D01*
G01X1573691Y113925D02*
X1578842Y119076D01*
G01X1579236Y118126D02*
X1599567D01*
G01X1578842Y119076D02*
X1584542D01*
G01X1579236Y118126D02*
X1599567D01*
G01X1586792Y119076D02*
X1588142D01*
G01X1579236Y118126D02*
X1599567D01*
G01X1579236D02*
X1599567D01*
G01X1579236D02*
X1599567D01*
G01X1557075Y102575D02*
X1558780Y104280D01*
G01X1556050Y102894D02*
X1558386Y105230D01*
G01X1558780Y104280D02*
X1562380D01*
G01X1558386Y105230D02*
X1561986D01*
G01X1562380Y104280D02*
X1571075Y112975D01*
G01X1561986Y105230D02*
X1563032Y106276D01*
G01X1560100Y126300D02*
X1559250D01*
G01X1558856Y127250D02*
X1559706D01*
G01X1562225Y128425D02*
X1560100Y126300D01*
G01X1559706Y127250D02*
X1561831Y129375D01*
G01X1566789Y128425D02*
X1562225D01*
G01X1561831Y129375D02*
X1565079D01*
G01X1588582Y125229D02*
X1593427D01*
G01X1593821Y126179D02*
X1588188D01*
G01X1586879Y123526D02*
X1588582Y125229D01*
G01X1588188Y126179D02*
X1586485Y124476D01*
G01X1571688Y123526D02*
X1586879D01*
G01X1586485Y124476D02*
X1572082D01*
G01X1569492Y125722D02*
X1566789Y128425D01*
G01X1569492Y125722D02*
X1571688Y123526D01*
G01X1572082Y124476D02*
X1567183Y129375D01*
G01X1566789Y128425D02*
X1562225D01*
G01X1567183Y129375D02*
X1565079D01*
G01X1572082Y124476D02*
X1567183Y129375D01*
G01X1569492Y125722D02*
X1566789Y128425D01*
G01X1561831Y129375D02*
X1565079D01*
G01X1567183D02*
X1565079D01*
G01X1566789Y128425D02*
X1562225D01*
G01X1559706Y127250D02*
X1561831Y129375D01*
G01X1562225Y128425D02*
X1560100Y126300D01*
G01X1558856Y127250D02*
X1559706D01*
G01X1560100Y126300D02*
X1559250D01*
G01X1572082Y124476D02*
X1567183Y129375D01*
G01X1569492Y125722D02*
X1571688Y123526D01*
G01X1586485Y124476D02*
X1572082D01*
G01X1571688Y123526D02*
X1586879D01*
G01X1588188Y126179D02*
X1586485Y124476D01*
G01X1586879Y123526D02*
X1588582Y125229D01*
G01X1593821Y126179D02*
X1588188D01*
G01X1588582Y125229D02*
X1593427D01*
G01X1573691Y113925D02*
X1578842Y119076D01*
G01X1576148Y115038D02*
X1579236Y118126D01*
G01X1578842Y119076D02*
X1584542D01*
G01X1586792D02*
X1588142D01*
G01X1579236Y118126D02*
X1599567D01*
G01X1556050Y102894D02*
X1558386Y105230D01*
G01X1557075Y102575D02*
X1558780Y104280D01*
G01X1558386Y105230D02*
X1561986D01*
G01X1558780Y104280D02*
X1562380D01*
G01X1563032Y106276D02*
X1565133Y108377D01*
G01X1566087Y109968D02*
X1566724D01*
G01D02*
X1570681Y113925D01*
G01X1561986Y105230D02*
X1563032Y106276D01*
G01X1562380Y104280D02*
X1571075Y112975D01*
G01X1570681Y113925D02*
X1573691D01*
G01X1571075Y112975D02*
X1574085D01*
G01X1573691Y113925D02*
X1578842Y119076D01*
G01X1574085Y112975D02*
X1576148Y115038D01*
G01X1528163Y174451D02*
X1533496Y173366D01*
G01X1528534Y175346D02*
X1533867Y174261D01*
G01X1533496Y173366D02*
X1545250Y165587D01*
G01X1533867Y174261D02*
X1545936Y166273D01*
G01X1545250Y165587D02*
X1547343Y162421D01*
G01X1545936Y166273D02*
X1548238Y162792D01*
G01X1532068Y170555D02*
X1539245Y165713D01*
G01X1531694Y169661D02*
X1538557Y165031D01*
G01X1539245Y165713D02*
X1544503Y157769D01*
G01X1538557Y165031D02*
X1543608Y157398D01*
G01X1528534Y175346D02*
X1533867Y174261D01*
G01X1528163Y174451D02*
X1533496Y173366D01*
G01X1533867Y174261D02*
X1545936Y166273D01*
G01X1533496Y173366D02*
X1545250Y165587D01*
G01X1545936Y166273D02*
X1548238Y162792D01*
G01X1545250Y165587D02*
X1547343Y162421D01*
G01X1531694Y169661D02*
X1538557Y165031D01*
G01X1532068Y170555D02*
X1539245Y165713D01*
G01X1538557Y165031D02*
X1543608Y157398D01*
G01X1539245Y165713D02*
X1544503Y157769D01*
G01X1528163Y174451D02*
X1533496Y173366D01*
G01X1528534Y175346D02*
X1533867Y174261D01*
G01X1533496Y173366D02*
X1545250Y165587D01*
G01X1533867Y174261D02*
X1545936Y166273D01*
G01X1545250Y165587D02*
X1547343Y162421D01*
G01X1545936Y166273D02*
X1548238Y162792D01*
G01X1532068Y170555D02*
X1539245Y165713D01*
G01X1531694Y169661D02*
X1538557Y165031D01*
G01X1539245Y165713D02*
X1544503Y157769D01*
G01X1538557Y165031D02*
X1543608Y157398D01*
G01X1528534Y175346D02*
X1533867Y174261D01*
G01X1528163Y174451D02*
X1533496Y173366D01*
G01X1533867Y174261D02*
X1545936Y166273D01*
G01X1533496Y173366D02*
X1545250Y165587D01*
G01X1545936Y166273D02*
X1548238Y162792D01*
G01X1545250Y165587D02*
X1547343Y162421D01*
G01X1531694Y169661D02*
X1538557Y165031D01*
G01X1532068Y170555D02*
X1539245Y165713D01*
G01X1538557Y165031D02*
X1543608Y157398D01*
G01X1539245Y165713D02*
X1544503Y157769D01*
G01X1582945Y522299D02*
X1592387Y512857D01*
G01X1591715Y512185D02*
X1582273Y521627D01*
G01X1580501Y523311D02*
G02X1582945Y522299I0J-3457D01*
G01X1582273Y521627D02*
G03X1580501Y522361I-1772J-1772D01*
G01X1576796Y523311D02*
X1580501D01*
G01X1564771D02*
X1576796D01*
G01X1580501Y522361D02*
X1567064D01*
G01X1564771Y523311D02*
X1576796D01*
G01X1567064Y522361D02*
X1564771D01*
G01X1580501D02*
X1567064D01*
G01X1576796Y523311D02*
X1580501D01*
G01X1582273Y521627D02*
G03X1580501Y522361I-1772J-1772D01*
G01Y523311D02*
G02X1582945Y522299I0J-3457D01*
G01X1591715Y512185D02*
X1582273Y521627D01*
G01X1582945Y522299D02*
X1592387Y512857D01*
G01X1580501Y522361D02*
X1567064D01*
G01D02*
X1564771D01*
G01Y523311D02*
X1576796D01*
G01X1582945Y522299D02*
X1592387Y512857D01*
G01X1591715Y512185D02*
X1582273Y521627D01*
G01X1580501Y523311D02*
G02X1582945Y522299I0J-3457D01*
G01X1582273Y521627D02*
G03X1580501Y522361I-1772J-1772D01*
G01X1576796Y523311D02*
X1580501D01*
G01X1564771D02*
X1576796D01*
G01X1580501Y522361D02*
X1567064D01*
G01X1564771Y523311D02*
X1576796D01*
G01X1567064Y522361D02*
X1564771D01*
G01X1580501D02*
X1567064D01*
G01X1576796Y523311D02*
X1580501D01*
G01X1582273Y521627D02*
G03X1580501Y522361I-1772J-1772D01*
G01Y523311D02*
G02X1582945Y522299I0J-3457D01*
G01X1591715Y512185D02*
X1582273Y521627D01*
G01X1582945Y522299D02*
X1592387Y512857D01*
G01X1580501Y522361D02*
X1567064D01*
G01D02*
X1564771D01*
G01Y523311D02*
X1576796D01*
G01X1603873Y13660D02*
Y11805D01*
G01X1602923Y13732D02*
Y11805D01*
G01X1612409Y13696D02*
Y9049D01*
G01X1613359Y13696D02*
Y8655D01*
G01X1612409Y9049D02*
X1611858Y8498D01*
G01X1613359Y8655D02*
X1612808Y8104D01*
G01X1611858Y8498D02*
Y5875D01*
G01X1612808Y8104D02*
Y5875D01*
G01X1602923Y13732D02*
Y11805D01*
G01X1603873Y13660D02*
Y11805D01*
G01X1593409Y11915D02*
Y13796D01*
G01X1594359Y11847D02*
Y13596D01*
G01X1613359Y13696D02*
Y8655D01*
G01X1612409Y13696D02*
Y9049D01*
G01X1613359Y8655D02*
X1612808Y8104D01*
G01X1612409Y9049D02*
X1611858Y8498D01*
G01X1612808Y8104D02*
Y5875D01*
G01X1611858Y8498D02*
Y5875D01*
G01X1594359Y11847D02*
Y13596D01*
G01X1593409Y11915D02*
Y13796D01*
G01X1612409Y13696D02*
Y9049D01*
G01X1613359Y13696D02*
Y8655D01*
G01X1612409Y9049D02*
X1611858Y8498D01*
G01X1613359Y8655D02*
X1612808Y8104D01*
G01X1611858Y8498D02*
Y5875D01*
G01X1612808Y8104D02*
Y5875D01*
G01X1602923Y13732D02*
Y11805D01*
G01X1603873Y13660D02*
Y11805D01*
G01X1593409Y11915D02*
Y13796D01*
G01X1594359Y11847D02*
Y13596D01*
G01X1613359Y13696D02*
Y8655D01*
G01X1612409Y13696D02*
Y9049D01*
G01X1613359Y8655D02*
X1612808Y8104D01*
G01X1612409Y9049D02*
X1611858Y8498D01*
G01X1612808Y8104D02*
Y5875D01*
G01X1611858Y8498D02*
Y5875D01*
G01X1603873Y13660D02*
Y11805D01*
G01X1602923Y13732D02*
Y11805D01*
G01X1594359Y11847D02*
Y13596D01*
G01X1593409Y11915D02*
Y13796D01*
G01X1621859Y13460D02*
Y11800D01*
G01X1622809Y13460D02*
Y11800D01*
G01X1631214Y13475D02*
Y7316D01*
G01X1632164Y7537D02*
Y13441D01*
G01X1640878Y11756D02*
Y13281D01*
G01X1641828Y11656D02*
Y13219D01*
G01X1622809Y13460D02*
Y11800D01*
G01X1621859Y13460D02*
Y11800D01*
G01X1632164Y7537D02*
Y13441D01*
G01X1631214Y13475D02*
Y7316D01*
G01X1641828Y11656D02*
Y13219D01*
G01X1640878Y11756D02*
Y13281D01*
G01X1650782Y9256D02*
X1650209Y9829D01*
G01D02*
Y13696D01*
G01X1650782Y9256D02*
X1650209Y9829D01*
G01D02*
Y13696D01*
G01X1595194Y57662D02*
X1610155Y47717D01*
G01X1595565Y58558D02*
X1610442Y48667D01*
G01X1610155Y47717D02*
X1614718D01*
G01X1610442Y48667D02*
X1615112D01*
G01X1614718Y47717D02*
X1615249Y47186D01*
G01X1615112Y48667D02*
X1616199Y47580D01*
G01X1615249Y47186D02*
Y46383D01*
G01X1616199Y47580D02*
Y46221D01*
G01X1594492Y54574D02*
X1600102Y50834D01*
G01X1594121Y53679D02*
X1599247Y50261D01*
G01X1600102Y50833D02*
X1605217Y47423D01*
G01X1600495Y48888D02*
X1601119Y49012D01*
G01X1600102Y50833D02*
X1605217Y47423D01*
G01X1601119Y49012D02*
X1602242Y48263D01*
G01X1600102Y50833D02*
X1605217Y47423D01*
G01X1604114Y47015D02*
X1604573Y46709D01*
G01X1605217Y47423D02*
X1607078Y45172D01*
G01X1604573Y46709D02*
X1606111Y44849D01*
G01X1607078Y45172D02*
X1607037Y44290D01*
G01X1606111Y44849D02*
X1606081Y44212D01*
G01X1596673Y44259D02*
Y45200D01*
G01X1597623Y44259D02*
Y45542D01*
G01X1596673Y45200D02*
X1592792Y49893D01*
G01X1597623Y45542D02*
X1593311Y50758D01*
G01X1592792Y49892D02*
X1591467Y50157D01*
G01X1595565Y58558D02*
X1610442Y48667D01*
G01X1595194Y57662D02*
X1610155Y47717D01*
G01X1610442Y48667D02*
X1615112D01*
G01X1610155Y47717D02*
X1614718D01*
G01X1615112Y48667D02*
X1616199Y47580D01*
G01X1614718Y47717D02*
X1615249Y47186D01*
G01X1616199Y47580D02*
Y46221D01*
G01X1615249Y47186D02*
Y46383D01*
G01X1594121Y53679D02*
X1599247Y50261D01*
G01X1594492Y54574D02*
X1600102Y50834D01*
G01X1600495Y48888D02*
X1601119Y49012D01*
G01D02*
X1602242Y48263D01*
G01X1604114Y47015D02*
X1604573Y46709D01*
G01X1600102Y50833D02*
X1605217Y47423D01*
G01X1604573Y46709D02*
X1606111Y44849D01*
G01X1605217Y47423D02*
X1607078Y45172D01*
G01X1606111Y44849D02*
X1606081Y44212D01*
G01X1607078Y45172D02*
X1607037Y44290D01*
G01X1597623Y44259D02*
Y45542D01*
G01X1596673Y44259D02*
Y45200D01*
G01X1597623Y45542D02*
X1593311Y50758D01*
G01X1596673Y45200D02*
X1592792Y49893D01*
G01Y49892D02*
X1591467Y50157D01*
G01X1595194Y57662D02*
X1610155Y47717D01*
G01X1595565Y58558D02*
X1610442Y48667D01*
G01X1610155Y47717D02*
X1614718D01*
G01X1610442Y48667D02*
X1615112D01*
G01X1614718Y47717D02*
X1615249Y47186D01*
G01X1615112Y48667D02*
X1616199Y47580D01*
G01X1615249Y47186D02*
Y46383D01*
G01X1616199Y47580D02*
Y46221D01*
G01X1594492Y54574D02*
X1600102Y50834D01*
G01X1594121Y53679D02*
X1599247Y50261D01*
G01X1600102Y50833D02*
X1605217Y47423D01*
G01X1600495Y48888D02*
X1601119Y49012D01*
G01X1600102Y50833D02*
X1605217Y47423D01*
G01X1601119Y49012D02*
X1602242Y48263D01*
G01X1600102Y50833D02*
X1605217Y47423D01*
G01X1604114Y47015D02*
X1604573Y46709D01*
G01X1605217Y47423D02*
X1607078Y45172D01*
G01X1604573Y46709D02*
X1606111Y44849D01*
G01X1607078Y45172D02*
X1607037Y44290D01*
G01X1606111Y44849D02*
X1606081Y44212D01*
G01X1596673Y44259D02*
Y45200D01*
G01X1597623Y44259D02*
Y45542D01*
G01X1596673Y45200D02*
X1592792Y49893D01*
G01X1597623Y45542D02*
X1593311Y50758D01*
G01X1592792Y49892D02*
X1591467Y50157D01*
G01X1595565Y58558D02*
X1610442Y48667D01*
G01X1595194Y57662D02*
X1610155Y47717D01*
G01X1610442Y48667D02*
X1615112D01*
G01X1610155Y47717D02*
X1614718D01*
G01X1615112Y48667D02*
X1616199Y47580D01*
G01X1614718Y47717D02*
X1615249Y47186D01*
G01X1616199Y47580D02*
Y46221D01*
G01X1615249Y47186D02*
Y46383D01*
G01X1594121Y53679D02*
X1599247Y50261D01*
G01X1594492Y54574D02*
X1600102Y50834D01*
G01X1600495Y48888D02*
X1601119Y49012D01*
G01D02*
X1602242Y48263D01*
G01X1604114Y47015D02*
X1604573Y46709D01*
G01X1600102Y50833D02*
X1605217Y47423D01*
G01X1604573Y46709D02*
X1606111Y44849D01*
G01X1605217Y47423D02*
X1607078Y45172D01*
G01X1606111Y44849D02*
X1606081Y44212D01*
G01X1607078Y45172D02*
X1607037Y44290D01*
G01X1597623Y44259D02*
Y45542D01*
G01X1596673Y44259D02*
Y45200D01*
G01X1597623Y45542D02*
X1593311Y50758D01*
G01X1596673Y45200D02*
X1592792Y49893D01*
G01Y49892D02*
X1591467Y50157D01*
G01X1615168Y40252D02*
Y38206D01*
G01X1616118Y40252D02*
Y38600D01*
G01X1615168Y38206D02*
X1615559Y37815D01*
G01X1616118Y38600D02*
X1616509Y38209D01*
G01X1615559Y37815D02*
Y34948D01*
G01X1616509Y38209D02*
Y34948D01*
G01X1607073Y38204D02*
Y34934D01*
G01X1606123Y38204D02*
Y34962D01*
G01X1596673Y38209D02*
Y34962D01*
G01X1597623Y38209D02*
Y34934D01*
G01X1616118Y40252D02*
Y38600D01*
G01X1615168Y40252D02*
Y38206D01*
G01X1616118Y38600D02*
X1616509Y38209D01*
G01X1615168Y38206D02*
X1615559Y37815D01*
G01X1616509Y38209D02*
Y34948D01*
G01X1615559Y37815D02*
Y34948D01*
G01X1606123Y38204D02*
Y34962D01*
G01X1607073Y38204D02*
Y34934D01*
G01X1597623Y38209D02*
Y34934D01*
G01X1596673Y38209D02*
Y34962D01*
G01X1624670Y39529D02*
Y34269D01*
G01X1625620Y39559D02*
Y34979D01*
G01X1634350Y39485D02*
Y35075D01*
G01X1635300Y39339D02*
Y35101D01*
G01X1643909Y35184D02*
Y38691D01*
G01X1644859Y35184D02*
Y38659D01*
G01X1625620Y39559D02*
Y34979D01*
G01X1624670Y39529D02*
Y34269D01*
G01X1635300Y39339D02*
Y35101D01*
G01X1634350Y39485D02*
Y35075D01*
G01X1644859Y35184D02*
Y38659D01*
G01X1643909Y35184D02*
Y38691D01*
G01X1600299Y124450D02*
X1601632D01*
G01X1601603Y125400D02*
X1599905D01*
G01X1599775Y123926D02*
X1600299Y124450D01*
G01X1599905Y125400D02*
X1599381Y124876D01*
G01X1594730Y123926D02*
X1599775D01*
G01X1599381Y124876D02*
X1595124D01*
G01X1593427Y125229D02*
X1594730Y123926D01*
G01X1595124Y124876D02*
X1593821Y126179D01*
G01X1600299Y124450D02*
X1601632D01*
G01X1601603Y125400D02*
X1599905D01*
G01X1599775Y123926D02*
X1600299Y124450D01*
G01X1599905Y125400D02*
X1599381Y124876D01*
G01X1594730Y123926D02*
X1599775D01*
G01X1599381Y124876D02*
X1595124D01*
G01X1593427Y125229D02*
X1594730Y123926D01*
G01X1595124Y124876D02*
X1593821Y126179D01*
G01X1595124Y124876D02*
X1593821Y126179D01*
G01X1593427Y125229D02*
X1594730Y123926D01*
G01X1599381Y124876D02*
X1595124D01*
G01X1594730Y123926D02*
X1599775D01*
G01X1599905Y125400D02*
X1599381Y124876D01*
G01X1599775Y123926D02*
X1600299Y124450D01*
G01X1601603Y125400D02*
X1599905D01*
G01X1600299Y124450D02*
X1601632D01*
G01X1595124Y124876D02*
X1593821Y126179D01*
G01X1593427Y125229D02*
X1594730Y123926D01*
G01X1599381Y124876D02*
X1595124D01*
G01X1594730Y123926D02*
X1599775D01*
G01X1599905Y125400D02*
X1599381Y124876D01*
G01X1599775Y123926D02*
X1600299Y124450D01*
G01X1601603Y125400D02*
X1599905D01*
G01X1600299Y124450D02*
X1601632D01*
G01X1590392Y119076D02*
X1591742D01*
G01X1593992D02*
X1595342D01*
G01X1597592D02*
X1599173D01*
G01X1599567Y118126D02*
X1599882Y118441D01*
G01X1599173Y119076D02*
X1599497Y119400D01*
G01X1599882Y118441D02*
X1604093D01*
G01X1599497Y119400D02*
X1601902D01*
G01X1590392Y119076D02*
X1591742D01*
G01X1593992D02*
X1595342D01*
G01X1597592D02*
X1599173D01*
G01X1599567Y118126D02*
X1599882Y118441D01*
G01X1599173Y119076D02*
X1599497Y119400D01*
G01X1599882Y118441D02*
X1604093D01*
G01X1599497Y119400D02*
X1601902D01*
G01X1590392Y119076D02*
X1591742D01*
G01X1593992D02*
X1595342D01*
G01X1597592D02*
X1599173D01*
G01D02*
X1599497Y119400D01*
G01X1599567Y118126D02*
X1599882Y118441D01*
G01X1599497Y119400D02*
X1601902D01*
G01X1599882Y118441D02*
X1604093D01*
G01X1590392Y119076D02*
X1591742D01*
G01X1593992D02*
X1595342D01*
G01X1597592D02*
X1599173D01*
G01D02*
X1599497Y119400D01*
G01X1599567Y118126D02*
X1599882Y118441D01*
G01X1599497Y119400D02*
X1601902D01*
G01X1599882Y118441D02*
X1604093D01*
G01X1590392Y119076D02*
X1591742D01*
G01X1593992D02*
X1595342D01*
G01X1597592D02*
X1599173D01*
G01X1599567Y118126D02*
X1599882Y118441D01*
G01X1599173Y119076D02*
X1599497Y119400D01*
G01X1599882Y118441D02*
X1604093D01*
G01X1599497Y119400D02*
X1601902D01*
G01X1600299Y124450D02*
X1601632D01*
G01X1601603Y125400D02*
X1599905D01*
G01X1599775Y123926D02*
X1600299Y124450D01*
G01X1599905Y125400D02*
X1599381Y124876D01*
G01X1594730Y123926D02*
X1599775D01*
G01X1599381Y124876D02*
X1595124D01*
G01X1593427Y125229D02*
X1594730Y123926D01*
G01X1595124Y124876D02*
X1593821Y126179D01*
G01X1595124Y124876D02*
X1593821Y126179D01*
G01X1593427Y125229D02*
X1594730Y123926D01*
G01X1599381Y124876D02*
X1595124D01*
G01X1594730Y123926D02*
X1599775D01*
G01X1599905Y125400D02*
X1599381Y124876D01*
G01X1599775Y123926D02*
X1600299Y124450D01*
G01X1601603Y125400D02*
X1599905D01*
G01X1600299Y124450D02*
X1601632D01*
G01X1590392Y119076D02*
X1591742D01*
G01X1593992D02*
X1595342D01*
G01X1597592D02*
X1599173D01*
G01D02*
X1599497Y119400D01*
G01X1599567Y118126D02*
X1599882Y118441D01*
G01X1599497Y119400D02*
X1601902D01*
G01X1599882Y118441D02*
X1604093D01*
G01X1620093Y184351D02*
Y183567D01*
G01X1621043Y184403D02*
Y183961D01*
G01X1620093Y183567D02*
X1629523Y174137D01*
G01X1621043Y183961D02*
X1621707Y183297D01*
G01X1620093Y183567D02*
X1629523Y174137D01*
G01X1623037Y181967D02*
X1623673Y181331D01*
G01X1620093Y183567D02*
X1629523Y174137D01*
G01X1625003Y180001D02*
X1625639Y179365D01*
G01X1620093Y183567D02*
X1629523Y174137D01*
G01X1626969Y178035D02*
X1627605Y177399D01*
G01X1620093Y183567D02*
X1629523Y174137D01*
G01X1628935Y176069D02*
X1630473Y174531D01*
G01X1629523Y174137D02*
Y170539D01*
G01X1630473Y174531D02*
Y173740D01*
G01X1629523Y174137D02*
Y170539D01*
G01X1630473Y171859D02*
Y170884D01*
G01X1620093Y184351D02*
Y183567D01*
G01X1621043Y184403D02*
Y183961D01*
G01X1620093Y183567D02*
X1629523Y174137D01*
G01X1621043Y183961D02*
X1621707Y183297D01*
G01X1620093Y183567D02*
X1629523Y174137D01*
G01X1623037Y181967D02*
X1623673Y181331D01*
G01X1620093Y183567D02*
X1629523Y174137D01*
G01X1625003Y180001D02*
X1625639Y179365D01*
G01X1620093Y183567D02*
X1629523Y174137D01*
G01X1626969Y178035D02*
X1627605Y177399D01*
G01X1620093Y183567D02*
X1629523Y174137D01*
G01X1628935Y176069D02*
X1630473Y174531D01*
G01X1629523Y174137D02*
Y170539D01*
G01X1630473Y174531D02*
Y173740D01*
G01X1629523Y174137D02*
Y170539D01*
G01X1630473Y171859D02*
Y170884D01*
G01X1621043Y184403D02*
Y183961D01*
G01X1620093Y184351D02*
Y183567D01*
G01X1621043Y183961D02*
X1621707Y183297D01*
G01X1623037Y181967D02*
X1623673Y181331D01*
G01X1625003Y180001D02*
X1625639Y179365D01*
G01X1626969Y178035D02*
X1627605Y177399D01*
G01X1628935Y176069D02*
X1630473Y174531D01*
G01X1620093Y183567D02*
X1629523Y174137D01*
G01X1630473Y174531D02*
Y173740D01*
G01Y171859D02*
Y170884D01*
G01X1629523Y174137D02*
Y170539D01*
G01X1621043Y184403D02*
Y183961D01*
G01X1620093Y184351D02*
Y183567D01*
G01X1621043Y183961D02*
X1621707Y183297D01*
G01X1623037Y181967D02*
X1623673Y181331D01*
G01X1625003Y180001D02*
X1625639Y179365D01*
G01X1626969Y178035D02*
X1627605Y177399D01*
G01X1628935Y176069D02*
X1630473Y174531D01*
G01X1620093Y183567D02*
X1629523Y174137D01*
G01X1630473Y174531D02*
Y173740D01*
G01Y171859D02*
Y170884D01*
G01X1629523Y174137D02*
Y170539D01*
G01X1620093Y184351D02*
Y183567D01*
G01X1621043Y184403D02*
Y183961D01*
G01X1620093Y183567D02*
X1629523Y174137D01*
G01X1621043Y183961D02*
X1621707Y183297D01*
G01X1620093Y183567D02*
X1629523Y174137D01*
G01X1623037Y181967D02*
X1623673Y181331D01*
G01X1620093Y183567D02*
X1629523Y174137D01*
G01X1625003Y180001D02*
X1625639Y179365D01*
G01X1620093Y183567D02*
X1629523Y174137D01*
G01X1626969Y178035D02*
X1627605Y177399D01*
G01X1620093Y183567D02*
X1629523Y174137D01*
G01X1628935Y176069D02*
X1630473Y174531D01*
G01X1629523Y174137D02*
Y170539D01*
G01X1630473Y174531D02*
Y173740D01*
G01X1629523Y174137D02*
Y170539D01*
G01X1630473Y171859D02*
Y170884D01*
G01X1620093Y184351D02*
Y183567D01*
G01X1621043Y184403D02*
Y183961D01*
G01X1620093Y183567D02*
X1629523Y174137D01*
G01X1621043Y183961D02*
X1621707Y183297D01*
G01X1620093Y183567D02*
X1629523Y174137D01*
G01X1623037Y181967D02*
X1623673Y181331D01*
G01X1620093Y183567D02*
X1629523Y174137D01*
G01X1625003Y180001D02*
X1625639Y179365D01*
G01X1620093Y183567D02*
X1629523Y174137D01*
G01X1626969Y178035D02*
X1627605Y177399D01*
G01X1620093Y183567D02*
X1629523Y174137D01*
G01X1628935Y176069D02*
X1630473Y174531D01*
G01X1629523Y174137D02*
Y170539D01*
G01X1630473Y174531D02*
Y173740D01*
G01X1629523Y174137D02*
Y170539D01*
G01X1630473Y171859D02*
Y170884D01*
G01X1621043Y184403D02*
Y183961D01*
G01X1620093Y184351D02*
Y183567D01*
G01X1621043Y183961D02*
X1621707Y183297D01*
G01X1623037Y181967D02*
X1623673Y181331D01*
G01X1625003Y180001D02*
X1625639Y179365D01*
G01X1626969Y178035D02*
X1627605Y177399D01*
G01X1628935Y176069D02*
X1630473Y174531D01*
G01X1620093Y183567D02*
X1629523Y174137D01*
G01X1630473Y174531D02*
Y173740D01*
G01Y171859D02*
Y170884D01*
G01X1629523Y174137D02*
Y170539D01*
G01X1621043Y184403D02*
Y183961D01*
G01X1620093Y184351D02*
Y183567D01*
G01X1621043Y183961D02*
X1621707Y183297D01*
G01X1623037Y181967D02*
X1623673Y181331D01*
G01X1625003Y180001D02*
X1625639Y179365D01*
G01X1626969Y178035D02*
X1627605Y177399D01*
G01X1628935Y176069D02*
X1630473Y174531D01*
G01X1620093Y183567D02*
X1629523Y174137D01*
G01X1630473Y174531D02*
Y173740D01*
G01Y171859D02*
Y170884D01*
G01X1629523Y174137D02*
Y170539D01*
G01X1605299Y474850D02*
X1605982D01*
G01X1604865Y475800D02*
X1606376D01*
G01X1605982Y474850D02*
X1606718Y474114D01*
G01X1608309Y472523D02*
X1608982Y471850D01*
G01X1606376Y475800D02*
X1609376Y472800D01*
G01X1608982Y471850D02*
X1612734D01*
G01X1614984D02*
X1617250D01*
G01X1609376Y472800D02*
X1617644D01*
G01X1617250Y471850D02*
X1617700Y471400D01*
G01X1617644Y472800D02*
X1618650Y471794D01*
G01X1617700Y471400D02*
Y470396D01*
G01X1618650Y471794D02*
Y470902D01*
G01X1604865Y475800D02*
X1606376D01*
G01X1605299Y474850D02*
X1605982D01*
G01X1606376Y475800D02*
X1609376Y472800D01*
G01X1605982Y474850D02*
X1606718Y474114D01*
G01X1606376Y475800D02*
X1609376Y472800D01*
G01X1608309Y472523D02*
X1608982Y471850D01*
G01X1609376Y472800D02*
X1617644D01*
G01X1608982Y471850D02*
X1612734D01*
G01X1609376Y472800D02*
X1617644D01*
G01X1614984Y471850D02*
X1617250D01*
G01X1617644Y472800D02*
X1618650Y471794D01*
G01X1617250Y471850D02*
X1617700Y471400D01*
G01X1618650Y471794D02*
Y470902D01*
G01X1617700Y471400D02*
Y470396D01*
G01X1614950Y522135D02*
Y532800D01*
G01Y522135D02*
Y532800D01*
G01Y522135D02*
Y532800D01*
G01X1615900Y523800D02*
Y522135D01*
G01X1613719Y519163D02*
G03X1614950Y522135I-2972J2972D01*
G01X1615900D02*
G02X1614391Y518491I-5154J0D01*
G01X1607016Y512460D02*
X1613719Y519163D01*
G01X1614391Y518491D02*
X1613436Y517536D01*
G01X1607016Y512460D02*
X1613719Y519163D01*
G01X1611209Y515309D02*
X1607688Y511788D01*
G01X1605845Y511975D02*
G03X1607016Y512460I0J1656D01*
G01X1607688Y511788D02*
G02X1605845Y511025I-1843J1844D01*
G01X1594516Y511975D02*
X1605845D01*
G01Y511025D02*
X1594516D01*
G01X1592387Y512857D02*
G03X1594516Y511975I2129J2129D01*
G01Y511025D02*
G02X1591715Y512185I0J3962D01*
G01X1594516Y511025D02*
G02X1591715Y512185I0J3962D01*
G01X1592387Y512857D02*
G03X1594516Y511975I2129J2129D01*
G01X1605845Y511025D02*
X1594516D01*
G01Y511975D02*
X1605845D01*
G01X1607688Y511788D02*
G02X1605845Y511025I-1843J1844D01*
G01Y511975D02*
G03X1607016Y512460I0J1656D01*
G01X1614391Y518491D02*
X1613436Y517536D01*
G01X1611209Y515309D02*
X1607688Y511788D01*
G01X1607016Y512460D02*
X1613719Y519163D01*
G01X1615900Y522135D02*
G02X1614391Y518491I-5154J0D01*
G01X1613719Y519163D02*
G03X1614950Y522135I-2972J2972D01*
G01X1615900Y523800D02*
Y522135D01*
G01X1614950D02*
Y532800D01*
G01X1609938Y481484D02*
X1610999D01*
G01X1609938Y482434D02*
X1611393D01*
G01X1610999Y481484D02*
X1611705Y480778D01*
G01X1613296Y479187D02*
X1613916Y478567D01*
G01X1611393Y482434D02*
X1614310Y479517D01*
G01X1613296Y479187D02*
X1613916Y478567D01*
G01D02*
X1615800D01*
G01X1614310Y479517D02*
X1616194D01*
G01X1615800Y478567D02*
X1616250Y478117D01*
G01X1616194Y479517D02*
X1617700Y478011D01*
G01X1609938Y481484D02*
X1610999D01*
G01X1609938Y482434D02*
X1611393D01*
G01X1610999Y481484D02*
X1611705Y480778D01*
G01X1613296Y479187D02*
X1613916Y478567D01*
G01X1611393Y482434D02*
X1614310Y479517D01*
G01X1613296Y479187D02*
X1613916Y478567D01*
G01D02*
X1615800D01*
G01X1614310Y479517D02*
X1616194D01*
G01X1615800Y478567D02*
X1616250Y478117D01*
G01X1616194Y479517D02*
X1617700Y478011D01*
G01X1609938Y482434D02*
X1611393D01*
G01X1609938Y481484D02*
X1610999D01*
G01X1611393Y482434D02*
X1614310Y479517D01*
G01X1610999Y481484D02*
X1611705Y480778D01*
G01X1611393Y482434D02*
X1614310Y479517D01*
G01D02*
X1616194D01*
G01X1613296Y479187D02*
X1613916Y478567D01*
G01X1614310Y479517D02*
X1616194D01*
G01X1613916Y478567D02*
X1615800D01*
G01X1616194Y479517D02*
X1617700Y478011D01*
G01X1615800Y478567D02*
X1616250Y478117D01*
G01X1609938Y482434D02*
X1611393D01*
G01X1609938Y481484D02*
X1610999D01*
G01X1611393Y482434D02*
X1614310Y479517D01*
G01X1610999Y481484D02*
X1611705Y480778D01*
G01X1611393Y482434D02*
X1614310Y479517D01*
G01D02*
X1616194D01*
G01X1613296Y479187D02*
X1613916Y478567D01*
G01X1614310Y479517D02*
X1616194D01*
G01X1613916Y478567D02*
X1615800D01*
G01X1616194Y479517D02*
X1617700Y478011D01*
G01X1615800Y478567D02*
X1616250Y478117D01*
G01X1612283Y467482D02*
X1613957D01*
G01D02*
X1614937Y466502D01*
G01X1612081Y466532D02*
X1613563D01*
G01X1613957Y467482D02*
X1614937Y466502D01*
G01X1613563Y466532D02*
X1614543Y465552D01*
G01X1614937Y466502D02*
X1622352D01*
G01X1614543Y465552D02*
X1622410D01*
G01X1612283Y467482D02*
X1613957D01*
G01D02*
X1614937Y466502D01*
G01X1612081Y466532D02*
X1613563D01*
G01X1613957Y467482D02*
X1614937Y466502D01*
G01X1613563Y466532D02*
X1614543Y465552D01*
G01X1614937Y466502D02*
X1622352D01*
G01X1614543Y465552D02*
X1622410D01*
G01X1612081Y466532D02*
X1613563D01*
G01X1612283Y467482D02*
X1613957D01*
G01X1612081Y466532D02*
X1613563D01*
G01D02*
X1614543Y465552D01*
G01X1613957Y467482D02*
X1614937Y466502D01*
G01X1614543Y465552D02*
X1622410D01*
G01X1614937Y466502D02*
X1622352D01*
G01X1612081Y466532D02*
X1613563D01*
G01X1612283Y467482D02*
X1613957D01*
G01X1612081Y466532D02*
X1613563D01*
G01D02*
X1614543Y465552D01*
G01X1613957Y467482D02*
X1614937Y466502D01*
G01X1614543Y465552D02*
X1622410D01*
G01X1614937Y466502D02*
X1622352D01*
G01X1614950Y522135D02*
Y532800D01*
G01Y522135D02*
Y532800D01*
G01Y522135D02*
Y532800D01*
G01X1615900Y523800D02*
Y522135D01*
G01X1613719Y519163D02*
G03X1614950Y522135I-2972J2972D01*
G01X1615900D02*
G02X1614391Y518491I-5154J0D01*
G01X1607016Y512460D02*
X1613719Y519163D01*
G01X1614391Y518491D02*
X1613436Y517536D01*
G01X1607016Y512460D02*
X1613719Y519163D01*
G01X1611209Y515309D02*
X1607688Y511788D01*
G01X1605845Y511975D02*
G03X1607016Y512460I0J1656D01*
G01X1607688Y511788D02*
G02X1605845Y511025I-1843J1844D01*
G01X1594516Y511975D02*
X1605845D01*
G01Y511025D02*
X1594516D01*
G01X1592387Y512857D02*
G03X1594516Y511975I2129J2129D01*
G01Y511025D02*
G02X1591715Y512185I0J3962D01*
G01X1594516Y511025D02*
G02X1591715Y512185I0J3962D01*
G01X1592387Y512857D02*
G03X1594516Y511975I2129J2129D01*
G01X1605845Y511025D02*
X1594516D01*
G01Y511975D02*
X1605845D01*
G01X1607688Y511788D02*
G02X1605845Y511025I-1843J1844D01*
G01Y511975D02*
G03X1607016Y512460I0J1656D01*
G01X1614391Y518491D02*
X1613436Y517536D01*
G01X1611209Y515309D02*
X1607688Y511788D01*
G01X1607016Y512460D02*
X1613719Y519163D01*
G01X1615900Y522135D02*
G02X1614391Y518491I-5154J0D01*
G01X1613719Y519163D02*
G03X1614950Y522135I-2972J2972D01*
G01X1615900Y523800D02*
Y522135D01*
G01X1614950D02*
Y532800D01*
G01X1612283Y467482D02*
X1613957D01*
G01D02*
X1614937Y466502D01*
G01X1612081Y466532D02*
X1613563D01*
G01X1613957Y467482D02*
X1614937Y466502D01*
G01X1613563Y466532D02*
X1614543Y465552D01*
G01X1614937Y466502D02*
X1622352D01*
G01X1614543Y465552D02*
X1622410D01*
G01X1609938Y481484D02*
X1610999D01*
G01X1609938Y482434D02*
X1611393D01*
G01X1610999Y481484D02*
X1611705Y480778D01*
G01X1613296Y479187D02*
X1613916Y478567D01*
G01X1611393Y482434D02*
X1614310Y479517D01*
G01X1613296Y479187D02*
X1613916Y478567D01*
G01D02*
X1615800D01*
G01X1614310Y479517D02*
X1616194D01*
G01X1615800Y478567D02*
X1616250Y478117D01*
G01X1616194Y479517D02*
X1617700Y478011D01*
G01X1609938Y482434D02*
X1611393D01*
G01X1609938Y481484D02*
X1610999D01*
G01X1611393Y482434D02*
X1614310Y479517D01*
G01X1610999Y481484D02*
X1611705Y480778D01*
G01X1611393Y482434D02*
X1614310Y479517D01*
G01D02*
X1616194D01*
G01X1613296Y479187D02*
X1613916Y478567D01*
G01X1614310Y479517D02*
X1616194D01*
G01X1613916Y478567D02*
X1615800D01*
G01X1616194Y479517D02*
X1617700Y478011D01*
G01X1615800Y478567D02*
X1616250Y478117D01*
G01X1612081Y466532D02*
X1613563D01*
G01X1612283Y467482D02*
X1613957D01*
G01X1612081Y466532D02*
X1613563D01*
G01D02*
X1614543Y465552D01*
G01X1613957Y467482D02*
X1614937Y466502D01*
G01X1614543Y465552D02*
X1622410D01*
G01X1614937Y466502D02*
X1622352D01*
G01X1605299Y474850D02*
X1605982D01*
G01X1604865Y475800D02*
X1606376D01*
G01X1605982Y474850D02*
X1606718Y474114D01*
G01X1608309Y472523D02*
X1608982Y471850D01*
G01X1606376Y475800D02*
X1609376Y472800D01*
G01X1608982Y471850D02*
X1612734D01*
G01X1614984D02*
X1617250D01*
G01X1609376Y472800D02*
X1617644D01*
G01X1617250Y471850D02*
X1617700Y471400D01*
G01X1617644Y472800D02*
X1618650Y471794D01*
G01X1617700Y471400D02*
Y470396D01*
G01X1618650Y471794D02*
Y470902D01*
G01X1604865Y475800D02*
X1606376D01*
G01X1605299Y474850D02*
X1605982D01*
G01X1606376Y475800D02*
X1609376Y472800D01*
G01X1605982Y474850D02*
X1606718Y474114D01*
G01X1606376Y475800D02*
X1609376Y472800D01*
G01X1608309Y472523D02*
X1608982Y471850D01*
G01X1609376Y472800D02*
X1617644D01*
G01X1608982Y471850D02*
X1612734D01*
G01X1609376Y472800D02*
X1617644D01*
G01X1614984Y471850D02*
X1617250D01*
G01X1617644Y472800D02*
X1618650Y471794D01*
G01X1617250Y471850D02*
X1617700Y471400D01*
G01X1618650Y471794D02*
Y470902D01*
G01X1617700Y471400D02*
Y470396D01*
G01X1648837Y540338D02*
X1653417Y544918D01*
G01X1654089Y544246D02*
X1649509Y539666D01*
G01X1646090Y539200D02*
G03X1648837Y540338I0J3884D01*
G01X1649509Y539666D02*
G02X1646091Y538250I-3418J3418D01*
G01X1621350Y539200D02*
X1646090D01*
G01X1646091Y538250D02*
X1621350D01*
G01X1614950Y532800D02*
G02X1621350Y539200I6400J0D01*
G01Y538250D02*
G03X1615900Y532800I0J-5450D01*
G01D02*
Y531450D01*
G01Y528300D02*
Y526950D01*
G01Y532800D02*
Y531450D01*
G01Y528300D02*
Y526950D01*
G01X1621350Y538250D02*
G03X1615900Y532800I0J-5450D01*
G01X1614950D02*
G02X1621350Y539200I6400J0D01*
G01X1646091Y538250D02*
X1621350D01*
G01Y539200D02*
X1646090D01*
G01X1649509Y539666D02*
G02X1646091Y538250I-3418J3418D01*
G01X1646090Y539200D02*
G03X1648837Y540338I0J3884D01*
G01X1654089Y544246D02*
X1649509Y539666D01*
G01X1648837Y540338D02*
X1653417Y544918D01*
G01X1648837Y540338D02*
X1653417Y544918D01*
G01X1654089Y544246D02*
X1649509Y539666D01*
G01X1646090Y539200D02*
G03X1648837Y540338I0J3884D01*
G01X1649509Y539666D02*
G02X1646091Y538250I-3418J3418D01*
G01X1621350Y539200D02*
X1646090D01*
G01X1646091Y538250D02*
X1621350D01*
G01X1614950Y532800D02*
G02X1621350Y539200I6400J0D01*
G01Y538250D02*
G03X1615900Y532800I0J-5450D01*
G01D02*
Y531450D01*
G01Y528300D02*
Y526950D01*
G01Y532800D02*
Y531450D01*
G01Y528300D02*
Y526950D01*
G01X1621350Y538250D02*
G03X1615900Y532800I0J-5450D01*
G01X1614950D02*
G02X1621350Y539200I6400J0D01*
G01X1646091Y538250D02*
X1621350D01*
G01Y539200D02*
X1646090D01*
G01X1649509Y539666D02*
G02X1646091Y538250I-3418J3418D01*
G01X1646090Y539200D02*
G03X1648837Y540338I0J3884D01*
G01X1654089Y544246D02*
X1649509Y539666D01*
G01X1648837Y540338D02*
X1653417Y544918D01*
G01X1651732Y6775D02*
Y9650D01*
G01X1650782Y6784D02*
Y9256D01*
G01X1651732Y9650D02*
X1651159Y10223D01*
G01D02*
Y13696D01*
G01X1650782Y6784D02*
Y9256D01*
G01X1651732Y6775D02*
Y9650D01*
G01D02*
X1651159Y10223D01*
G01D02*
Y13696D01*
G01X1659500Y10999D02*
Y13619D01*
G01X1660450Y10850D02*
Y13301D01*
G01X1669004Y6686D02*
Y13801D01*
G01X1669954Y6686D02*
Y13591D01*
G01X1678453Y13566D02*
Y11831D01*
G01X1679403Y13354D02*
Y11831D01*
G01X1688009Y13460D02*
Y11208D01*
G01X1688959Y13460D02*
Y11240D01*
G01X1660450Y10850D02*
Y13301D01*
G01X1659500Y10999D02*
Y13619D01*
G01X1669954Y6686D02*
Y13591D01*
G01X1669004Y6686D02*
Y13801D01*
G01X1679403Y13354D02*
Y11831D01*
G01X1678453Y13566D02*
Y11831D01*
G01X1688959Y13460D02*
Y11240D01*
G01X1688009Y13460D02*
Y11208D01*
G01X1697222Y11936D02*
Y13677D01*
G01X1698172Y11986D02*
Y13459D01*
G01X1706817Y11858D02*
Y13788D01*
G01X1707767Y11970D02*
Y13604D01*
G01X1698172Y11986D02*
Y13459D01*
G01X1697222Y11936D02*
Y13677D01*
G01X1707767Y11970D02*
Y13604D01*
G01X1706817Y11858D02*
Y13788D01*
G01X1701648Y39048D02*
Y35095D01*
G01X1700698Y39102D02*
Y35273D01*
G01X1710800Y38600D02*
Y35393D01*
G01X1709850Y34999D02*
Y38650D01*
G01X1700698Y39102D02*
Y35273D01*
G01X1701648Y39048D02*
Y35095D01*
G01X1709850Y34999D02*
Y38650D01*
G01X1710800Y38600D02*
Y35393D01*
G01X1653323Y35148D02*
Y39012D01*
G01X1654273Y35220D02*
Y39012D01*
G01X1662773Y35148D02*
Y39012D01*
G01X1663723Y35220D02*
Y39012D01*
G01X1672259Y35184D02*
Y38641D01*
G01X1673209Y35184D02*
Y38709D01*
G01X1681709Y38891D02*
Y35184D01*
G01X1682659D02*
Y38859D01*
G01X1692109Y38909D02*
Y35184D01*
G01X1691159Y38741D02*
Y35184D01*
G01X1654273Y35220D02*
Y39012D01*
G01X1653323Y35148D02*
Y39012D01*
G01X1663723Y35220D02*
Y39012D01*
G01X1662773Y35148D02*
Y39012D01*
G01X1673209Y35184D02*
Y38709D01*
G01X1672259Y35184D02*
Y38641D01*
G01X1682659Y35184D02*
Y38859D01*
G01X1681709Y38891D02*
Y35184D01*
G01X1691159Y38741D02*
Y35184D01*
G01X1692109Y38909D02*
Y35184D01*
G01X1700698Y39102D02*
Y35273D01*
G01X1701648Y39048D02*
Y35095D01*
G01X1709850Y34999D02*
Y38650D01*
G01X1710800Y38600D02*
Y35393D01*
G01X1701648Y39048D02*
Y35095D01*
G01X1700698Y39102D02*
Y35273D01*
G01X1710800Y38600D02*
Y35393D01*
G01X1709850Y34999D02*
Y38650D01*
G01X1703323Y548478D02*
Y547900D01*
G01X1702373D02*
Y548478D01*
G01X1700751Y551050D02*
G02X1703323Y548478I0J-2572D01*
G01X1702373D02*
G03X1700751Y550100I-1622J0D01*
G01X1697857Y551050D02*
X1700751D01*
G01Y550100D02*
X1697858D01*
G01X1693326Y549173D02*
G02X1697857Y551050I4531J-4531D01*
G01X1697858Y550100D02*
G03X1693998Y548501I0J-5459D01*
G01X1688623Y544470D02*
X1693326Y549173D01*
G01X1693998Y548501D02*
X1689295Y543798D01*
G01X1685569Y543205D02*
G03X1688623Y544470I0J4319D01*
G01X1689295Y543798D02*
G02X1685570Y542255I-3725J3725D01*
G01X1684299Y543205D02*
X1685569D01*
G01X1685570Y542255D02*
X1684300D01*
G01X1681296Y541961D02*
G02X1684299Y543205I3003J-3003D01*
G01X1684300Y542255D02*
G03X1681968Y541289I0J-3298D01*
G01X1678332Y538997D02*
X1681296Y541961D01*
G01X1681968Y541289D02*
X1679029Y538350D01*
G01X1678332Y538997D02*
X1681296Y541961D01*
G01X1679029Y538350D02*
X1679004Y538326D01*
G01X1676159Y538097D02*
G03X1678332Y538997I0J3073D01*
G01X1679004Y538326D02*
G02X1676159Y537147I-2845J2843D01*
G01X1673377Y538097D02*
X1676159D01*
G01Y537147D02*
X1673377D01*
G01X1669456Y542018D02*
G03X1673377Y538097I3921J0D01*
G01Y537147D02*
G02X1668506Y542018I0J4871D01*
G01X1669456Y542765D02*
Y542018D01*
G01X1668506D02*
Y542765D01*
G01X1666348Y545873D02*
G02X1669456Y542765I0J-3108D01*
G01X1668506D02*
G03X1666348Y544923I-2158J0D01*
G01X1655723Y545873D02*
X1666348D01*
G01Y544923D02*
X1664723D01*
G01X1655723Y545873D02*
X1666348D01*
G01X1661573Y544923D02*
X1660223D01*
G01X1655723Y545873D02*
X1666348D01*
G01X1657073Y544923D02*
X1655723D01*
G01X1653417Y544918D02*
G02X1655723Y545873I2306J-2306D01*
G01Y544923D02*
G03X1654089Y544246I0J-2311D01*
G01X1655723Y544923D02*
G03X1654089Y544246I0J-2311D01*
G01X1653417Y544918D02*
G02X1655723Y545873I2306J-2306D01*
G01X1666348Y544923D02*
X1664723D01*
G01X1661573D02*
X1660223D01*
G01X1657073D02*
X1655723D01*
G01Y545873D02*
X1666348D01*
G01X1668506Y542765D02*
G03X1666348Y544923I-2158J0D01*
G01Y545873D02*
G02X1669456Y542765I0J-3108D01*
G01X1668506Y542018D02*
Y542765D01*
G01X1669456D02*
Y542018D01*
G01X1673377Y537147D02*
G02X1668506Y542018I0J4871D01*
G01X1669456D02*
G03X1673377Y538097I3921J0D01*
G01X1676159Y537147D02*
X1673377D01*
G01Y538097D02*
X1676159D01*
G01X1679004Y538326D02*
G02X1676159Y537147I-2845J2843D01*
G01Y538097D02*
G03X1678332Y538997I0J3073D01*
G01X1681968Y541289D02*
X1679029Y538350D01*
G01D02*
X1679004Y538326D01*
G01X1678332Y538997D02*
X1681296Y541961D01*
G01X1684300Y542255D02*
G03X1681968Y541289I0J-3298D01*
G01X1681296Y541961D02*
G02X1684299Y543205I3003J-3003D01*
G01X1685570Y542255D02*
X1684300D01*
G01X1684299Y543205D02*
X1685569D01*
G01X1689295Y543798D02*
G02X1685570Y542255I-3725J3725D01*
G01X1685569Y543205D02*
G03X1688623Y544470I0J4319D01*
G01X1693998Y548501D02*
X1689295Y543798D01*
G01X1688623Y544470D02*
X1693326Y549173D01*
G01X1697858Y550100D02*
G03X1693998Y548501I0J-5459D01*
G01X1693326Y549173D02*
G02X1697857Y551050I4531J-4531D01*
G01X1700751Y550100D02*
X1697858D01*
G01X1697857Y551050D02*
X1700751D01*
G01X1702373Y548478D02*
G03X1700751Y550100I-1622J0D01*
G01Y551050D02*
G02X1703323Y548478I0J-2572D01*
G01X1702373Y547900D02*
Y548478D01*
G01X1703323D02*
Y547900D01*
G01Y548478D02*
Y547900D01*
G01X1702373D02*
Y548478D01*
G01X1700751Y551050D02*
G02X1703323Y548478I0J-2572D01*
G01X1702373D02*
G03X1700751Y550100I-1622J0D01*
G01X1697857Y551050D02*
X1700751D01*
G01Y550100D02*
X1697858D01*
G01X1693326Y549173D02*
G02X1697857Y551050I4531J-4531D01*
G01X1697858Y550100D02*
G03X1693998Y548501I0J-5459D01*
G01X1688623Y544470D02*
X1693326Y549173D01*
G01X1693998Y548501D02*
X1689295Y543798D01*
G01X1685569Y543205D02*
G03X1688623Y544470I0J4319D01*
G01X1689295Y543798D02*
G02X1685570Y542255I-3725J3725D01*
G01X1684299Y543205D02*
X1685569D01*
G01X1685570Y542255D02*
X1684300D01*
G01X1681296Y541961D02*
G02X1684299Y543205I3003J-3003D01*
G01X1684300Y542255D02*
G03X1681968Y541289I0J-3298D01*
G01X1678332Y538997D02*
X1681296Y541961D01*
G01X1681968Y541289D02*
X1679029Y538350D01*
G01X1678332Y538997D02*
X1681296Y541961D01*
G01X1679029Y538350D02*
X1679004Y538326D01*
G01X1676159Y538097D02*
G03X1678332Y538997I0J3073D01*
G01X1679004Y538326D02*
G02X1676159Y537147I-2845J2843D01*
G01X1673377Y538097D02*
X1676159D01*
G01Y537147D02*
X1673377D01*
G01X1669456Y542018D02*
G03X1673377Y538097I3921J0D01*
G01Y537147D02*
G02X1668506Y542018I0J4871D01*
G01X1669456Y542765D02*
Y542018D01*
G01X1668506D02*
Y542765D01*
G01X1666348Y545873D02*
G02X1669456Y542765I0J-3108D01*
G01X1668506D02*
G03X1666348Y544923I-2158J0D01*
G01X1655723Y545873D02*
X1666348D01*
G01Y544923D02*
X1664723D01*
G01X1655723Y545873D02*
X1666348D01*
G01X1661573Y544923D02*
X1660223D01*
G01X1655723Y545873D02*
X1666348D01*
G01X1657073Y544923D02*
X1655723D01*
G01X1653417Y544918D02*
G02X1655723Y545873I2306J-2306D01*
G01Y544923D02*
G03X1654089Y544246I0J-2311D01*
G01X1655723Y544923D02*
G03X1654089Y544246I0J-2311D01*
G01X1653417Y544918D02*
G02X1655723Y545873I2306J-2306D01*
G01X1666348Y544923D02*
X1664723D01*
G01X1661573D02*
X1660223D01*
G01X1657073D02*
X1655723D01*
G01Y545873D02*
X1666348D01*
G01X1668506Y542765D02*
G03X1666348Y544923I-2158J0D01*
G01Y545873D02*
G02X1669456Y542765I0J-3108D01*
G01X1668506Y542018D02*
Y542765D01*
G01X1669456D02*
Y542018D01*
G01X1673377Y537147D02*
G02X1668506Y542018I0J4871D01*
G01X1669456D02*
G03X1673377Y538097I3921J0D01*
G01X1676159Y537147D02*
X1673377D01*
G01Y538097D02*
X1676159D01*
G01X1679004Y538326D02*
G02X1676159Y537147I-2845J2843D01*
G01Y538097D02*
G03X1678332Y538997I0J3073D01*
G01X1681968Y541289D02*
X1679029Y538350D01*
G01D02*
X1679004Y538326D01*
G01X1678332Y538997D02*
X1681296Y541961D01*
G01X1684300Y542255D02*
G03X1681968Y541289I0J-3298D01*
G01X1681296Y541961D02*
G02X1684299Y543205I3003J-3003D01*
G01X1685570Y542255D02*
X1684300D01*
G01X1684299Y543205D02*
X1685569D01*
G01X1689295Y543798D02*
G02X1685570Y542255I-3725J3725D01*
G01X1685569Y543205D02*
G03X1688623Y544470I0J4319D01*
G01X1693998Y548501D02*
X1689295Y543798D01*
G01X1688623Y544470D02*
X1693326Y549173D01*
G01X1697858Y550100D02*
G03X1693998Y548501I0J-5459D01*
G01X1693326Y549173D02*
G02X1697857Y551050I4531J-4531D01*
G01X1700751Y550100D02*
X1697858D01*
G01X1697857Y551050D02*
X1700751D01*
G01X1702373Y548478D02*
G03X1700751Y550100I-1622J0D01*
G01Y551050D02*
G02X1703323Y548478I0J-2572D01*
G01X1702373Y547900D02*
Y548478D01*
G01X1703323D02*
Y547900D01*
G01X1759001Y32822D02*
X1763397Y37221D01*
G01X1759001Y32822D02*
X1763397Y37221D01*
G01X1761247Y33725D02*
X1759395Y31872D01*
G01D02*
X1758315D01*
G01X1759395D02*
X1758315D01*
G01X1761247Y33725D02*
X1759395Y31872D01*
G01X1759001Y32822D02*
X1763397Y37221D01*
G01X1716272Y11630D02*
Y13783D01*
G01X1717222Y11680D02*
Y13609D01*
G01X1725709Y13796D02*
Y11909D01*
G01X1726659Y13596D02*
Y11941D01*
G01X1744986Y22287D02*
Y20627D01*
G01X1745936Y22209D02*
Y20261D01*
G01X1773895Y12878D02*
X1772755Y11738D01*
G01X1775107Y12746D02*
X1773149Y10788D01*
G01X1772755Y11738D02*
X1771578D01*
G01X1769328D02*
X1768691D01*
G01X1773149Y10788D02*
X1768297D01*
G01X1769328Y11738D02*
X1768691D01*
G01D02*
X1768241Y12188D01*
G01X1768297Y10788D02*
X1767303Y11782D01*
G01X1766650Y13754D02*
X1765695Y14709D01*
G01X1767278Y11782D02*
X1764745Y14315D01*
G01X1765695Y14709D02*
Y15436D01*
G01Y17686D02*
Y19036D01*
G01Y21286D02*
Y22636D01*
G01X1764745Y14315D02*
Y22625D01*
G01X1758964Y18316D02*
Y14776D01*
G01X1758014Y18985D02*
Y14382D01*
G01X1758964Y14776D02*
X1759563Y14177D01*
G01D02*
X1760200D01*
G01X1761154Y12586D02*
X1762109Y11631D01*
G01D02*
X1762746D01*
G01X1763700Y10040D02*
X1764655Y9085D01*
G01D02*
X1765292D01*
G01X1758014Y14382D02*
X1764261Y8135D01*
G01X1764655Y9085D02*
X1765292D01*
G01X1767542D02*
X1768892D01*
G01X1771142D02*
X1772492D01*
G01X1764261Y8135D02*
X1780086D01*
G01X1717222Y11680D02*
Y13609D01*
G01X1716272Y11630D02*
Y13783D01*
G01X1726659Y13596D02*
Y11941D01*
G01X1725709Y13796D02*
Y11909D01*
G01X1745936Y22209D02*
Y20261D01*
G01X1744986Y22287D02*
Y20627D01*
G01X1775107Y12746D02*
X1773149Y10788D01*
G01X1773895Y12878D02*
X1772755Y11738D01*
G01X1773149Y10788D02*
X1768297D01*
G01X1772755Y11738D02*
X1771578D01*
G01X1773149Y10788D02*
X1768297D01*
G01D02*
X1767303Y11782D01*
G01X1769328Y11738D02*
X1768691D01*
G01X1768297Y10788D02*
X1767303Y11782D01*
G01X1768691Y11738D02*
X1768241Y12188D01*
G01X1767278Y11782D02*
X1764745Y14315D01*
G01X1766650Y13754D02*
X1765695Y14709D01*
G01X1764745Y14315D02*
Y22625D01*
G01X1765695Y14709D02*
Y15436D01*
G01X1764745Y14315D02*
Y22625D01*
G01X1765695Y17686D02*
Y19036D01*
G01X1764745Y14315D02*
Y22625D01*
G01X1765695Y21286D02*
Y22636D01*
G01X1758014Y18985D02*
Y14382D01*
G01X1758964Y18316D02*
Y14776D01*
G01X1758014Y14382D02*
X1764261Y8135D01*
G01X1758964Y14776D02*
X1759563Y14177D01*
G01X1758014Y14382D02*
X1764261Y8135D01*
G01X1759563Y14177D02*
X1760200D01*
G01X1758014Y14382D02*
X1764261Y8135D01*
G01X1761154Y12586D02*
X1762109Y11631D01*
G01X1758014Y14382D02*
X1764261Y8135D01*
G01X1762109Y11631D02*
X1762746D01*
G01X1758014Y14382D02*
X1764261Y8135D01*
G01X1763700Y10040D02*
X1764655Y9085D01*
G01X1758014Y14382D02*
X1764261Y8135D01*
G01D02*
X1780086D01*
G01X1764655Y9085D02*
X1765292D01*
G01X1764261Y8135D02*
X1780086D01*
G01X1767542Y9085D02*
X1768892D01*
G01X1764261Y8135D02*
X1780086D01*
G01X1771142Y9085D02*
X1772492D01*
G01X1764261Y8135D02*
X1780086D01*
G01X1764261D02*
X1780086D01*
G01X1759001Y32822D02*
X1763397Y37221D01*
G01X1759001Y32822D02*
X1763397Y37221D01*
G01X1761247Y33725D02*
X1759395Y31872D01*
G01D02*
X1758315D01*
G01X1759395D02*
X1758315D01*
G01X1761247Y33725D02*
X1759395Y31872D01*
G01X1759001Y32822D02*
X1763397Y37221D01*
G01X1728808Y38962D02*
Y35033D01*
G01X1729758Y38678D02*
Y35335D01*
G01X1738277Y38623D02*
Y35052D01*
G01X1739227Y35072D02*
Y38627D01*
G01X1747859Y35441D02*
Y34460D01*
G01X1748809Y35509D02*
Y34292D01*
G01X1763397Y37221D02*
X1776151D01*
G01X1775757Y36271D02*
X1770991D01*
G01X1763397Y37221D02*
X1776151D01*
G01X1768741Y36271D02*
X1767391D01*
G01X1763397Y37221D02*
X1776151D01*
G01X1765141Y36271D02*
X1763791D01*
G01D02*
X1762837Y35316D01*
G01X1758325Y32822D02*
X1759001D01*
G01X1754579Y39379D02*
X1755369Y41688D01*
G01X1753679Y39688D02*
X1754541Y42205D01*
G01X1755369Y41688D02*
X1755884Y42204D01*
G01D02*
X1756521D01*
G01X1757475Y43795D02*
X1758430Y44750D01*
G01D02*
X1759780D01*
G01X1754541Y42205D02*
X1758036Y45700D01*
G01X1758430Y44750D02*
X1759780D01*
G01X1762030D02*
X1763380D01*
G01X1765630D02*
X1766980D01*
G01X1769230D02*
X1770580D01*
G01X1772830D02*
X1776238D01*
G01X1758036Y45700D02*
X1776632D01*
G01X1729758Y38678D02*
Y35335D01*
G01X1728808Y38962D02*
Y35033D01*
G01X1739227Y35072D02*
Y38627D01*
G01X1738277Y38623D02*
Y35052D01*
G01X1748809Y35509D02*
Y34292D01*
G01X1747859Y35441D02*
Y34460D01*
G01X1758325Y32822D02*
X1759001D01*
G01X1763791Y36271D02*
X1762837Y35316D01*
G01X1775757Y36271D02*
X1770991D01*
G01X1768741D02*
X1767391D01*
G01X1765141D02*
X1763791D01*
G01X1763397Y37221D02*
X1776151D01*
G01X1753679Y39688D02*
X1754541Y42205D01*
G01X1754579Y39379D02*
X1755369Y41688D01*
G01X1754541Y42205D02*
X1758036Y45700D01*
G01X1755369Y41688D02*
X1755884Y42204D01*
G01X1754541Y42205D02*
X1758036Y45700D01*
G01X1755884Y42204D02*
X1756521D01*
G01X1754541Y42205D02*
X1758036Y45700D01*
G01X1757475Y43795D02*
X1758430Y44750D01*
G01X1754541Y42205D02*
X1758036Y45700D01*
G01D02*
X1776632D01*
G01X1758430Y44750D02*
X1759780D01*
G01X1758036Y45700D02*
X1776632D01*
G01X1762030Y44750D02*
X1763380D01*
G01X1758036Y45700D02*
X1776632D01*
G01X1765630Y44750D02*
X1766980D01*
G01X1758036Y45700D02*
X1776632D01*
G01X1769230Y44750D02*
X1770580D01*
G01X1758036Y45700D02*
X1776632D01*
G01X1772830Y44750D02*
X1776238D01*
G01X1719383Y35058D02*
Y39217D01*
G01X1720333Y35310D02*
Y39233D01*
G01Y35310D02*
Y39233D01*
G01X1719383Y35058D02*
Y39217D01*
G01Y35058D02*
Y39217D01*
G01X1720333Y35310D02*
Y39233D01*
G01X1728808Y38962D02*
Y35033D01*
G01X1729758Y38678D02*
Y35335D01*
G01X1738277Y38623D02*
Y35052D01*
G01X1739227Y35072D02*
Y38627D01*
G01X1747859Y35441D02*
Y34460D01*
G01X1748809Y35509D02*
Y34292D01*
G01X1763397Y37221D02*
X1776151D01*
G01X1775757Y36271D02*
X1770991D01*
G01X1763397Y37221D02*
X1776151D01*
G01X1768741Y36271D02*
X1767391D01*
G01X1763397Y37221D02*
X1776151D01*
G01X1765141Y36271D02*
X1763791D01*
G01D02*
X1762837Y35316D01*
G01X1758325Y32822D02*
X1759001D01*
G01X1720333Y35310D02*
Y39233D01*
G01X1719383Y35058D02*
Y39217D01*
G01X1729758Y38678D02*
Y35335D01*
G01X1728808Y38962D02*
Y35033D01*
G01X1739227Y35072D02*
Y38627D01*
G01X1738277Y38623D02*
Y35052D01*
G01X1748809Y35509D02*
Y34292D01*
G01X1747859Y35441D02*
Y34460D01*
G01X1758325Y32822D02*
X1759001D01*
G01X1763791Y36271D02*
X1762837Y35316D01*
G01X1775757Y36271D02*
X1770991D01*
G01X1768741D02*
X1767391D01*
G01X1765141D02*
X1763791D01*
G01X1763397Y37221D02*
X1776151D01*
G01X1754579Y39379D02*
X1755369Y41688D01*
G01X1753679Y39688D02*
X1754541Y42205D01*
G01X1755369Y41688D02*
X1755884Y42204D01*
G01D02*
X1756521D01*
G01X1757475Y43795D02*
X1758430Y44750D01*
G01D02*
X1759780D01*
G01X1754541Y42205D02*
X1758036Y45700D01*
G01X1758430Y44750D02*
X1759780D01*
G01X1762030D02*
X1763380D01*
G01X1765630D02*
X1766980D01*
G01X1769230D02*
X1770580D01*
G01X1772830D02*
X1776238D01*
G01X1758036Y45700D02*
X1776632D01*
G01X1753679Y39688D02*
X1754541Y42205D01*
G01X1754579Y39379D02*
X1755369Y41688D01*
G01X1754541Y42205D02*
X1758036Y45700D01*
G01X1755369Y41688D02*
X1755884Y42204D01*
G01X1754541Y42205D02*
X1758036Y45700D01*
G01X1755884Y42204D02*
X1756521D01*
G01X1754541Y42205D02*
X1758036Y45700D01*
G01X1757475Y43795D02*
X1758430Y44750D01*
G01X1754541Y42205D02*
X1758036Y45700D01*
G01D02*
X1776632D01*
G01X1758430Y44750D02*
X1759780D01*
G01X1758036Y45700D02*
X1776632D01*
G01X1762030Y44750D02*
X1763380D01*
G01X1758036Y45700D02*
X1776632D01*
G01X1765630Y44750D02*
X1766980D01*
G01X1758036Y45700D02*
X1776632D01*
G01X1769230Y44750D02*
X1770580D01*
G01X1758036Y45700D02*
X1776632D01*
G01X1772830Y44750D02*
X1776238D01*
G01X1767950Y177252D02*
Y180850D01*
G01X1767000Y177226D02*
Y180655D01*
G01X1755400Y177204D02*
Y181349D01*
G01X1754450Y177274D02*
Y181399D01*
G01X1742767Y177239D02*
Y181017D01*
G01X1741817Y177239D02*
Y180983D01*
G01X1729218Y177239D02*
Y181031D01*
G01X1730168Y177239D02*
Y181017D01*
G01X1767000Y177226D02*
Y180655D01*
G01X1767950Y177252D02*
Y180850D01*
G01X1754450Y177274D02*
Y181399D01*
G01X1755400Y177204D02*
Y181349D01*
G01X1741817Y177239D02*
Y180983D01*
G01X1742767Y177239D02*
Y181017D01*
G01X1730168Y177239D02*
Y181017D01*
G01X1729218Y177239D02*
Y181031D01*
G01X1767950Y177252D02*
Y180850D01*
G01X1767000Y177226D02*
Y180655D01*
G01X1755400Y177204D02*
Y181349D01*
G01X1754450Y177274D02*
Y181399D01*
G01X1742767Y177239D02*
Y181017D01*
G01X1741817Y177239D02*
Y180983D01*
G01X1729218Y177239D02*
Y181031D01*
G01X1730168Y177239D02*
Y181017D01*
G01X1767000Y177226D02*
Y180655D01*
G01X1767950Y177252D02*
Y180850D01*
G01X1754450Y177274D02*
Y181399D01*
G01X1755400Y177204D02*
Y181349D01*
G01X1741817Y177239D02*
Y180983D01*
G01X1742767Y177239D02*
Y181017D01*
G01X1730168Y177239D02*
Y181017D01*
G01X1729218Y177239D02*
Y181031D01*
G01X1760665Y198813D02*
Y197293D01*
G01X1761615Y198823D02*
Y197321D01*
G01X1748107Y198772D02*
Y197293D01*
G01X1749057Y198864D02*
Y197293D01*
G01X1735548Y199691D02*
Y197226D01*
G01X1736498Y199805D02*
Y197266D01*
G01X1773266Y199972D02*
Y197291D01*
G01X1761615Y198823D02*
Y197321D01*
G01X1760665Y198813D02*
Y197293D01*
G01X1749057Y198864D02*
Y197293D01*
G01X1748107Y198772D02*
Y197293D01*
G01X1736498Y199805D02*
Y197266D01*
G01X1735548Y199691D02*
Y197226D01*
G01X1773266Y199972D02*
Y197291D01*
G01X1771341Y448172D02*
Y449869D01*
G01X1770391Y448172D02*
Y449869D01*
G01X1746144Y448172D02*
Y449958D01*
G01X1745194Y448172D02*
Y449958D01*
G01X1758742Y448172D02*
Y449998D01*
G01X1757792Y448172D02*
Y449998D01*
G01X1770391Y448172D02*
Y449869D01*
G01X1771341Y448172D02*
Y449869D01*
G01X1745194Y448172D02*
Y449958D01*
G01X1746144Y448172D02*
Y449958D01*
G01X1757792Y448172D02*
Y449998D01*
G01X1758742Y448172D02*
Y449998D01*
G01X1765042Y467021D02*
Y470534D01*
G01X1764092Y467021D02*
Y470345D01*
G01X1765042Y470534D02*
X1764675Y471421D01*
G01X1764092Y470345D02*
X1763725Y471232D01*
G01X1764675Y471421D02*
Y475205D01*
G01X1763725Y471232D02*
Y475205D01*
G01X1739845Y467021D02*
Y487275D01*
G01X1738895Y467021D02*
Y487335D01*
G01X1752330Y467134D02*
Y486956D01*
G01X1751380Y466908D02*
Y486934D01*
G01X1764092Y467021D02*
Y470345D01*
G01X1765042Y467021D02*
Y470534D01*
G01X1764092Y470345D02*
X1763725Y471232D01*
G01X1765042Y470534D02*
X1764675Y471421D01*
G01X1763725Y471232D02*
Y475205D01*
G01X1764675Y471421D02*
Y475205D01*
G01X1738895Y467021D02*
Y487335D01*
G01X1739845Y467021D02*
Y487275D01*
G01X1751380Y466908D02*
Y486934D01*
G01X1752330Y467134D02*
Y486956D01*
G01X1765042Y467021D02*
Y470534D01*
G01X1764092Y467021D02*
Y470345D01*
G01X1765042Y470534D02*
X1764675Y471421D01*
G01X1764092Y470345D02*
X1763725Y471232D01*
G01X1764675Y471421D02*
Y475205D01*
G01X1763725Y471232D02*
Y475205D01*
G01X1739845Y467021D02*
Y487275D01*
G01X1738895Y467021D02*
Y487335D01*
G01X1752330Y467134D02*
Y486956D01*
G01X1751380Y466908D02*
Y486934D01*
G01X1764092Y467021D02*
Y470345D01*
G01X1765042Y467021D02*
Y470534D01*
G01X1764092Y470345D02*
X1763725Y471232D01*
G01X1765042Y470534D02*
X1764675Y471421D01*
G01X1763725Y471232D02*
Y475205D01*
G01X1764675Y471421D02*
Y475205D01*
G01X1738895Y467021D02*
Y487335D01*
G01X1739845Y467021D02*
Y487275D01*
G01X1751380Y466908D02*
Y486934D01*
G01X1752330Y467134D02*
Y486956D01*
G01X1774742Y9085D02*
X1776092D01*
G01X1778342D02*
X1779692D01*
G01D02*
X1780647Y10040D01*
G01X1782238Y11631D02*
X1782507Y11900D01*
G01X1780086Y8135D02*
X1783457Y11506D01*
G01X1782507Y11900D02*
Y13696D01*
G01X1783457Y11506D02*
Y13696D01*
G01X1774742Y9085D02*
X1776092D01*
G01X1778342D02*
X1779692D01*
G01X1780086Y8135D02*
X1783457Y11506D01*
G01X1779692Y9085D02*
X1780647Y10040D01*
G01X1780086Y8135D02*
X1783457Y11506D01*
G01X1782238Y11631D02*
X1782507Y11900D01*
G01X1783457Y11506D02*
Y13696D01*
G01X1782507Y11900D02*
Y13696D01*
G01X1777157Y36215D02*
Y35184D01*
G01X1776207D02*
Y35821D01*
G01X1776151Y37221D02*
X1777157Y36215D01*
G01X1776207Y35821D02*
X1775757Y36271D01*
G01X1776238Y44750D02*
X1777193Y43795D01*
G01X1778147Y42204D02*
X1778784D01*
G01D02*
X1779738Y41250D01*
G01X1780693Y39659D02*
X1781329D01*
G01D02*
X1782284Y38704D01*
G01X1783238Y37113D02*
X1783875D01*
G01D02*
X1785379Y35609D01*
G01X1776632Y45700D02*
X1786329Y36003D01*
G01X1785379Y35609D02*
Y34906D01*
G01X1786329Y36003D02*
Y35462D01*
G01X1776207Y35821D02*
X1775757Y36271D01*
G01X1776151Y37221D02*
X1777157Y36215D01*
G01X1776207Y35184D02*
Y35821D01*
G01X1777157Y36215D02*
Y35184D01*
G01X1776632Y45700D02*
X1786329Y36003D01*
G01X1776238Y44750D02*
X1777193Y43795D01*
G01X1776632Y45700D02*
X1786329Y36003D01*
G01X1778147Y42204D02*
X1778784D01*
G01X1776632Y45700D02*
X1786329Y36003D01*
G01X1778784Y42204D02*
X1779738Y41250D01*
G01X1776632Y45700D02*
X1786329Y36003D01*
G01X1780693Y39659D02*
X1781329D01*
G01X1776632Y45700D02*
X1786329Y36003D01*
G01X1781329Y39659D02*
X1782284Y38704D01*
G01X1776632Y45700D02*
X1786329Y36003D01*
G01X1783238Y37113D02*
X1783875D01*
G01X1776632Y45700D02*
X1786329Y36003D01*
G01X1783875Y37113D02*
X1785379Y35609D01*
G01X1786329Y36003D02*
Y35462D01*
G01X1785379Y35609D02*
Y34906D01*
G01X1777157Y36215D02*
Y35184D01*
G01X1776207D02*
Y35821D01*
G01X1776151Y37221D02*
X1777157Y36215D01*
G01X1776207Y35821D02*
X1775757Y36271D01*
G01X1776207Y35821D02*
X1775757Y36271D01*
G01X1776151Y37221D02*
X1777157Y36215D01*
G01X1776207Y35184D02*
Y35821D01*
G01X1777157Y36215D02*
Y35184D01*
G01X1776238Y44750D02*
X1777193Y43795D01*
G01X1778147Y42204D02*
X1778784D01*
G01D02*
X1779738Y41250D01*
G01X1780693Y39659D02*
X1781329D01*
G01D02*
X1782284Y38704D01*
G01X1783238Y37113D02*
X1783875D01*
G01D02*
X1785379Y35609D01*
G01X1776632Y45700D02*
X1786329Y36003D01*
G01X1785379Y35609D02*
Y34906D01*
G01X1786329Y36003D02*
Y35462D01*
G01X1776632Y45700D02*
X1786329Y36003D01*
G01X1776238Y44750D02*
X1777193Y43795D01*
G01X1776632Y45700D02*
X1786329Y36003D01*
G01X1778147Y42204D02*
X1778784D01*
G01X1776632Y45700D02*
X1786329Y36003D01*
G01X1778784Y42204D02*
X1779738Y41250D01*
G01X1776632Y45700D02*
X1786329Y36003D01*
G01X1780693Y39659D02*
X1781329D01*
G01X1776632Y45700D02*
X1786329Y36003D01*
G01X1781329Y39659D02*
X1782284Y38704D01*
G01X1776632Y45700D02*
X1786329Y36003D01*
G01X1783238Y37113D02*
X1783875D01*
G01X1776632Y45700D02*
X1786329Y36003D01*
G01X1783875Y37113D02*
X1785379Y35609D01*
G01X1786329Y36003D02*
Y35462D01*
G01X1785379Y35609D02*
Y34906D01*
G01X1817350Y180951D02*
Y177182D01*
G01X1818300Y181050D02*
Y177296D01*
G01X1804809Y180533D02*
Y177239D01*
G01X1805759Y180365D02*
Y177239D01*
G01X1779550Y180704D02*
Y177177D01*
G01X1780500Y180751D02*
Y177301D01*
G01X1818300Y181050D02*
Y177296D01*
G01X1817350Y180951D02*
Y177182D01*
G01X1805759Y180365D02*
Y177239D01*
G01X1804809Y180533D02*
Y177239D01*
G01X1793050Y180751D02*
Y177049D01*
G01X1792100Y180752D02*
Y177129D01*
G01X1780500Y180751D02*
Y177301D01*
G01X1779550Y180704D02*
Y177177D01*
G01X1792100Y180752D02*
Y177129D01*
G01X1793050Y180751D02*
Y177049D01*
G01X1774216Y199922D02*
Y197291D01*
G01X1817350Y180951D02*
Y177182D01*
G01X1818300Y181050D02*
Y177296D01*
G01X1804809Y180533D02*
Y177239D01*
G01X1805759Y180365D02*
Y177239D01*
G01X1792100Y180752D02*
Y177129D01*
G01X1793050Y180751D02*
Y177049D01*
G01X1779550Y180704D02*
Y177177D01*
G01X1780500Y180751D02*
Y177301D01*
G01X1818300Y181050D02*
Y177296D01*
G01X1817350Y180951D02*
Y177182D01*
G01X1805759Y180365D02*
Y177239D01*
G01X1804809Y180533D02*
Y177239D01*
G01X1793050Y180751D02*
Y177049D01*
G01X1792100Y180752D02*
Y177129D01*
G01X1780500Y180751D02*
Y177301D01*
G01X1779550Y180704D02*
Y177177D01*
G01X1774216Y199922D02*
Y197291D01*
G01X1823707Y199632D02*
Y197291D01*
G01X1824657Y199664D02*
Y197291D01*
G01X1811066Y198603D02*
Y197291D01*
G01X1812016Y198603D02*
Y197291D01*
G01X1798466Y198603D02*
Y197291D01*
G01X1799416Y198603D02*
Y197291D01*
G01X1785866Y199971D02*
Y197291D01*
G01X1786816Y199922D02*
Y197291D01*
G01X1824657Y199664D02*
Y197291D01*
G01X1823707Y199632D02*
Y197291D01*
G01X1812016Y198603D02*
Y197291D01*
G01X1811066Y198603D02*
Y197291D01*
G01X1799416Y198603D02*
Y197291D01*
G01X1798466Y198603D02*
Y197291D01*
G01X1786816Y199922D02*
Y197291D01*
G01X1785866Y199971D02*
Y197291D01*
G01X1783939Y448172D02*
Y449804D01*
G01X1782989Y448172D02*
Y449804D01*
G01X1796538Y448172D02*
Y449836D01*
G01X1795588Y448172D02*
Y449836D01*
G01X1809136Y448172D02*
Y450063D01*
G01X1808186Y448172D02*
Y450063D01*
G01X1821735Y448172D02*
Y449869D01*
G01X1820785Y448172D02*
Y449869D01*
G01X1834333Y448172D02*
Y450095D01*
G01X1833383Y448172D02*
Y450095D01*
G01X1782989Y448172D02*
Y449804D01*
G01X1783939Y448172D02*
Y449804D01*
G01X1795588Y448172D02*
Y449836D01*
G01X1796538Y448172D02*
Y449836D01*
G01X1808186Y448172D02*
Y450063D01*
G01X1809136Y448172D02*
Y450063D01*
G01X1820785Y448172D02*
Y449869D01*
G01X1821735Y448172D02*
Y449869D01*
G01X1833383Y448172D02*
Y450095D01*
G01X1834333Y448172D02*
Y450095D01*
G01X1777640Y467021D02*
Y470484D01*
G01X1776690Y467021D02*
Y470295D01*
G01X1777640Y470484D02*
X1777275Y471366D01*
G01X1776690Y470295D02*
X1776325Y471177D01*
G01X1777275Y471366D02*
Y474605D01*
G01X1776325Y471177D02*
Y474605D01*
G01X1790239Y467021D02*
Y469619D01*
G01X1789289Y467021D02*
Y469808D01*
G01X1790239Y469619D02*
X1792947Y476157D01*
G01X1789289Y469808D02*
X1791997Y476346D01*
G01X1792947Y476157D02*
Y478626D01*
G01X1791997Y476346D02*
Y478633D01*
G01X1802837Y466657D02*
Y467409D01*
G01X1801887Y466621D02*
Y467598D01*
G01X1802837Y467409D02*
X1804580Y471617D01*
G01X1801887Y467598D02*
X1803630Y471806D01*
G01X1804580Y471617D02*
Y473585D01*
G01X1803630Y471806D02*
Y473425D01*
G01X1815377Y467079D02*
Y477837D01*
G01X1814427Y466963D02*
Y477830D01*
G01X1828087Y476037D02*
Y466968D01*
G01X1827137Y467074D02*
Y476057D01*
G01X1776690Y467021D02*
Y470295D01*
G01X1777640Y467021D02*
Y470484D01*
G01X1776690Y470295D02*
X1776325Y471177D01*
G01X1777640Y470484D02*
X1777275Y471366D01*
G01X1776325Y471177D02*
Y474605D01*
G01X1777275Y471366D02*
Y474605D01*
G01X1789289Y467021D02*
Y469808D01*
G01X1790239Y467021D02*
Y469619D01*
G01X1789289Y469808D02*
X1791997Y476346D01*
G01X1790239Y469619D02*
X1792947Y476157D01*
G01X1791997Y476346D02*
Y478633D01*
G01X1792947Y476157D02*
Y478626D01*
G01X1801887Y466621D02*
Y467598D01*
G01X1802837Y466657D02*
Y467409D01*
G01X1801887Y467598D02*
X1803630Y471806D01*
G01X1802837Y467409D02*
X1804580Y471617D01*
G01X1803630Y471806D02*
Y473425D01*
G01X1804580Y471617D02*
Y473585D01*
G01X1814427Y466963D02*
Y477830D01*
G01X1815377Y467079D02*
Y477837D01*
G01X1827137Y467074D02*
Y476057D01*
G01X1828087Y476037D02*
Y466968D01*
G01X1777640Y467021D02*
Y470484D01*
G01X1776690Y467021D02*
Y470295D01*
G01X1777640Y470484D02*
X1777275Y471366D01*
G01X1776690Y470295D02*
X1776325Y471177D01*
G01X1777275Y471366D02*
Y474605D01*
G01X1776325Y471177D02*
Y474605D01*
G01X1790239Y467021D02*
Y469619D01*
G01X1789289Y467021D02*
Y469808D01*
G01X1790239Y469619D02*
X1792947Y476157D01*
G01X1789289Y469808D02*
X1791997Y476346D01*
G01X1792947Y476157D02*
Y478626D01*
G01X1791997Y476346D02*
Y478633D01*
G01X1802837Y466657D02*
Y467409D01*
G01X1801887Y466621D02*
Y467598D01*
G01X1802837Y467409D02*
X1804580Y471617D01*
G01X1801887Y467598D02*
X1803630Y471806D01*
G01X1804580Y471617D02*
Y473585D01*
G01X1803630Y471806D02*
Y473425D01*
G01X1815377Y467079D02*
Y477837D01*
G01X1814427Y466963D02*
Y477830D01*
G01X1828087Y476037D02*
Y466968D01*
G01X1827137Y467074D02*
Y476057D01*
G01X1776690Y467021D02*
Y470295D01*
G01X1777640Y467021D02*
Y470484D01*
G01X1776690Y470295D02*
X1776325Y471177D01*
G01X1777640Y470484D02*
X1777275Y471366D01*
G01X1776325Y471177D02*
Y474605D01*
G01X1777275Y471366D02*
Y474605D01*
G01X1789289Y467021D02*
Y469808D01*
G01X1790239Y467021D02*
Y469619D01*
G01X1789289Y469808D02*
X1791997Y476346D01*
G01X1790239Y469619D02*
X1792947Y476157D01*
G01X1791997Y476346D02*
Y478633D01*
G01X1792947Y476157D02*
Y478626D01*
G01X1801887Y466621D02*
Y467598D01*
G01X1802837Y466657D02*
Y467409D01*
G01X1801887Y467598D02*
X1803630Y471806D01*
G01X1802837Y467409D02*
X1804580Y471617D01*
G01X1803630Y471806D02*
Y473425D01*
G01X1804580Y471617D02*
Y473585D01*
G01X1814427Y466963D02*
Y477830D01*
G01X1815377Y467079D02*
Y477837D01*
G01X1827137Y467074D02*
Y476057D01*
G01X1828087Y476037D02*
Y466968D01*
G01X1910119Y206450D02*
X1911750D01*
G01X1910826Y207400D02*
X1912144D01*
G01X1910119Y206450D02*
X1911750D01*
G01D02*
X1913029Y205171D01*
G01X1912144Y207400D02*
X1913979Y205565D01*
G01X1913029Y205171D02*
Y203889D01*
G01X1913979Y205565D02*
Y203625D01*
G01X1910826Y207400D02*
X1912144D01*
G01D02*
X1913979Y205565D01*
G01X1910119Y206450D02*
X1911750D01*
G01X1912144Y207400D02*
X1913979Y205565D01*
G01X1911750Y206450D02*
X1913029Y205171D01*
G01X1913979Y205565D02*
Y203625D01*
G01X1913029Y205171D02*
Y203889D01*
G01X1913871Y193001D02*
Y193385D01*
G01X1914821Y193079D02*
Y193779D01*
G01X1913871Y193385D02*
X1912742Y194514D01*
G01X1914821Y193779D02*
X1913692Y194908D01*
G01X1912742Y194514D02*
Y196508D01*
G01X1913692Y194908D02*
Y196642D01*
G01X1914821Y193079D02*
Y193779D01*
G01X1913871Y193001D02*
Y193385D01*
G01X1914821Y193779D02*
X1913692Y194908D01*
G01X1913871Y193385D02*
X1912742Y194514D01*
G01X1913692Y194908D02*
Y196642D01*
G01X1912742Y194514D02*
Y196508D01*
G01X1908503Y192900D02*
Y194250D01*
G01Y196500D02*
Y198048D01*
G01X1909453Y190300D02*
Y198442D01*
G01X1908503Y198048D02*
X1906337Y200214D01*
G01X1909453Y198442D02*
X1907287Y200608D01*
G01X1906337Y200214D02*
Y202142D01*
G01X1907287Y200608D02*
Y202536D01*
G01X1906337Y202142D02*
X1905886Y202593D01*
G01X1907287Y202536D02*
X1906280Y203543D01*
G01X1905886Y202593D02*
X1905038D01*
G01X1906280Y203543D02*
X1905394D01*
G01X1909453Y190300D02*
Y198442D01*
G01X1908503Y192900D02*
Y194250D01*
G01X1909453Y190300D02*
Y198442D01*
G01X1908503Y196500D02*
Y198048D01*
G01X1909453Y198442D02*
X1907287Y200608D01*
G01X1908503Y198048D02*
X1906337Y200214D01*
G01X1907287Y200608D02*
Y202536D01*
G01X1906337Y200214D02*
Y202142D01*
G01X1907287Y202536D02*
X1906280Y203543D01*
G01X1906337Y202142D02*
X1905886Y202593D01*
G01X1906280Y203543D02*
X1905394D01*
G01X1905886Y202593D02*
X1905038D01*
G01X1951534Y216390D02*
X1952190D01*
G01Y217340D02*
X1951140D01*
G01X1950632Y215488D02*
X1951534Y216390D01*
G01D02*
X1952190D01*
G01X1951140Y217340D02*
X1950238Y216438D01*
G01X1948012Y215488D02*
X1950632D01*
G01D02*
X1951534Y216390D01*
G01X1950238Y216438D02*
X1948406D01*
G01X1944549Y218951D02*
X1948012Y215488D01*
G01X1948406Y216438D02*
X1944943Y219901D01*
G01X1948406Y216438D02*
X1944943Y219901D01*
G01X1948406Y216438D02*
X1944943Y219901D01*
G01X1944549Y218951D02*
X1948012Y215488D01*
G01X1950238Y216438D02*
X1948406D01*
G01X1948012Y215488D02*
X1950632D01*
G01X1951140Y217340D02*
X1950238Y216438D01*
G01D02*
X1948406D01*
G01X1950632Y215488D02*
X1951534Y216390D01*
G01X1952190Y217340D02*
X1951140D01*
G01D02*
X1950238Y216438D01*
G01X1951534Y216390D02*
X1952190D01*
G01X1943667Y218951D02*
X1944549D01*
G01X1943667D02*
X1944549D01*
G01X1944943Y219901D02*
X1943751D01*
G01X1944943D02*
X1943751D01*
G01X1943667Y218951D02*
X1944549D01*
G54D13*
G01X1161577Y-46380D02*
X1139678D01*
G01X1160827Y-48190D02*
X1139678D01*
G01X1160827D02*
X1139678D01*
G01X1161577Y-46380D02*
X1139678D01*
G01X1365330Y-41050D02*
X1171158D01*
G01X1365330Y-42860D02*
X1171158D01*
G01Y-41050D02*
G03Y-48430I0J-3690D01*
G01Y-42860D02*
G03Y-46620I0J-1880D01*
G01Y-48430D02*
X1363437D01*
G01X1171158Y-46620D02*
X1363437D01*
G01Y-52190D02*
X1167387D01*
G01X1363437Y-54000D02*
X1166637D01*
G01X1167387Y-52190D02*
X1161577Y-46380D01*
G01X1166637Y-54000D02*
X1160827Y-48190D01*
G01X1365330Y-42860D02*
X1171158D01*
G01X1365330Y-41050D02*
X1171158D01*
G01Y-42860D02*
G03Y-46620I0J-1880D01*
G01Y-41050D02*
G03Y-48430I0J-3690D01*
G01Y-46620D02*
X1363437D01*
G01X1171158Y-48430D02*
X1363437D01*
G01Y-54000D02*
X1166637D01*
G01X1363437Y-52190D02*
X1167387D01*
G01X1166637Y-54000D02*
X1160827Y-48190D01*
G01X1167387Y-52190D02*
X1161577Y-46380D01*
G01X1363437Y-48430D02*
G02Y-52190I0J-1880D01*
G01Y-46620D02*
G02Y-54000I0J-3690D01*
G01Y-46620D02*
G02Y-54000I0J-3690D01*
G01Y-48430D02*
G02Y-52190I0J-1880D01*
G01X1880630Y38374D02*
X1886857Y32147D01*
G01D02*
X1891800D01*
G01D02*
X1893308Y33655D01*
G01X1877579Y33145D02*
X1878555Y32169D01*
G01X1870670Y37494D02*
X1876745Y31419D01*
G01X1878555Y32169D02*
Y27033D01*
G01X1876745Y31419D02*
Y27783D01*
G01X1878555Y27033D02*
X1874912Y23390D01*
G01X1876745Y27783D02*
X1873102Y24140D01*
G01X1874912Y23390D02*
Y17537D01*
G01X1873102Y24140D02*
Y16787D01*
G01X1874912Y17537D02*
X1875995Y16454D01*
G01X1873102Y16787D02*
X1875245Y14644D01*
G01X1875995Y16454D02*
X1877996D01*
G01X1875245Y14644D02*
X1878746D01*
G01X1877996Y16454D02*
X1881022Y19480D01*
G01X1878746Y14644D02*
X1881772Y17670D01*
G01X1881022Y19480D02*
X1885739D01*
G01X1881772Y17670D02*
X1886489D01*
G01X1885739Y19480D02*
X1886399Y20140D01*
G01X1889213Y22954D02*
X1890189Y23930D01*
G01X1893003Y26744D02*
X1893719Y27460D01*
G01X1886489Y17670D02*
X1894469Y25650D01*
G01X1893719Y27460D02*
X1896491D01*
G01X1894469Y25650D02*
X1900945D01*
G01X1870670Y37494D02*
X1876745Y31419D01*
G01X1870670Y37494D02*
X1876745Y31419D01*
G01X1877579Y33145D02*
X1878555Y32169D01*
G01X1876745Y31419D02*
Y27783D01*
G01X1878555Y32169D02*
Y27033D01*
G01X1876745Y27783D02*
X1873102Y24140D01*
G01X1878555Y27033D02*
X1874912Y23390D01*
G01X1873102Y24140D02*
Y16787D01*
G01X1874912Y23390D02*
Y17537D01*
G01X1873102Y16787D02*
X1875245Y14644D01*
G01X1874912Y17537D02*
X1875995Y16454D01*
G01X1875245Y14644D02*
X1878746D01*
G01X1875995Y16454D02*
X1877996D01*
G01X1878746Y14644D02*
X1881772Y17670D01*
G01X1877996Y16454D02*
X1881022Y19480D01*
G01X1881772Y17670D02*
X1886489D01*
G01X1881022Y19480D02*
X1885739D01*
G01X1886489Y17670D02*
X1894469Y25650D01*
G01X1885739Y19480D02*
X1886399Y20140D01*
G01X1886489Y17670D02*
X1894469Y25650D01*
G01X1889213Y22954D02*
X1890189Y23930D01*
G01X1886489Y17670D02*
X1894469Y25650D01*
G01X1893003Y26744D02*
X1893719Y27460D01*
G01X1894469Y25650D02*
X1900945D01*
G01X1893719Y27460D02*
X1896491D01*
G01X1880630Y38374D02*
X1886857Y32147D01*
G01D02*
X1891800D01*
G01D02*
X1893308Y33655D01*
G01X1882440Y40276D02*
Y39124D01*
G01X1880630Y45611D02*
Y38374D01*
G01X1882440Y39124D02*
X1887607Y33957D01*
G01D02*
X1891050D01*
G01D02*
X1892558Y35465D01*
G01D02*
X1896410D01*
G01X1893308Y33655D02*
X1900932D01*
G01X1875916Y56609D02*
X1873369D01*
G01X1878908Y58419D02*
X1872619D01*
G01X1873369Y56609D02*
X1872480Y55720D01*
G01X1872619Y58419D02*
X1870670Y56470D01*
G01X1872480Y55720D02*
Y50672D01*
G01Y46692D02*
Y45312D01*
G01Y41332D02*
Y38244D01*
G01X1870670Y56470D02*
Y37494D01*
G01X1872480Y38244D02*
X1874765Y35959D01*
G01X1878908Y58419D02*
X1872619D01*
G01X1875916Y56609D02*
X1873369D01*
G01X1872619Y58419D02*
X1870670Y56470D01*
G01X1873369Y56609D02*
X1872480Y55720D01*
G01X1870670Y56470D02*
Y37494D01*
G01X1872480Y55720D02*
Y50672D01*
G01X1870670Y56470D02*
Y37494D01*
G01X1872480Y46692D02*
Y45312D01*
G01X1870670Y56470D02*
Y37494D01*
G01X1872480Y41332D02*
Y38244D01*
G01D02*
X1874765Y35959D01*
G01X1884659Y57625D02*
X1887623D01*
G01X1884648Y59435D02*
X1887623D01*
G01X1884648D02*
X1887623D01*
G01X1884659Y57625D02*
X1887623D01*
G01X1880630Y45611D02*
Y38374D01*
G01X1882440Y40276D02*
Y39124D01*
G01D02*
X1887607Y33957D01*
G01D02*
X1891050D01*
G01D02*
X1892558Y35465D01*
G01X1893308Y33655D02*
X1900932D01*
G01X1892558Y35465D02*
X1896410D01*
G01X1884659Y57625D02*
X1887623D01*
G01X1884648Y59435D02*
X1887623D01*
G01X1884659Y57625D02*
X1887623D01*
G01X1884648Y59435D02*
X1887623D01*
G01X1884659Y57625D02*
X1887623D01*
G01X1884648Y59435D02*
X1887623D01*
G01X1884648D02*
X1887623D01*
G01X1884659Y57625D02*
X1887623D01*
G01X1909373Y154015D02*
Y153263D01*
G01X1907563Y153947D02*
Y152513D01*
G01X1909373Y153263D02*
X1911759Y150877D01*
G01X1907563Y152513D02*
X1909949Y150127D01*
G01X1907563Y153947D02*
Y152513D01*
G01X1909373Y154015D02*
Y153263D01*
G01X1907563Y152513D02*
X1909949Y150127D01*
G01X1909373Y153263D02*
X1911759Y150877D01*
G01X1903468Y148749D02*
X1907514Y144703D01*
G01X1903566Y146091D02*
X1905704Y143953D01*
G01X1907514Y144703D02*
Y143410D01*
G01X1905704Y143953D02*
Y143135D01*
G01X1903468Y148749D02*
X1907514Y144703D01*
G01X1903566Y146091D02*
X1901658Y147999D01*
G01X1903468Y153344D02*
Y148749D01*
G01X1901658Y147999D02*
Y153344D01*
G01Y147999D02*
Y153344D01*
G01X1903468D02*
Y148749D01*
G01X1903566Y146091D02*
X1905704Y143953D01*
G01X1903566Y146091D02*
X1901658Y147999D01*
G01X1903468Y148749D02*
X1907514Y144703D01*
G01X1905704Y143953D02*
Y143135D01*
G01X1907514Y144703D02*
Y143410D01*
G01X1909373Y154015D02*
Y153263D01*
G01X1907563Y153947D02*
Y152513D01*
G01X1909373Y153263D02*
X1911759Y150877D01*
G01X1907563Y152513D02*
X1909949Y150127D01*
G01X1907563Y153947D02*
Y152513D01*
G01X1909373Y154015D02*
Y153263D01*
G01X1907563Y152513D02*
X1909949Y150127D01*
G01X1909373Y153263D02*
X1911759Y150877D01*
G01X1903468Y148749D02*
X1907514Y144703D01*
G01X1903566Y146091D02*
X1905704Y143953D01*
G01X1907514Y144703D02*
Y143410D01*
G01X1905704Y143953D02*
Y143135D01*
G01X1903468Y148749D02*
X1907514Y144703D01*
G01X1903566Y146091D02*
X1901658Y147999D01*
G01X1903468Y153344D02*
Y148749D01*
G01X1901658Y147999D02*
Y153344D01*
G01X1903468Y148749D02*
X1907514Y144703D01*
G01X1903566Y146091D02*
X1905704Y143953D01*
G01X1907514Y144703D02*
Y143410D01*
G01X1905704Y143953D02*
Y143135D01*
G01X1903468Y148749D02*
X1907514Y144703D01*
G01X1903566Y146091D02*
X1901658Y147999D01*
G01X1903468Y153344D02*
Y148749D01*
G01X1901658Y147999D02*
Y153344D01*
G01X1903468Y148749D02*
X1907514Y144703D01*
G01X1903566Y146091D02*
X1905704Y143953D01*
G01X1907514Y144703D02*
Y143410D01*
G01X1905704Y143953D02*
Y143135D01*
G01X1903468Y148749D02*
X1907514Y144703D01*
G01X1903566Y146091D02*
X1901658Y147999D01*
G01X1903468Y153344D02*
Y148749D01*
G01X1901658Y147999D02*
Y153344D01*
G01Y147999D02*
Y153344D01*
G01X1903468D02*
Y148749D01*
G01X1903566Y146091D02*
X1905704Y143953D01*
G01X1903566Y146091D02*
X1901658Y147999D01*
G01X1903468Y148749D02*
X1907514Y144703D01*
G01X1905704Y143953D02*
Y143135D01*
G01X1907514Y144703D02*
Y143410D01*
G54D14*
G01X170984Y94681D02*
X171742Y93923D01*
G01X172892Y94400D02*
X172134Y95158D01*
G01X170984Y94681D02*
X171742Y93923D01*
G01X172892Y94400D02*
X172134Y95158D01*
G01X176896Y89309D02*
Y99177D01*
G01Y89309D02*
Y99177D01*
G01X172892Y94400D02*
X172134Y95158D01*
G01X170984Y94681D02*
X171742Y93923D01*
G01X172892Y94400D02*
X172134Y95158D01*
G01X170984Y94681D02*
X171742Y93923D01*
G01X176896Y89309D02*
Y99177D01*
G01Y89309D02*
Y99177D01*
G01X172892Y94400D02*
X172134Y95158D01*
G01X170984Y94681D02*
X171742Y93923D01*
G01X176896Y89309D02*
Y99177D01*
G01X170984Y99983D02*
Y94681D01*
G01X172134Y95158D02*
Y96158D01*
G01X170984Y99983D02*
Y94681D01*
G01X172134Y98158D02*
Y99506D01*
G01X184651Y113650D02*
X170984Y99983D01*
G01X172134Y99506D02*
X174164Y101536D01*
G01X184651Y113650D02*
X170984Y99983D01*
G01X174164Y101536D02*
X175136D01*
G01X184651Y113650D02*
X170984Y99983D01*
G01X175700Y103072D02*
X176428Y103800D01*
G01X184651Y113650D02*
X170984Y99983D01*
G01X176428Y103800D02*
X177100D01*
G01X184651Y113650D02*
X170984Y99983D01*
G01X177800Y105172D02*
X178828Y106200D01*
G01X184651Y113650D02*
X170984Y99983D01*
G01X178828Y106200D02*
X179800D01*
G01X184651Y113650D02*
X170984Y99983D01*
G01X180800Y108172D02*
X185128Y112500D01*
G01X186777Y113650D02*
X184651D01*
G01D02*
X170984Y99983D01*
G01X185128Y112500D02*
X186300D01*
G01X187577Y112850D02*
X186777Y113650D01*
G01X186300Y112500D02*
X187100Y111700D01*
G01X188523Y112850D02*
X187577D01*
G01X187100Y111700D02*
X189000D01*
G01X189323Y113650D02*
X188523Y112850D01*
G01X189000Y111700D02*
X189800Y112500D01*
G01X190523Y113650D02*
X189323D01*
G01X189800Y112500D02*
X191000D01*
G01X195800Y118927D02*
X190523Y113650D01*
G01X191000Y112500D02*
X196950Y118450D01*
G01X195800Y124600D02*
Y127127D01*
G01Y124600D02*
Y118927D01*
G01X196950Y118450D02*
Y126650D01*
G01X195800Y127127D02*
X202734Y134061D01*
G01X196950Y126650D02*
X203884Y133584D01*
G01X202734Y134061D02*
Y134766D01*
G01X203884Y133584D02*
Y135243D01*
G01X202734Y134766D02*
X199366Y138134D01*
G01X203884Y135243D02*
X200516Y138611D01*
G01X199366Y138134D02*
Y140302D01*
G01X200516Y138611D02*
Y139825D01*
G01X199366Y140302D02*
X202750Y143686D01*
G01X200516Y139825D02*
X203900Y143209D01*
G01X202750Y143686D02*
Y147967D01*
G01X203900Y143209D02*
Y147490D01*
G01X202750Y147967D02*
X206231Y151448D01*
G01X203900Y147490D02*
X207381Y150971D01*
G01X206231Y151448D02*
Y173477D01*
G01X207381Y150971D02*
Y173000D01*
G01X170984Y99983D02*
Y94681D01*
G01X172134Y95158D02*
Y96158D01*
G01X170984Y99983D02*
Y94681D01*
G01X172134Y98158D02*
Y99506D01*
G01X184651Y113650D02*
X170984Y99983D01*
G01X172134Y99506D02*
X174164Y101536D01*
G01X184651Y113650D02*
X170984Y99983D01*
G01X174164Y101536D02*
X175136D01*
G01X184651Y113650D02*
X170984Y99983D01*
G01X175700Y103072D02*
X176428Y103800D01*
G01X184651Y113650D02*
X170984Y99983D01*
G01X176428Y103800D02*
X177100D01*
G01X184651Y113650D02*
X170984Y99983D01*
G01X177800Y105172D02*
X178828Y106200D01*
G01X184651Y113650D02*
X170984Y99983D01*
G01X178828Y106200D02*
X179800D01*
G01X184651Y113650D02*
X170984Y99983D01*
G01X180800Y108172D02*
X185128Y112500D01*
G01X186777Y113650D02*
X184651D01*
G01D02*
X170984Y99983D01*
G01X185128Y112500D02*
X186300D01*
G01X187577Y112850D02*
X186777Y113650D01*
G01X186300Y112500D02*
X187100Y111700D01*
G01X188523Y112850D02*
X187577D01*
G01X187100Y111700D02*
X189000D01*
G01X189323Y113650D02*
X188523Y112850D01*
G01X189000Y111700D02*
X189800Y112500D01*
G01X190523Y113650D02*
X189323D01*
G01X189800Y112500D02*
X191000D01*
G01X195800Y118927D02*
X190523Y113650D01*
G01X191000Y112500D02*
X196950Y118450D01*
G01X195800Y124600D02*
Y127127D01*
G01Y124600D02*
Y118927D01*
G01X196950Y118450D02*
Y126650D01*
G01X195800Y127127D02*
X202734Y134061D01*
G01X196950Y126650D02*
X203884Y133584D01*
G01X202734Y134061D02*
Y134766D01*
G01X203884Y133584D02*
Y135243D01*
G01X202734Y134766D02*
X199366Y138134D01*
G01X203884Y135243D02*
X200516Y138611D01*
G01X199366Y138134D02*
Y140302D01*
G01X200516Y138611D02*
Y139825D01*
G01X199366Y140302D02*
X202750Y143686D01*
G01X200516Y139825D02*
X203900Y143209D01*
G01X202750Y143686D02*
Y147967D01*
G01X203900Y143209D02*
Y147490D01*
G01X202750Y147967D02*
X206231Y151448D01*
G01X203900Y147490D02*
X207381Y150971D01*
G01X206231Y151448D02*
Y173477D01*
G01X207381Y150971D02*
Y173000D01*
G01X178046Y98700D02*
Y95046D01*
G01X178546Y99200D02*
X178046Y98700D01*
G01X176896Y99177D02*
X178069Y100350D01*
G01X183400Y99200D02*
X178546D01*
G01X178069Y100350D02*
X182923D01*
G01X200900Y116700D02*
X183400Y99200D01*
G01X182923Y100350D02*
X199750Y117177D01*
G01X200900Y120704D02*
Y124557D01*
G01Y120704D02*
Y116700D01*
G01X199750Y117177D02*
Y125034D01*
G01X200900Y124557D02*
X207666Y131323D01*
G01X199750Y125034D02*
X206516Y131800D01*
G01X207666Y131323D02*
Y134294D01*
G01Y136294D02*
Y137294D01*
G01Y139294D02*
Y140294D01*
G01Y142294D02*
Y143294D01*
G01Y145294D02*
Y146066D01*
G01X206516Y131800D02*
Y146543D01*
G01X207666Y146066D02*
X211281Y149681D01*
G01X206516Y146543D02*
X210131Y150158D01*
G01X211281Y149681D02*
Y161100D01*
G01X210131Y150158D02*
Y161577D01*
G01X178046Y98700D02*
Y95046D01*
G01X178546Y99200D02*
X178046Y98700D01*
G01X176896Y99177D02*
X178069Y100350D01*
G01X183400Y99200D02*
X178546D01*
G01X178069Y100350D02*
X182923D01*
G01X200900Y116700D02*
X183400Y99200D01*
G01X182923Y100350D02*
X199750Y117177D01*
G01X200900Y120704D02*
Y124557D01*
G01Y120704D02*
Y116700D01*
G01X199750Y117177D02*
Y125034D01*
G01X200900Y124557D02*
X207666Y131323D01*
G01X199750Y125034D02*
X206516Y131800D01*
G01X207666Y131323D02*
Y134294D01*
G01Y136294D02*
Y137294D01*
G01Y139294D02*
Y140294D01*
G01Y142294D02*
Y143294D01*
G01Y145294D02*
Y146066D01*
G01X206516Y131800D02*
Y146543D01*
G01X207666Y146066D02*
X211281Y149681D01*
G01X206516Y146543D02*
X210131Y150158D01*
G01X211281Y149681D02*
Y161100D01*
G01X210131Y150158D02*
Y161577D01*
G01X196950Y118450D02*
Y126650D01*
G01X195800Y124600D02*
Y127127D01*
G01X196950Y126650D02*
X203884Y133584D01*
G01X195800Y127127D02*
X202734Y134061D01*
G01X203884Y133584D02*
Y135243D01*
G01X202734Y134061D02*
Y134766D01*
G01X203884Y135243D02*
X200516Y138611D01*
G01X202734Y134766D02*
X199366Y138134D01*
G01X200516Y138611D02*
Y139825D01*
G01X199366Y138134D02*
Y140302D01*
G01X200516Y139825D02*
X203900Y143209D01*
G01X199366Y140302D02*
X202750Y143686D01*
G01X203900Y143209D02*
Y147490D01*
G01X202750Y143686D02*
Y147967D01*
G01X203900Y147490D02*
X207381Y150971D01*
G01X202750Y147967D02*
X206231Y151448D01*
G01X207381Y150971D02*
Y173000D01*
G01X206231Y151448D02*
Y173477D01*
G01X196950Y118450D02*
Y126650D01*
G01X195800Y124600D02*
Y118927D01*
G01X191000Y112500D02*
X196950Y118450D01*
G01X195800Y118927D02*
X190523Y113650D01*
G01X189800Y112500D02*
X191000D01*
G01X190523Y113650D02*
X189323D01*
G01X189000Y111700D02*
X189800Y112500D01*
G01X189323Y113650D02*
X188523Y112850D01*
G01X187100Y111700D02*
X189000D01*
G01X188523Y112850D02*
X187577D01*
G01X186300Y112500D02*
X187100Y111700D01*
G01X187577Y112850D02*
X186777Y113650D01*
G01X185128Y112500D02*
X186300D01*
G01X186777Y113650D02*
X184651D01*
G01X172134Y99506D02*
X174164Y101536D01*
G01D02*
X175136D01*
G01X175700Y103072D02*
X176428Y103800D01*
G01D02*
X177100D01*
G01X177800Y105172D02*
X178828Y106200D01*
G01D02*
X179800D01*
G01X180800Y108172D02*
X185128Y112500D01*
G01D02*
X186300D01*
G01X184651Y113650D02*
X170984Y99983D01*
G01X172134Y95158D02*
Y96158D01*
G01Y98158D02*
Y99506D01*
G01X170984Y99983D02*
Y94681D01*
G01X196950Y118450D02*
Y126650D01*
G01X195800Y124600D02*
Y127127D01*
G01X196950Y126650D02*
X203884Y133584D01*
G01X195800Y127127D02*
X202734Y134061D01*
G01X203884Y133584D02*
Y135243D01*
G01X202734Y134061D02*
Y134766D01*
G01X203884Y135243D02*
X200516Y138611D01*
G01X202734Y134766D02*
X199366Y138134D01*
G01X200516Y138611D02*
Y139825D01*
G01X199366Y138134D02*
Y140302D01*
G01X200516Y139825D02*
X203900Y143209D01*
G01X199366Y140302D02*
X202750Y143686D01*
G01X203900Y143209D02*
Y147490D01*
G01X202750Y143686D02*
Y147967D01*
G01X203900Y147490D02*
X207381Y150971D01*
G01X202750Y147967D02*
X206231Y151448D01*
G01X207381Y150971D02*
Y173000D01*
G01X206231Y151448D02*
Y173477D01*
G01X196950Y118450D02*
Y126650D01*
G01X195800Y124600D02*
Y118927D01*
G01X191000Y112500D02*
X196950Y118450D01*
G01X195800Y118927D02*
X190523Y113650D01*
G01X189800Y112500D02*
X191000D01*
G01X190523Y113650D02*
X189323D01*
G01X189000Y111700D02*
X189800Y112500D01*
G01X189323Y113650D02*
X188523Y112850D01*
G01X187100Y111700D02*
X189000D01*
G01X188523Y112850D02*
X187577D01*
G01X186300Y112500D02*
X187100Y111700D01*
G01X187577Y112850D02*
X186777Y113650D01*
G01X185128Y112500D02*
X186300D01*
G01X186777Y113650D02*
X184651D01*
G01X172134Y99506D02*
X174164Y101536D01*
G01D02*
X175136D01*
G01X175700Y103072D02*
X176428Y103800D01*
G01D02*
X177100D01*
G01X177800Y105172D02*
X178828Y106200D01*
G01D02*
X179800D01*
G01X180800Y108172D02*
X185128Y112500D01*
G01D02*
X186300D01*
G01X184651Y113650D02*
X170984Y99983D01*
G01X172134Y95158D02*
Y96158D01*
G01Y98158D02*
Y99506D01*
G01X170984Y99983D02*
Y94681D01*
G01X199750Y117177D02*
Y125034D01*
G01X200900Y120704D02*
Y124557D01*
G01X199750Y125034D02*
X206516Y131800D01*
G01X200900Y124557D02*
X207666Y131323D01*
G01X206516Y131800D02*
Y146543D01*
G01X207666Y131323D02*
Y134294D01*
G01X206516Y131800D02*
Y146543D01*
G01X207666Y136294D02*
Y137294D01*
G01X206516Y131800D02*
Y146543D01*
G01X207666Y139294D02*
Y140294D01*
G01X206516Y131800D02*
Y146543D01*
G01X207666Y142294D02*
Y143294D01*
G01X206516Y131800D02*
Y146543D01*
G01X207666Y145294D02*
Y146066D01*
G01X206516Y146543D02*
X210131Y150158D01*
G01X207666Y146066D02*
X211281Y149681D01*
G01X210131Y150158D02*
Y161577D01*
G01X211281Y149681D02*
Y161100D01*
G01X199750Y117177D02*
Y125034D01*
G01X200900Y120704D02*
Y116700D01*
G01X182923Y100350D02*
X199750Y117177D01*
G01X200900Y116700D02*
X183400Y99200D01*
G01X178069Y100350D02*
X182923D01*
G01X183400Y99200D02*
X178546D01*
G01X176896Y99177D02*
X178069Y100350D01*
G01X178546Y99200D02*
X178046Y98700D01*
G01D02*
Y95046D01*
G01X199750Y117177D02*
Y125034D01*
G01X200900Y120704D02*
Y124557D01*
G01X199750Y125034D02*
X206516Y131800D01*
G01X200900Y124557D02*
X207666Y131323D01*
G01X206516Y131800D02*
Y146543D01*
G01X207666Y131323D02*
Y134294D01*
G01X206516Y131800D02*
Y146543D01*
G01X207666Y136294D02*
Y137294D01*
G01X206516Y131800D02*
Y146543D01*
G01X207666Y139294D02*
Y140294D01*
G01X206516Y131800D02*
Y146543D01*
G01X207666Y142294D02*
Y143294D01*
G01X206516Y131800D02*
Y146543D01*
G01X207666Y145294D02*
Y146066D01*
G01X206516Y146543D02*
X210131Y150158D01*
G01X207666Y146066D02*
X211281Y149681D01*
G01X210131Y150158D02*
Y161577D01*
G01X211281Y149681D02*
Y161100D01*
G01X199750Y117177D02*
Y125034D01*
G01X200900Y120704D02*
Y116700D01*
G01X182923Y100350D02*
X199750Y117177D01*
G01X200900Y116700D02*
X183400Y99200D01*
G01X178069Y100350D02*
X182923D01*
G01X183400Y99200D02*
X178546D01*
G01X176896Y99177D02*
X178069Y100350D01*
G01X178546Y99200D02*
X178046Y98700D01*
G01D02*
Y95046D01*
G01X196950Y118450D02*
Y126650D01*
G01X195800Y124600D02*
Y127127D01*
G01X196950Y126650D02*
X203884Y133584D01*
G01X195800Y127127D02*
X202734Y134061D01*
G01X203884Y133584D02*
Y135243D01*
G01X202734Y134061D02*
Y134766D01*
G01X203884Y135243D02*
X200516Y138611D01*
G01X202734Y134766D02*
X199366Y138134D01*
G01X200516Y138611D02*
Y139825D01*
G01X199366Y138134D02*
Y140302D01*
G01X200516Y139825D02*
X203900Y143209D01*
G01X199366Y140302D02*
X202750Y143686D01*
G01X203900Y143209D02*
Y147490D01*
G01X202750Y143686D02*
Y147967D01*
G01X203900Y147490D02*
X207381Y150971D01*
G01X202750Y147967D02*
X206231Y151448D01*
G01X207381Y150971D02*
Y173000D01*
G01X206231Y151448D02*
Y173477D01*
G01X196950Y118450D02*
Y126650D01*
G01X195800Y124600D02*
Y118927D01*
G01X191000Y112500D02*
X196950Y118450D01*
G01X195800Y118927D02*
X190523Y113650D01*
G01X189800Y112500D02*
X191000D01*
G01X190523Y113650D02*
X189323D01*
G01X189000Y111700D02*
X189800Y112500D01*
G01X189323Y113650D02*
X188523Y112850D01*
G01X187100Y111700D02*
X189000D01*
G01X188523Y112850D02*
X187577D01*
G01X186300Y112500D02*
X187100Y111700D01*
G01X187577Y112850D02*
X186777Y113650D01*
G01X185128Y112500D02*
X186300D01*
G01X186777Y113650D02*
X184651D01*
G01X172134Y99506D02*
X174164Y101536D01*
G01D02*
X175136D01*
G01X175700Y103072D02*
X176428Y103800D01*
G01D02*
X177100D01*
G01X177800Y105172D02*
X178828Y106200D01*
G01D02*
X179800D01*
G01X180800Y108172D02*
X185128Y112500D01*
G01D02*
X186300D01*
G01X184651Y113650D02*
X170984Y99983D01*
G01X172134Y95158D02*
Y96158D01*
G01Y98158D02*
Y99506D01*
G01X170984Y99983D02*
Y94681D01*
G01X199750Y117177D02*
Y125034D01*
G01X200900Y120704D02*
Y124557D01*
G01X199750Y125034D02*
X206516Y131800D01*
G01X200900Y124557D02*
X207666Y131323D01*
G01X206516Y131800D02*
Y146543D01*
G01X207666Y131323D02*
Y134294D01*
G01X206516Y131800D02*
Y146543D01*
G01X207666Y136294D02*
Y137294D01*
G01X206516Y131800D02*
Y146543D01*
G01X207666Y139294D02*
Y140294D01*
G01X206516Y131800D02*
Y146543D01*
G01X207666Y142294D02*
Y143294D01*
G01X206516Y131800D02*
Y146543D01*
G01X207666Y145294D02*
Y146066D01*
G01X206516Y146543D02*
X210131Y150158D01*
G01X207666Y146066D02*
X211281Y149681D01*
G01X210131Y150158D02*
Y161577D01*
G01X211281Y149681D02*
Y161100D01*
G01X199750Y117177D02*
Y125034D01*
G01X200900Y120704D02*
Y116700D01*
G01X182923Y100350D02*
X199750Y117177D01*
G01X200900Y116700D02*
X183400Y99200D01*
G01X178069Y100350D02*
X182923D01*
G01X183400Y99200D02*
X178546D01*
G01X176896Y99177D02*
X178069Y100350D01*
G01X178546Y99200D02*
X178046Y98700D01*
G01D02*
Y95046D01*
G01X206231Y173477D02*
X207404Y174650D01*
G01X207381Y173000D02*
X207881Y173500D01*
G01X207404Y174650D02*
X209449D01*
G01X207881Y173500D02*
X209926D01*
G01X209449Y174650D02*
X209950Y175151D01*
G01X209926Y173500D02*
X211100Y174674D01*
G01X209950Y175151D02*
Y179773D01*
G01X211100Y174674D02*
Y179296D01*
G01X209950Y179773D02*
X255468Y225291D01*
G01X211100Y179296D02*
X255945Y224141D01*
G01X206231Y173477D02*
X207404Y174650D01*
G01X207381Y173000D02*
X207881Y173500D01*
G01X207404Y174650D02*
X209449D01*
G01X207881Y173500D02*
X209926D01*
G01X209449Y174650D02*
X209950Y175151D01*
G01X209926Y173500D02*
X211100Y174674D01*
G01X209950Y175151D02*
Y179773D01*
G01X211100Y174674D02*
Y179296D01*
G01X209950Y179773D02*
X255468Y225291D01*
G01X211100Y179296D02*
X255945Y224141D01*
G01X211281Y161100D02*
X211781Y161600D01*
G01X210131Y161577D02*
X211304Y162750D01*
G01X211781Y161600D02*
X216708D01*
G01X211304Y162750D02*
X216231D01*
G01X216708Y161600D02*
X217881Y162773D01*
G01X216231Y162750D02*
X216731Y163250D01*
G01X217881Y162773D02*
Y165477D01*
G01X216731Y163250D02*
Y165000D01*
G01X217881Y165477D02*
X216708Y166650D01*
G01X216731Y165000D02*
X216231Y165500D01*
G01X216708Y166650D02*
X211550D01*
G01X216231Y165500D02*
X211073D01*
G01X211550Y166650D02*
X211050Y167150D01*
G01X211073Y165500D02*
X209900Y166673D01*
G01X211050Y167150D02*
Y169100D01*
G01X209900Y166673D02*
Y169577D01*
G01X211050Y169100D02*
X211550Y169600D01*
G01X209900Y169577D02*
X211073Y170750D01*
G01X211550Y169600D02*
X213727D01*
G01X211073Y170750D02*
X213250D01*
G01X213727Y169600D02*
X214900Y170773D01*
G01X213250Y170750D02*
X213750Y171250D01*
G01X214900Y170773D02*
Y177561D01*
G01X213750Y171250D02*
Y178038D01*
G01X214900Y177561D02*
X257255Y219916D01*
G01X213750Y178038D02*
X256778Y221066D01*
G01X211281Y161100D02*
X211781Y161600D01*
G01X210131Y161577D02*
X211304Y162750D01*
G01X211781Y161600D02*
X216708D01*
G01X211304Y162750D02*
X216231D01*
G01X216708Y161600D02*
X217881Y162773D01*
G01X216231Y162750D02*
X216731Y163250D01*
G01X217881Y162773D02*
Y165477D01*
G01X216731Y163250D02*
Y165000D01*
G01X217881Y165477D02*
X216708Y166650D01*
G01X216731Y165000D02*
X216231Y165500D01*
G01X216708Y166650D02*
X211550D01*
G01X216231Y165500D02*
X211073D01*
G01X211550Y166650D02*
X211050Y167150D01*
G01X211073Y165500D02*
X209900Y166673D01*
G01X211050Y167150D02*
Y169100D01*
G01X209900Y166673D02*
Y169577D01*
G01X211050Y169100D02*
X211550Y169600D01*
G01X209900Y169577D02*
X211073Y170750D01*
G01X211550Y169600D02*
X213727D01*
G01X211073Y170750D02*
X213250D01*
G01X213727Y169600D02*
X214900Y170773D01*
G01X213250Y170750D02*
X213750Y171250D01*
G01X214900Y170773D02*
Y177561D01*
G01X213750Y171250D02*
Y178038D01*
G01X214900Y177561D02*
X257255Y219916D01*
G01X213750Y178038D02*
X256778Y221066D01*
G01X207381Y173000D02*
X207881Y173500D01*
G01X206231Y173477D02*
X207404Y174650D01*
G01X207881Y173500D02*
X209926D01*
G01X207404Y174650D02*
X209449D01*
G01X209926Y173500D02*
X211100Y174674D01*
G01X209449Y174650D02*
X209950Y175151D01*
G01X211100Y174674D02*
Y179296D01*
G01X209950Y175151D02*
Y179773D01*
G01X211100Y179296D02*
X255945Y224141D01*
G01X209950Y179773D02*
X255468Y225291D01*
G01X207381Y173000D02*
X207881Y173500D01*
G01X206231Y173477D02*
X207404Y174650D01*
G01X207881Y173500D02*
X209926D01*
G01X207404Y174650D02*
X209449D01*
G01X209926Y173500D02*
X211100Y174674D01*
G01X209449Y174650D02*
X209950Y175151D01*
G01X211100Y174674D02*
Y179296D01*
G01X209950Y175151D02*
Y179773D01*
G01X211100Y179296D02*
X255945Y224141D01*
G01X209950Y179773D02*
X255468Y225291D01*
G01X210131Y161577D02*
X211304Y162750D01*
G01X211281Y161100D02*
X211781Y161600D01*
G01X211304Y162750D02*
X216231D01*
G01X211781Y161600D02*
X216708D01*
G01X216231Y162750D02*
X216731Y163250D01*
G01X216708Y161600D02*
X217881Y162773D01*
G01X216731Y163250D02*
Y165000D01*
G01X217881Y162773D02*
Y165477D01*
G01X216731Y165000D02*
X216231Y165500D01*
G01X217881Y165477D02*
X216708Y166650D01*
G01X216231Y165500D02*
X211073D01*
G01X216708Y166650D02*
X211550D01*
G01X211073Y165500D02*
X209900Y166673D01*
G01X211550Y166650D02*
X211050Y167150D01*
G01X209900Y166673D02*
Y169577D01*
G01X211050Y167150D02*
Y169100D01*
G01X209900Y169577D02*
X211073Y170750D01*
G01X211050Y169100D02*
X211550Y169600D01*
G01X211073Y170750D02*
X213250D01*
G01X211550Y169600D02*
X213727D01*
G01X213250Y170750D02*
X213750Y171250D01*
G01X213727Y169600D02*
X214900Y170773D01*
G01X213750Y171250D02*
Y178038D01*
G01X214900Y170773D02*
Y177561D01*
G01X213750Y178038D02*
X256778Y221066D01*
G01X214900Y177561D02*
X257255Y219916D01*
G01X210131Y161577D02*
X211304Y162750D01*
G01X211281Y161100D02*
X211781Y161600D01*
G01X211304Y162750D02*
X216231D01*
G01X211781Y161600D02*
X216708D01*
G01X216231Y162750D02*
X216731Y163250D01*
G01X216708Y161600D02*
X217881Y162773D01*
G01X216731Y163250D02*
Y165000D01*
G01X217881Y162773D02*
Y165477D01*
G01X216731Y165000D02*
X216231Y165500D01*
G01X217881Y165477D02*
X216708Y166650D01*
G01X216231Y165500D02*
X211073D01*
G01X216708Y166650D02*
X211550D01*
G01X211073Y165500D02*
X209900Y166673D01*
G01X211550Y166650D02*
X211050Y167150D01*
G01X209900Y166673D02*
Y169577D01*
G01X211050Y167150D02*
Y169100D01*
G01X209900Y169577D02*
X211073Y170750D01*
G01X211050Y169100D02*
X211550Y169600D01*
G01X211073Y170750D02*
X213250D01*
G01X211550Y169600D02*
X213727D01*
G01X213250Y170750D02*
X213750Y171250D01*
G01X213727Y169600D02*
X214900Y170773D01*
G01X213750Y171250D02*
Y178038D01*
G01X214900Y170773D02*
Y177561D01*
G01X213750Y178038D02*
X256778Y221066D01*
G01X214900Y177561D02*
X257255Y219916D01*
G01X207381Y173000D02*
X207881Y173500D01*
G01X206231Y173477D02*
X207404Y174650D01*
G01X207881Y173500D02*
X209926D01*
G01X207404Y174650D02*
X209449D01*
G01X209926Y173500D02*
X211100Y174674D01*
G01X209449Y174650D02*
X209950Y175151D01*
G01X211100Y174674D02*
Y179296D01*
G01X209950Y175151D02*
Y179773D01*
G01X211100Y179296D02*
X255945Y224141D01*
G01X209950Y179773D02*
X255468Y225291D01*
G01X210131Y161577D02*
X211304Y162750D01*
G01X211281Y161100D02*
X211781Y161600D01*
G01X211304Y162750D02*
X216231D01*
G01X211781Y161600D02*
X216708D01*
G01X216231Y162750D02*
X216731Y163250D01*
G01X216708Y161600D02*
X217881Y162773D01*
G01X216731Y163250D02*
Y165000D01*
G01X217881Y162773D02*
Y165477D01*
G01X216731Y165000D02*
X216231Y165500D01*
G01X217881Y165477D02*
X216708Y166650D01*
G01X216231Y165500D02*
X211073D01*
G01X216708Y166650D02*
X211550D01*
G01X211073Y165500D02*
X209900Y166673D01*
G01X211550Y166650D02*
X211050Y167150D01*
G01X209900Y166673D02*
Y169577D01*
G01X211050Y167150D02*
Y169100D01*
G01X209900Y169577D02*
X211073Y170750D01*
G01X211050Y169100D02*
X211550Y169600D01*
G01X211073Y170750D02*
X213250D01*
G01X211550Y169600D02*
X213727D01*
G01X213250Y170750D02*
X213750Y171250D01*
G01X213727Y169600D02*
X214900Y170773D01*
G01X213750Y171250D02*
Y178038D01*
G01X214900Y170773D02*
Y177561D01*
G01X213750Y178038D02*
X256778Y221066D01*
G01X214900Y177561D02*
X257255Y219916D01*
G01X259276Y370405D02*
X175979Y453702D01*
G01X259753Y371555D02*
X177129Y454179D01*
G01X259753Y371555D02*
X177129Y454179D01*
G01X259276Y370405D02*
X175979Y453702D01*
G01X259276Y370405D02*
X175979Y453702D01*
G01X259753Y371555D02*
X177129Y454179D01*
G01X259753Y371555D02*
X177129Y454179D01*
G01X259276Y370405D02*
X175979Y453702D01*
G01D02*
Y456664D01*
G01X177129Y454179D02*
Y456187D01*
G01X175979Y456664D02*
X177341Y458026D01*
G01X177129Y456187D02*
X177818Y456876D01*
G01X175979Y456664D02*
X177341Y458026D01*
G01D02*
X178620D01*
G01X177818Y456876D02*
X179097D01*
G01X178620Y458026D02*
X179322Y458728D01*
G01X179097Y456876D02*
X180472Y458251D01*
G01X179322Y458728D02*
Y469114D01*
G01X180472Y458251D02*
Y469591D01*
G01X177129Y454179D02*
Y456187D01*
G01X175979Y453702D02*
Y456664D01*
G01X177129Y456187D02*
X177818Y456876D01*
G01D02*
X179097D01*
G01X175979Y456664D02*
X177341Y458026D01*
G01X177818Y456876D02*
X179097D01*
G01X177341Y458026D02*
X178620D01*
G01X179097Y456876D02*
X180472Y458251D01*
G01X178620Y458026D02*
X179322Y458728D01*
G01X180472Y458251D02*
Y469591D01*
G01X179322Y458728D02*
Y469114D01*
G01X261412Y375431D02*
X184172Y452671D01*
G01X260935Y374281D02*
X183022Y452194D01*
G01X184172Y452671D02*
Y471480D01*
G01X183022Y452194D02*
Y471003D01*
G01X260935Y374281D02*
X183022Y452194D01*
G01X261412Y375431D02*
X184172Y452671D01*
G01X183022Y452194D02*
Y471003D01*
G01X184172Y452671D02*
Y471480D01*
G01X175979Y453702D02*
Y456664D01*
G01X177129Y454179D02*
Y456187D01*
G01X175979Y456664D02*
X177341Y458026D01*
G01X177129Y456187D02*
X177818Y456876D01*
G01X175979Y456664D02*
X177341Y458026D01*
G01D02*
X178620D01*
G01X177818Y456876D02*
X179097D01*
G01X178620Y458026D02*
X179322Y458728D01*
G01X179097Y456876D02*
X180472Y458251D01*
G01X179322Y458728D02*
Y469114D01*
G01X180472Y458251D02*
Y469591D01*
G01X177129Y454179D02*
Y456187D01*
G01X175979Y453702D02*
Y456664D01*
G01X177129Y456187D02*
X177818Y456876D01*
G01D02*
X179097D01*
G01X175979Y456664D02*
X177341Y458026D01*
G01X177818Y456876D02*
X179097D01*
G01X177341Y458026D02*
X178620D01*
G01X179097Y456876D02*
X180472Y458251D01*
G01X178620Y458026D02*
X179322Y458728D01*
G01X180472Y458251D02*
Y469591D01*
G01X179322Y458728D02*
Y469114D01*
G01X261412Y375431D02*
X184172Y452671D01*
G01X260935Y374281D02*
X183022Y452194D01*
G01X184172Y452671D02*
Y471480D01*
G01X183022Y452194D02*
Y471003D01*
G01X260935Y374281D02*
X183022Y452194D01*
G01X261412Y375431D02*
X184172Y452671D01*
G01X183022Y452194D02*
Y471003D01*
G01X184172Y452671D02*
Y471480D01*
G01X179322Y469114D02*
X178420Y470016D01*
G01X180472Y469591D02*
X178897Y471166D01*
G01X178420Y470016D02*
X177141D01*
G01X178897Y471166D02*
X177618D01*
G01X177141Y470016D02*
X175766Y471391D01*
G01X177618Y471166D02*
X176916Y471868D01*
G01X175766Y471391D02*
Y504413D01*
G01Y506161D02*
Y507451D01*
G01Y509175D02*
Y511498D01*
G01X176916Y471868D02*
Y511975D01*
G01X175766Y511498D02*
X174564Y512700D01*
G01X176916Y511975D02*
X173591Y515300D01*
G01X180472Y469591D02*
X178897Y471166D01*
G01X179322Y469114D02*
X178420Y470016D01*
G01X178897Y471166D02*
X177618D01*
G01X178420Y470016D02*
X177141D01*
G01X177618Y471166D02*
X176916Y471868D01*
G01X177141Y470016D02*
X175766Y471391D01*
G01X176916Y471868D02*
Y511975D01*
G01X175766Y471391D02*
Y504413D01*
G01X176916Y471868D02*
Y511975D01*
G01X175766Y506161D02*
Y507451D01*
G01X176916Y471868D02*
Y511975D01*
G01X175766Y509175D02*
Y511498D01*
G01X176916Y511975D02*
X173591Y515300D01*
G01X175766Y511498D02*
X174564Y512700D01*
G01X184172Y471480D02*
X181072Y474580D01*
G01X183022Y471003D02*
X179922Y474103D01*
G01X181072Y474580D02*
Y476320D01*
G01X179922Y474103D02*
Y476797D01*
G01X181072Y476320D02*
X184172Y479420D01*
G01X179922Y476797D02*
X183022Y479897D01*
G01X184172Y479420D02*
Y482460D01*
G01X183022Y479897D02*
Y481983D01*
G01X184172Y482460D02*
X182797Y483835D01*
G01X183022Y481983D02*
X182320Y482685D01*
G01X182797Y483835D02*
X181564D01*
G01X182320Y482685D02*
X181087D01*
G01X181564Y483835D02*
X180862Y484537D01*
G01X181087Y482685D02*
X179712Y484060D01*
G01X180862Y484537D02*
Y486623D01*
G01X179712Y484060D02*
Y487100D01*
G01X180862Y486623D02*
X181564Y487325D01*
G01X179712Y487100D02*
X181087Y488475D01*
G01X181564Y487325D02*
X182797D01*
G01X181087Y488475D02*
X182320D01*
G01X182797Y487325D02*
X184172Y488700D01*
G01X182320Y488475D02*
X183022Y489177D01*
G01X184172Y488700D02*
Y491740D01*
G01X183022Y489177D02*
Y491263D01*
G01X184172Y491740D02*
X182797Y493115D01*
G01X183022Y491263D02*
X182320Y491965D01*
G01X182797Y493115D02*
X181564D01*
G01X182320Y491965D02*
X181087D01*
G01X181564Y493115D02*
X180862Y493817D01*
G01X181087Y491965D02*
X179712Y493340D01*
G01X180862Y493817D02*
Y495903D01*
G01X179712Y493340D02*
Y496380D01*
G01X180862Y495903D02*
X181564Y496605D01*
G01X179712Y496380D02*
X181087Y497755D01*
G01X181564Y496605D02*
X182797D01*
G01X181087Y497755D02*
X182320D01*
G01X182797Y496605D02*
X184172Y497980D01*
G01X182320Y497755D02*
X183022Y498457D01*
G01X184172Y497980D02*
Y500328D01*
G01X183022Y498457D02*
Y499851D01*
G01X184172Y500328D02*
X180795Y503705D01*
G01X183022Y499851D02*
X179355Y503518D01*
G01X180795Y503705D02*
Y513411D01*
G01X179645Y505264D02*
Y506264D01*
G01X180795Y503705D02*
Y513411D01*
G01X179645Y508264D02*
Y509264D01*
G01X180795Y503705D02*
Y513411D01*
G01X179645Y511264D02*
Y511961D01*
G01X183022Y471003D02*
X179922Y474103D01*
G01X184172Y471480D02*
X181072Y474580D01*
G01X179922Y474103D02*
Y476797D01*
G01X181072Y474580D02*
Y476320D01*
G01X179922Y476797D02*
X183022Y479897D01*
G01X181072Y476320D02*
X184172Y479420D01*
G01X183022Y479897D02*
Y481983D01*
G01X184172Y479420D02*
Y482460D01*
G01X183022Y481983D02*
X182320Y482685D01*
G01X184172Y482460D02*
X182797Y483835D01*
G01X182320Y482685D02*
X181087D01*
G01X182797Y483835D02*
X181564D01*
G01X181087Y482685D02*
X179712Y484060D01*
G01X181564Y483835D02*
X180862Y484537D01*
G01X179712Y484060D02*
Y487100D01*
G01X180862Y484537D02*
Y486623D01*
G01X179712Y487100D02*
X181087Y488475D01*
G01X180862Y486623D02*
X181564Y487325D01*
G01X181087Y488475D02*
X182320D01*
G01X181564Y487325D02*
X182797D01*
G01X182320Y488475D02*
X183022Y489177D01*
G01X182797Y487325D02*
X184172Y488700D01*
G01X183022Y489177D02*
Y491263D01*
G01X184172Y488700D02*
Y491740D01*
G01X183022Y491263D02*
X182320Y491965D01*
G01X184172Y491740D02*
X182797Y493115D01*
G01X182320Y491965D02*
X181087D01*
G01X182797Y493115D02*
X181564D01*
G01X181087Y491965D02*
X179712Y493340D01*
G01X181564Y493115D02*
X180862Y493817D01*
G01X179712Y493340D02*
Y496380D01*
G01X180862Y493817D02*
Y495903D01*
G01X179712Y496380D02*
X181087Y497755D01*
G01X180862Y495903D02*
X181564Y496605D01*
G01X181087Y497755D02*
X182320D01*
G01X181564Y496605D02*
X182797D01*
G01X182320Y497755D02*
X183022Y498457D01*
G01X182797Y496605D02*
X184172Y497980D01*
G01X183022Y498457D02*
Y499851D01*
G01X184172Y497980D02*
Y500328D01*
G01X183022Y499851D02*
X179355Y503518D01*
G01X184172Y500328D02*
X180795Y503705D01*
G01X179645Y505264D02*
Y506264D01*
G01Y508264D02*
Y509264D01*
G01Y511264D02*
Y511961D01*
G01X180795Y503705D02*
Y513411D01*
G01X179322Y469114D02*
X178420Y470016D01*
G01X180472Y469591D02*
X178897Y471166D01*
G01X178420Y470016D02*
X177141D01*
G01X178897Y471166D02*
X177618D01*
G01X177141Y470016D02*
X175766Y471391D01*
G01X177618Y471166D02*
X176916Y471868D01*
G01X175766Y471391D02*
Y504413D01*
G01Y506161D02*
Y507451D01*
G01Y509175D02*
Y511498D01*
G01X176916Y471868D02*
Y511975D01*
G01X175766Y511498D02*
X174564Y512700D01*
G01X176916Y511975D02*
X173591Y515300D01*
G01X180472Y469591D02*
X178897Y471166D01*
G01X179322Y469114D02*
X178420Y470016D01*
G01X178897Y471166D02*
X177618D01*
G01X178420Y470016D02*
X177141D01*
G01X177618Y471166D02*
X176916Y471868D01*
G01X177141Y470016D02*
X175766Y471391D01*
G01X176916Y471868D02*
Y511975D01*
G01X175766Y471391D02*
Y504413D01*
G01X176916Y471868D02*
Y511975D01*
G01X175766Y506161D02*
Y507451D01*
G01X176916Y471868D02*
Y511975D01*
G01X175766Y509175D02*
Y511498D01*
G01X176916Y511975D02*
X173591Y515300D01*
G01X175766Y511498D02*
X174564Y512700D01*
G01X184172Y471480D02*
X181072Y474580D01*
G01X183022Y471003D02*
X179922Y474103D01*
G01X181072Y474580D02*
Y476320D01*
G01X179922Y474103D02*
Y476797D01*
G01X181072Y476320D02*
X184172Y479420D01*
G01X179922Y476797D02*
X183022Y479897D01*
G01X184172Y479420D02*
Y482460D01*
G01X183022Y479897D02*
Y481983D01*
G01X184172Y482460D02*
X182797Y483835D01*
G01X183022Y481983D02*
X182320Y482685D01*
G01X182797Y483835D02*
X181564D01*
G01X182320Y482685D02*
X181087D01*
G01X181564Y483835D02*
X180862Y484537D01*
G01X181087Y482685D02*
X179712Y484060D01*
G01X180862Y484537D02*
Y486623D01*
G01X179712Y484060D02*
Y487100D01*
G01X180862Y486623D02*
X181564Y487325D01*
G01X179712Y487100D02*
X181087Y488475D01*
G01X181564Y487325D02*
X182797D01*
G01X181087Y488475D02*
X182320D01*
G01X182797Y487325D02*
X184172Y488700D01*
G01X182320Y488475D02*
X183022Y489177D01*
G01X184172Y488700D02*
Y491740D01*
G01X183022Y489177D02*
Y491263D01*
G01X184172Y491740D02*
X182797Y493115D01*
G01X183022Y491263D02*
X182320Y491965D01*
G01X182797Y493115D02*
X181564D01*
G01X182320Y491965D02*
X181087D01*
G01X181564Y493115D02*
X180862Y493817D01*
G01X181087Y491965D02*
X179712Y493340D01*
G01X180862Y493817D02*
Y495903D01*
G01X179712Y493340D02*
Y496380D01*
G01X180862Y495903D02*
X181564Y496605D01*
G01X179712Y496380D02*
X181087Y497755D01*
G01X181564Y496605D02*
X182797D01*
G01X181087Y497755D02*
X182320D01*
G01X182797Y496605D02*
X184172Y497980D01*
G01X182320Y497755D02*
X183022Y498457D01*
G01X184172Y497980D02*
Y500328D01*
G01X183022Y498457D02*
Y499851D01*
G01X184172Y500328D02*
X180795Y503705D01*
G01X183022Y499851D02*
X179355Y503518D01*
G01X180795Y503705D02*
Y513411D01*
G01X179645Y505264D02*
Y506264D01*
G01X180795Y503705D02*
Y513411D01*
G01X179645Y508264D02*
Y509264D01*
G01X180795Y503705D02*
Y513411D01*
G01X179645Y511264D02*
Y511961D01*
G01X183022Y471003D02*
X179922Y474103D01*
G01X184172Y471480D02*
X181072Y474580D01*
G01X179922Y474103D02*
Y476797D01*
G01X181072Y474580D02*
Y476320D01*
G01X179922Y476797D02*
X183022Y479897D01*
G01X181072Y476320D02*
X184172Y479420D01*
G01X183022Y479897D02*
Y481983D01*
G01X184172Y479420D02*
Y482460D01*
G01X183022Y481983D02*
X182320Y482685D01*
G01X184172Y482460D02*
X182797Y483835D01*
G01X182320Y482685D02*
X181087D01*
G01X182797Y483835D02*
X181564D01*
G01X181087Y482685D02*
X179712Y484060D01*
G01X181564Y483835D02*
X180862Y484537D01*
G01X179712Y484060D02*
Y487100D01*
G01X180862Y484537D02*
Y486623D01*
G01X179712Y487100D02*
X181087Y488475D01*
G01X180862Y486623D02*
X181564Y487325D01*
G01X181087Y488475D02*
X182320D01*
G01X181564Y487325D02*
X182797D01*
G01X182320Y488475D02*
X183022Y489177D01*
G01X182797Y487325D02*
X184172Y488700D01*
G01X183022Y489177D02*
Y491263D01*
G01X184172Y488700D02*
Y491740D01*
G01X183022Y491263D02*
X182320Y491965D01*
G01X184172Y491740D02*
X182797Y493115D01*
G01X182320Y491965D02*
X181087D01*
G01X182797Y493115D02*
X181564D01*
G01X181087Y491965D02*
X179712Y493340D01*
G01X181564Y493115D02*
X180862Y493817D01*
G01X179712Y493340D02*
Y496380D01*
G01X180862Y493817D02*
Y495903D01*
G01X179712Y496380D02*
X181087Y497755D01*
G01X180862Y495903D02*
X181564Y496605D01*
G01X181087Y497755D02*
X182320D01*
G01X181564Y496605D02*
X182797D01*
G01X182320Y497755D02*
X183022Y498457D01*
G01X182797Y496605D02*
X184172Y497980D01*
G01X183022Y498457D02*
Y499851D01*
G01X184172Y497980D02*
Y500328D01*
G01X183022Y499851D02*
X179355Y503518D01*
G01X184172Y500328D02*
X180795Y503705D01*
G01X179645Y505264D02*
Y506264D01*
G01Y508264D02*
Y509264D01*
G01Y511264D02*
Y511961D01*
G01X180795Y503705D02*
Y513411D01*
G01X248692Y150185D02*
Y169092D01*
G01X249842Y168615D02*
Y149708D01*
G01X245592Y147085D02*
X248692Y150185D01*
G01X249842Y149708D02*
X246742Y146608D01*
G01X245592Y144708D02*
Y147085D01*
G01X246742Y146608D02*
Y145185D01*
G01X246915Y143385D02*
X245592Y144708D01*
G01X246742Y145185D02*
X247392Y144535D01*
G01X248020Y143385D02*
X246915D01*
G01X247392Y144535D02*
X248497D01*
G01X248722Y142683D02*
X248020Y143385D01*
G01X248497Y144535D02*
X249872Y143160D01*
G01X248722Y140597D02*
Y142683D01*
G01X249872Y143160D02*
Y141500D01*
G01X248722Y140597D02*
Y142683D01*
G01X249872Y141500D02*
Y140120D01*
G01X248020Y139895D02*
X248722Y140597D01*
G01X249872Y140120D02*
X248497Y138745D01*
G01X246667Y139895D02*
X248020D01*
G01X248497Y138745D02*
X247144D01*
G01X245292Y138520D02*
X246667Y139895D01*
G01X247144Y138745D02*
X246442Y138043D01*
G01X245292Y135480D02*
Y138520D01*
G01X246442Y138043D02*
Y135957D01*
G01X246667Y134105D02*
X245292Y135480D01*
G01X246442Y135957D02*
X247144Y135255D01*
G01X248142Y134105D02*
X246667D01*
G01X247144Y135255D02*
X248619D01*
G01X248792Y133455D02*
X248142Y134105D01*
G01X248619Y135255D02*
X249942Y133932D01*
G01X248792Y131265D02*
Y133455D01*
G01X249942Y133932D02*
Y130788D01*
G01X248142Y130615D02*
X248792Y131265D01*
G01X249942Y130788D02*
X248619Y129465D01*
G01X246667Y130615D02*
X248142D01*
G01X248619Y129465D02*
X247144D01*
G01X245292Y129240D02*
X246667Y130615D01*
G01X247144Y129465D02*
X246442Y128763D01*
G01X245292Y125500D02*
Y129240D01*
G01X246442Y128763D02*
Y127550D01*
G01X245292Y125500D02*
Y129240D01*
G01Y109812D02*
Y125500D01*
G01X246442Y125510D02*
Y124550D01*
G01X245292Y109812D02*
Y125500D01*
G01X246442Y122510D02*
Y121550D01*
G01X245292Y109812D02*
Y125500D01*
G01X246442Y119510D02*
Y118550D01*
G01X245292Y109812D02*
Y125500D01*
G01X246442Y116510D02*
Y115550D01*
G01X289842Y162232D02*
Y143889D01*
G01Y162232D02*
Y143889D01*
G01Y162232D02*
Y143889D01*
G01X290992Y155400D02*
Y154400D01*
G01X289842Y162232D02*
Y143889D01*
G01X290992Y152400D02*
Y151000D01*
G01X289842Y162232D02*
Y143889D01*
G01X290992Y149000D02*
Y147900D01*
G01X289842Y162232D02*
Y143889D01*
G01X290992Y145900D02*
Y144366D01*
G01X289842Y143889D02*
X291581Y142150D01*
G01X290992Y144366D02*
X292058Y143300D01*
G01X291581Y142150D02*
X293826D01*
G01X292058Y143300D02*
X294303D01*
G01X293892Y137790D02*
X291965D01*
G01X294369Y136640D02*
X292442D01*
G01X291965Y137790D02*
X290792Y136617D01*
G01X292442Y136640D02*
X291942Y136140D01*
G01X290792Y136617D02*
Y134013D01*
G01X291942Y136140D02*
Y134490D01*
G01X290792Y134013D02*
X291965Y132840D01*
G01X291942Y134490D02*
X292442Y133990D01*
G01X291965Y132840D02*
X293892D01*
G01X292442Y133990D02*
X294369D01*
G01X294542Y129799D02*
X282471Y117728D01*
G01X294542Y129799D02*
X282471Y117728D01*
G01X292816Y126446D02*
X292109Y125739D01*
G01X294542Y129799D02*
X282471Y117728D01*
G01X290694Y124324D02*
X289987Y123617D01*
G01X294542Y129799D02*
X282471Y117728D01*
G01X288572Y122202D02*
X287865Y121495D01*
G01X294542Y129799D02*
X282471Y117728D01*
G01X286450Y120080D02*
X285743Y119373D01*
G01X294542Y129799D02*
X282471Y117728D01*
G01X284328Y117958D02*
X283621Y117251D01*
G01X282471Y117728D02*
Y115324D01*
G01X283621Y117251D02*
Y115801D01*
G01X253762Y128999D02*
Y167293D01*
G01X252612Y167770D02*
Y135500D01*
G01X253762Y128999D02*
Y167293D01*
G01X252612Y135500D02*
Y129476D01*
G01X251642Y126879D02*
X253762Y128999D01*
G01X252612Y129476D02*
X250492Y127356D01*
G01X251642Y123500D02*
Y126879D01*
G01Y115350D02*
Y116310D01*
G01Y118350D02*
Y119310D01*
G01Y121350D02*
Y123500D01*
G01X250492Y127356D02*
Y114480D01*
G01X295372Y123748D02*
X293087Y121463D01*
G01X293564Y120313D02*
X292832D01*
G01X293087Y121463D02*
X292355D01*
G01X292832Y120313D02*
X289892Y117373D01*
G01X292355Y121463D02*
X287355Y116463D01*
G01X246442Y128763D02*
Y127550D01*
G01Y125510D02*
Y124550D01*
G01X245292Y125500D02*
Y129240D01*
G01X247144Y129465D02*
X246442Y128763D01*
G01X245292Y129240D02*
X246667Y130615D01*
G01X248619Y129465D02*
X247144D01*
G01X246667Y130615D02*
X248142D01*
G01X249942Y130788D02*
X248619Y129465D01*
G01X248142Y130615D02*
X248792Y131265D01*
G01X249942Y133932D02*
Y130788D01*
G01X248792Y131265D02*
Y133455D01*
G01X248619Y135255D02*
X249942Y133932D01*
G01X248792Y133455D02*
X248142Y134105D01*
G01X247144Y135255D02*
X248619D01*
G01X248142Y134105D02*
X246667D01*
G01X246442Y135957D02*
X247144Y135255D01*
G01X246667Y134105D02*
X245292Y135480D01*
G01X246442Y138043D02*
Y135957D01*
G01X245292Y135480D02*
Y138520D01*
G01X247144Y138745D02*
X246442Y138043D01*
G01X245292Y138520D02*
X246667Y139895D01*
G01X248497Y138745D02*
X247144D01*
G01X246667Y139895D02*
X248020D01*
G01X249872Y140120D02*
X248497Y138745D01*
G01X248020Y139895D02*
X248722Y140597D01*
G01X249872Y143160D02*
Y141500D01*
G01D02*
Y140120D01*
G01X248722Y140597D02*
Y142683D01*
G01X248497Y144535D02*
X249872Y143160D01*
G01X248722Y142683D02*
X248020Y143385D01*
G01X247392Y144535D02*
X248497D01*
G01X248020Y143385D02*
X246915D01*
G01X246742Y145185D02*
X247392Y144535D01*
G01X246915Y143385D02*
X245592Y144708D01*
G01X246742Y146608D02*
Y145185D01*
G01X245592Y144708D02*
Y147085D01*
G01X249842Y149708D02*
X246742Y146608D01*
G01X245592Y147085D02*
X248692Y150185D01*
G01X249842Y168615D02*
Y149708D01*
G01X248692Y150185D02*
Y169092D01*
G01X246442Y125510D02*
Y124550D01*
G01Y122510D02*
Y121550D01*
G01Y119510D02*
Y118550D01*
G01Y116510D02*
Y115550D01*
G01X245292Y109812D02*
Y125500D01*
G01X290992Y155400D02*
Y154400D01*
G01Y152400D02*
Y151000D01*
G01Y149000D02*
Y147900D01*
G01Y145900D02*
Y144366D01*
G01X289842Y162232D02*
Y143889D01*
G01X290992Y144366D02*
X292058Y143300D01*
G01X289842Y143889D02*
X291581Y142150D01*
G01X292058Y143300D02*
X294303D01*
G01X291581Y142150D02*
X293826D01*
G01X294369Y136640D02*
X292442D01*
G01X293892Y137790D02*
X291965D01*
G01X292442Y136640D02*
X291942Y136140D01*
G01X291965Y137790D02*
X290792Y136617D01*
G01X291942Y136140D02*
Y134490D01*
G01X290792Y136617D02*
Y134013D01*
G01X291942Y134490D02*
X292442Y133990D01*
G01X290792Y134013D02*
X291965Y132840D01*
G01X292442Y133990D02*
X294369D01*
G01X291965Y132840D02*
X293892D01*
G01X292816Y126446D02*
X292109Y125739D01*
G01X290694Y124324D02*
X289987Y123617D01*
G01X288572Y122202D02*
X287865Y121495D01*
G01X286450Y120080D02*
X285743Y119373D01*
G01X284328Y117958D02*
X283621Y117251D01*
G01X294542Y129799D02*
X282471Y117728D01*
G01X283621Y117251D02*
Y115801D01*
G01X282471Y117728D02*
Y115324D01*
G01X250492Y127356D02*
Y114480D01*
G01X251642Y123500D02*
Y126879D01*
G01X252612Y129476D02*
X250492Y127356D01*
G01X251642Y126879D02*
X253762Y128999D01*
G01X252612Y167770D02*
Y135500D01*
G01D02*
Y129476D01*
G01X253762Y128999D02*
Y167293D01*
G01X250492Y127356D02*
Y114480D01*
G01X251642Y115350D02*
Y116310D01*
G01X250492Y127356D02*
Y114480D01*
G01X251642Y118350D02*
Y119310D01*
G01X250492Y127356D02*
Y114480D01*
G01X251642Y121350D02*
Y123500D01*
G01X295372Y123748D02*
X293087Y121463D01*
G01D02*
X292355D01*
G01X293564Y120313D02*
X292832D01*
G01X292355Y121463D02*
X287355Y116463D01*
G01X292832Y120313D02*
X289892Y117373D01*
G01X248692Y150185D02*
Y169092D01*
G01X249842Y168615D02*
Y149708D01*
G01X245592Y147085D02*
X248692Y150185D01*
G01X249842Y149708D02*
X246742Y146608D01*
G01X245592Y144708D02*
Y147085D01*
G01X246742Y146608D02*
Y145185D01*
G01X246915Y143385D02*
X245592Y144708D01*
G01X246742Y145185D02*
X247392Y144535D01*
G01X248020Y143385D02*
X246915D01*
G01X247392Y144535D02*
X248497D01*
G01X248722Y142683D02*
X248020Y143385D01*
G01X248497Y144535D02*
X249872Y143160D01*
G01X248722Y140597D02*
Y142683D01*
G01X249872Y143160D02*
Y141500D01*
G01X248722Y140597D02*
Y142683D01*
G01X249872Y141500D02*
Y140120D01*
G01X248020Y139895D02*
X248722Y140597D01*
G01X249872Y140120D02*
X248497Y138745D01*
G01X246667Y139895D02*
X248020D01*
G01X248497Y138745D02*
X247144D01*
G01X245292Y138520D02*
X246667Y139895D01*
G01X247144Y138745D02*
X246442Y138043D01*
G01X245292Y135480D02*
Y138520D01*
G01X246442Y138043D02*
Y135957D01*
G01X246667Y134105D02*
X245292Y135480D01*
G01X246442Y135957D02*
X247144Y135255D01*
G01X248142Y134105D02*
X246667D01*
G01X247144Y135255D02*
X248619D01*
G01X248792Y133455D02*
X248142Y134105D01*
G01X248619Y135255D02*
X249942Y133932D01*
G01X248792Y131265D02*
Y133455D01*
G01X249942Y133932D02*
Y130788D01*
G01X248142Y130615D02*
X248792Y131265D01*
G01X249942Y130788D02*
X248619Y129465D01*
G01X246667Y130615D02*
X248142D01*
G01X248619Y129465D02*
X247144D01*
G01X245292Y129240D02*
X246667Y130615D01*
G01X247144Y129465D02*
X246442Y128763D01*
G01X245292Y125500D02*
Y129240D01*
G01X246442Y128763D02*
Y127550D01*
G01X245292Y125500D02*
Y129240D01*
G01Y109812D02*
Y125500D01*
G01X246442Y125510D02*
Y124550D01*
G01X245292Y109812D02*
Y125500D01*
G01X246442Y122510D02*
Y121550D01*
G01X245292Y109812D02*
Y125500D01*
G01X246442Y119510D02*
Y118550D01*
G01X245292Y109812D02*
Y125500D01*
G01X246442Y116510D02*
Y115550D01*
G01X248692Y150185D02*
Y169092D01*
G01X249842Y168615D02*
Y149708D01*
G01X245592Y147085D02*
X248692Y150185D01*
G01X249842Y149708D02*
X246742Y146608D01*
G01X245592Y144708D02*
Y147085D01*
G01X246742Y146608D02*
Y145185D01*
G01X246915Y143385D02*
X245592Y144708D01*
G01X246742Y145185D02*
X247392Y144535D01*
G01X248020Y143385D02*
X246915D01*
G01X247392Y144535D02*
X248497D01*
G01X248722Y142683D02*
X248020Y143385D01*
G01X248497Y144535D02*
X249872Y143160D01*
G01X248722Y140597D02*
Y142683D01*
G01X249872Y143160D02*
Y141500D01*
G01X248722Y140597D02*
Y142683D01*
G01X249872Y141500D02*
Y140120D01*
G01X248020Y139895D02*
X248722Y140597D01*
G01X249872Y140120D02*
X248497Y138745D01*
G01X246667Y139895D02*
X248020D01*
G01X248497Y138745D02*
X247144D01*
G01X245292Y138520D02*
X246667Y139895D01*
G01X247144Y138745D02*
X246442Y138043D01*
G01X245292Y135480D02*
Y138520D01*
G01X246442Y138043D02*
Y135957D01*
G01X246667Y134105D02*
X245292Y135480D01*
G01X246442Y135957D02*
X247144Y135255D01*
G01X248142Y134105D02*
X246667D01*
G01X247144Y135255D02*
X248619D01*
G01X248792Y133455D02*
X248142Y134105D01*
G01X248619Y135255D02*
X249942Y133932D01*
G01X248792Y131265D02*
Y133455D01*
G01X249942Y133932D02*
Y130788D01*
G01X248142Y130615D02*
X248792Y131265D01*
G01X249942Y130788D02*
X248619Y129465D01*
G01X246667Y130615D02*
X248142D01*
G01X248619Y129465D02*
X247144D01*
G01X245292Y129240D02*
X246667Y130615D01*
G01X247144Y129465D02*
X246442Y128763D01*
G01X245292Y125500D02*
Y129240D01*
G01X246442Y128763D02*
Y127550D01*
G01X245292Y125500D02*
Y129240D01*
G01Y109812D02*
Y125500D01*
G01X246442Y125510D02*
Y124550D01*
G01X245292Y109812D02*
Y125500D01*
G01X246442Y122510D02*
Y121550D01*
G01X245292Y109812D02*
Y125500D01*
G01X246442Y119510D02*
Y118550D01*
G01X245292Y109812D02*
Y125500D01*
G01X246442Y116510D02*
Y115550D01*
G01X289842Y162232D02*
Y143889D01*
G01Y162232D02*
Y143889D01*
G01Y162232D02*
Y143889D01*
G01X290992Y155400D02*
Y154400D01*
G01X289842Y162232D02*
Y143889D01*
G01X290992Y152400D02*
Y151000D01*
G01X289842Y162232D02*
Y143889D01*
G01X290992Y149000D02*
Y147900D01*
G01X289842Y162232D02*
Y143889D01*
G01X290992Y145900D02*
Y144366D01*
G01X289842Y143889D02*
X291581Y142150D01*
G01X290992Y144366D02*
X292058Y143300D01*
G01X291581Y142150D02*
X293826D01*
G01X292058Y143300D02*
X294303D01*
G01X293892Y137790D02*
X291965D01*
G01X294369Y136640D02*
X292442D01*
G01X291965Y137790D02*
X290792Y136617D01*
G01X292442Y136640D02*
X291942Y136140D01*
G01X290792Y136617D02*
Y134013D01*
G01X291942Y136140D02*
Y134490D01*
G01X290792Y134013D02*
X291965Y132840D01*
G01X291942Y134490D02*
X292442Y133990D01*
G01X291965Y132840D02*
X293892D01*
G01X292442Y133990D02*
X294369D01*
G01X294542Y129799D02*
X282471Y117728D01*
G01X294542Y129799D02*
X282471Y117728D01*
G01X292816Y126446D02*
X292109Y125739D01*
G01X294542Y129799D02*
X282471Y117728D01*
G01X290694Y124324D02*
X289987Y123617D01*
G01X294542Y129799D02*
X282471Y117728D01*
G01X288572Y122202D02*
X287865Y121495D01*
G01X294542Y129799D02*
X282471Y117728D01*
G01X286450Y120080D02*
X285743Y119373D01*
G01X294542Y129799D02*
X282471Y117728D01*
G01X284328Y117958D02*
X283621Y117251D01*
G01X282471Y117728D02*
Y115324D01*
G01X283621Y117251D02*
Y115801D01*
G01X253762Y128999D02*
Y167293D01*
G01X252612Y167770D02*
Y135500D01*
G01X253762Y128999D02*
Y167293D01*
G01X252612Y135500D02*
Y129476D01*
G01X251642Y126879D02*
X253762Y128999D01*
G01X252612Y129476D02*
X250492Y127356D01*
G01X251642Y123500D02*
Y126879D01*
G01Y115350D02*
Y116310D01*
G01Y118350D02*
Y119310D01*
G01Y121350D02*
Y123500D01*
G01X250492Y127356D02*
Y114480D01*
G01X253762Y128999D02*
Y167293D01*
G01X252612Y167770D02*
Y135500D01*
G01X253762Y128999D02*
Y167293D01*
G01X252612Y135500D02*
Y129476D01*
G01X251642Y126879D02*
X253762Y128999D01*
G01X252612Y129476D02*
X250492Y127356D01*
G01X251642Y123500D02*
Y126879D01*
G01Y115350D02*
Y116310D01*
G01Y118350D02*
Y119310D01*
G01Y121350D02*
Y123500D01*
G01X250492Y127356D02*
Y114480D01*
G01X295372Y123748D02*
X293087Y121463D01*
G01X293564Y120313D02*
X292832D01*
G01X293087Y121463D02*
X292355D01*
G01X292832Y120313D02*
X289892Y117373D01*
G01X292355Y121463D02*
X287355Y116463D01*
G01X246442Y128763D02*
Y127550D01*
G01Y125510D02*
Y124550D01*
G01X245292Y125500D02*
Y129240D01*
G01X247144Y129465D02*
X246442Y128763D01*
G01X245292Y129240D02*
X246667Y130615D01*
G01X248619Y129465D02*
X247144D01*
G01X246667Y130615D02*
X248142D01*
G01X249942Y130788D02*
X248619Y129465D01*
G01X248142Y130615D02*
X248792Y131265D01*
G01X249942Y133932D02*
Y130788D01*
G01X248792Y131265D02*
Y133455D01*
G01X248619Y135255D02*
X249942Y133932D01*
G01X248792Y133455D02*
X248142Y134105D01*
G01X247144Y135255D02*
X248619D01*
G01X248142Y134105D02*
X246667D01*
G01X246442Y135957D02*
X247144Y135255D01*
G01X246667Y134105D02*
X245292Y135480D01*
G01X246442Y138043D02*
Y135957D01*
G01X245292Y135480D02*
Y138520D01*
G01X247144Y138745D02*
X246442Y138043D01*
G01X245292Y138520D02*
X246667Y139895D01*
G01X248497Y138745D02*
X247144D01*
G01X246667Y139895D02*
X248020D01*
G01X249872Y140120D02*
X248497Y138745D01*
G01X248020Y139895D02*
X248722Y140597D01*
G01X249872Y143160D02*
Y141500D01*
G01D02*
Y140120D01*
G01X248722Y140597D02*
Y142683D01*
G01X248497Y144535D02*
X249872Y143160D01*
G01X248722Y142683D02*
X248020Y143385D01*
G01X247392Y144535D02*
X248497D01*
G01X248020Y143385D02*
X246915D01*
G01X246742Y145185D02*
X247392Y144535D01*
G01X246915Y143385D02*
X245592Y144708D01*
G01X246742Y146608D02*
Y145185D01*
G01X245592Y144708D02*
Y147085D01*
G01X249842Y149708D02*
X246742Y146608D01*
G01X245592Y147085D02*
X248692Y150185D01*
G01X249842Y168615D02*
Y149708D01*
G01X248692Y150185D02*
Y169092D01*
G01X246442Y125510D02*
Y124550D01*
G01Y122510D02*
Y121550D01*
G01Y119510D02*
Y118550D01*
G01Y116510D02*
Y115550D01*
G01X245292Y109812D02*
Y125500D01*
G01X246442Y128763D02*
Y127550D01*
G01Y125510D02*
Y124550D01*
G01X245292Y125500D02*
Y129240D01*
G01X247144Y129465D02*
X246442Y128763D01*
G01X245292Y129240D02*
X246667Y130615D01*
G01X248619Y129465D02*
X247144D01*
G01X246667Y130615D02*
X248142D01*
G01X249942Y130788D02*
X248619Y129465D01*
G01X248142Y130615D02*
X248792Y131265D01*
G01X249942Y133932D02*
Y130788D01*
G01X248792Y131265D02*
Y133455D01*
G01X248619Y135255D02*
X249942Y133932D01*
G01X248792Y133455D02*
X248142Y134105D01*
G01X247144Y135255D02*
X248619D01*
G01X248142Y134105D02*
X246667D01*
G01X246442Y135957D02*
X247144Y135255D01*
G01X246667Y134105D02*
X245292Y135480D01*
G01X246442Y138043D02*
Y135957D01*
G01X245292Y135480D02*
Y138520D01*
G01X247144Y138745D02*
X246442Y138043D01*
G01X245292Y138520D02*
X246667Y139895D01*
G01X248497Y138745D02*
X247144D01*
G01X246667Y139895D02*
X248020D01*
G01X249872Y140120D02*
X248497Y138745D01*
G01X248020Y139895D02*
X248722Y140597D01*
G01X249872Y143160D02*
Y141500D01*
G01D02*
Y140120D01*
G01X248722Y140597D02*
Y142683D01*
G01X248497Y144535D02*
X249872Y143160D01*
G01X248722Y142683D02*
X248020Y143385D01*
G01X247392Y144535D02*
X248497D01*
G01X248020Y143385D02*
X246915D01*
G01X246742Y145185D02*
X247392Y144535D01*
G01X246915Y143385D02*
X245592Y144708D01*
G01X246742Y146608D02*
Y145185D01*
G01X245592Y144708D02*
Y147085D01*
G01X249842Y149708D02*
X246742Y146608D01*
G01X245592Y147085D02*
X248692Y150185D01*
G01X249842Y168615D02*
Y149708D01*
G01X248692Y150185D02*
Y169092D01*
G01X246442Y125510D02*
Y124550D01*
G01Y122510D02*
Y121550D01*
G01Y119510D02*
Y118550D01*
G01Y116510D02*
Y115550D01*
G01X245292Y109812D02*
Y125500D01*
G01X290992Y155400D02*
Y154400D01*
G01Y152400D02*
Y151000D01*
G01Y149000D02*
Y147900D01*
G01Y145900D02*
Y144366D01*
G01X289842Y162232D02*
Y143889D01*
G01X290992Y144366D02*
X292058Y143300D01*
G01X289842Y143889D02*
X291581Y142150D01*
G01X292058Y143300D02*
X294303D01*
G01X291581Y142150D02*
X293826D01*
G01X294369Y136640D02*
X292442D01*
G01X293892Y137790D02*
X291965D01*
G01X292442Y136640D02*
X291942Y136140D01*
G01X291965Y137790D02*
X290792Y136617D01*
G01X291942Y136140D02*
Y134490D01*
G01X290792Y136617D02*
Y134013D01*
G01X291942Y134490D02*
X292442Y133990D01*
G01X290792Y134013D02*
X291965Y132840D01*
G01X292442Y133990D02*
X294369D01*
G01X291965Y132840D02*
X293892D01*
G01X292816Y126446D02*
X292109Y125739D01*
G01X290694Y124324D02*
X289987Y123617D01*
G01X288572Y122202D02*
X287865Y121495D01*
G01X286450Y120080D02*
X285743Y119373D01*
G01X284328Y117958D02*
X283621Y117251D01*
G01X294542Y129799D02*
X282471Y117728D01*
G01X283621Y117251D02*
Y115801D01*
G01X282471Y117728D02*
Y115324D01*
G01X250492Y127356D02*
Y114480D01*
G01X251642Y123500D02*
Y126879D01*
G01X252612Y129476D02*
X250492Y127356D01*
G01X251642Y126879D02*
X253762Y128999D01*
G01X252612Y167770D02*
Y135500D01*
G01D02*
Y129476D01*
G01X253762Y128999D02*
Y167293D01*
G01X250492Y127356D02*
Y114480D01*
G01X251642Y115350D02*
Y116310D01*
G01X250492Y127356D02*
Y114480D01*
G01X251642Y118350D02*
Y119310D01*
G01X250492Y127356D02*
Y114480D01*
G01X251642Y121350D02*
Y123500D01*
G01X250492Y127356D02*
Y114480D01*
G01X251642Y123500D02*
Y126879D01*
G01X252612Y129476D02*
X250492Y127356D01*
G01X251642Y126879D02*
X253762Y128999D01*
G01X252612Y167770D02*
Y135500D01*
G01D02*
Y129476D01*
G01X253762Y128999D02*
Y167293D01*
G01X250492Y127356D02*
Y114480D01*
G01X251642Y115350D02*
Y116310D01*
G01X250492Y127356D02*
Y114480D01*
G01X251642Y118350D02*
Y119310D01*
G01X250492Y127356D02*
Y114480D01*
G01X251642Y121350D02*
Y123500D01*
G01X295372Y123748D02*
X293087Y121463D01*
G01D02*
X292355D01*
G01X293564Y120313D02*
X292832D01*
G01X292355Y121463D02*
X287355Y116463D01*
G01X292832Y120313D02*
X289892Y117373D01*
G01X248692Y169092D02*
X262230Y182630D01*
G01X263043Y181816D02*
X249842Y168615D01*
G01X298036Y170426D02*
X289842Y162232D01*
G01X298036Y170426D02*
X289842Y162232D01*
G01X293821Y164584D02*
X293114Y163877D01*
G01X298036Y170426D02*
X289842Y162232D01*
G01X291699Y162462D02*
X290992Y161755D01*
G01D02*
Y160755D01*
G01Y158755D02*
Y157400D01*
G01X253762Y167293D02*
X265669Y179200D01*
G01X264856Y180014D02*
X252612Y167770D01*
G01X263043Y181816D02*
X249842Y168615D01*
G01X248692Y169092D02*
X262230Y182630D01*
G01X293821Y164584D02*
X293114Y163877D01*
G01X291699Y162462D02*
X290992Y161755D01*
G01X298036Y170426D02*
X289842Y162232D01*
G01X290992Y161755D02*
Y160755D01*
G01Y158755D02*
Y157400D01*
G01X264856Y180014D02*
X252612Y167770D01*
G01X253762Y167293D02*
X265669Y179200D01*
G01X248692Y169092D02*
X262230Y182630D01*
G01X263043Y181816D02*
X249842Y168615D01*
G01X248692Y169092D02*
X262230Y182630D01*
G01X263043Y181816D02*
X249842Y168615D01*
G01X298036Y170426D02*
X289842Y162232D01*
G01X298036Y170426D02*
X289842Y162232D01*
G01X293821Y164584D02*
X293114Y163877D01*
G01X298036Y170426D02*
X289842Y162232D01*
G01X291699Y162462D02*
X290992Y161755D01*
G01D02*
Y160755D01*
G01Y158755D02*
Y157400D01*
G01X253762Y167293D02*
X265669Y179200D01*
G01X264856Y180014D02*
X252612Y167770D01*
G01X253762Y167293D02*
X265669Y179200D01*
G01X264856Y180014D02*
X252612Y167770D01*
G01X263043Y181816D02*
X249842Y168615D01*
G01X248692Y169092D02*
X262230Y182630D01*
G01X263043Y181816D02*
X249842Y168615D01*
G01X248692Y169092D02*
X262230Y182630D01*
G01X293821Y164584D02*
X293114Y163877D01*
G01X291699Y162462D02*
X290992Y161755D01*
G01X298036Y170426D02*
X289842Y162232D01*
G01X290992Y161755D02*
Y160755D01*
G01Y158755D02*
Y157400D01*
G01X264856Y180014D02*
X252612Y167770D01*
G01X253762Y167293D02*
X265669Y179200D01*
G01X264856Y180014D02*
X252612Y167770D01*
G01X253762Y167293D02*
X265669Y179200D01*
G01X255468Y225291D02*
X262512D01*
G01X255945Y224141D02*
X262512D01*
G01X255468Y225291D02*
X262512D01*
G01X255945Y224141D02*
X262512D01*
G01X257255Y219916D02*
X263144D01*
G01X256778Y221066D02*
X263144D01*
G01X257255Y219916D02*
X263144D01*
G01X256778Y221066D02*
X263144D01*
G01X255945Y224141D02*
X262512D01*
G01X255468Y225291D02*
X262512D01*
G01X255945Y224141D02*
X262512D01*
G01X255468Y225291D02*
X262512D01*
G01X256778Y221066D02*
X263144D01*
G01X257255Y219916D02*
X263144D01*
G01X256778Y221066D02*
X263144D01*
G01X257255Y219916D02*
X263144D01*
G01X255945Y224141D02*
X262512D01*
G01X255468Y225291D02*
X262512D01*
G01X256778Y221066D02*
X263144D01*
G01X257255Y219916D02*
X263144D01*
G01X265892Y370405D02*
X259276D01*
G01X265892Y371555D02*
X259753D01*
G01X265892D02*
X259753D01*
G01X265892Y370405D02*
X259276D01*
G01X265392Y375431D02*
X261412D01*
G01X265372Y374281D02*
X260935D01*
G01X265372D02*
X260935D01*
G01X265392Y375431D02*
X261412D01*
G01X265892Y370405D02*
X259276D01*
G01X265892Y371555D02*
X259753D01*
G01X265892D02*
X259753D01*
G01X265892Y370405D02*
X259276D01*
G01X265392Y375431D02*
X261412D01*
G01X265372Y374281D02*
X260935D01*
G01X265372D02*
X260935D01*
G01X265392Y375431D02*
X261412D01*
G01X286648Y412549D02*
X286171D01*
G01X286170Y412550D02*
X273191D01*
G01X286647Y413700D02*
X273668D01*
G01X273191Y412550D02*
X272284Y413457D01*
G01X270799Y414942D02*
X270022Y415719D01*
G01X268536Y417205D02*
X246012Y439729D01*
G01X273668Y413700D02*
X247162Y440206D01*
G01X246012Y439729D02*
Y476878D01*
G01X247162Y440206D02*
Y476401D01*
G01X306192Y426314D02*
X286116Y446390D01*
G01X306969Y427165D02*
X287266Y446868D01*
G01X286116Y446390D02*
Y478550D01*
G01X287266Y446868D02*
Y492848D01*
G01X251072Y474309D02*
Y461305D01*
G01X249922Y474786D02*
Y460828D01*
G01X251072Y461305D02*
X251774Y460603D01*
G01X249922Y460828D02*
X251297Y459453D01*
G01X251774Y460603D02*
X254061D01*
G01X251297Y459453D02*
X253584D01*
G01X254061Y460603D02*
X255251Y459413D01*
G01X253584Y459453D02*
X254101Y458936D01*
G01X255251Y459413D02*
Y456738D01*
G01X254101Y458936D02*
Y457215D01*
G01X255251Y456738D02*
X254086Y455573D01*
G01X254101Y457215D02*
X253609Y456723D01*
G01X254086Y455573D02*
X251774D01*
G01X253609Y456723D02*
X251297D01*
G01X251774Y455573D02*
X251072Y454871D01*
G01X251297Y456723D02*
X249922Y455348D01*
G01X251072Y454871D02*
Y453545D01*
G01X249922Y455348D02*
Y453068D01*
G01X251072Y453545D02*
X251774Y452843D01*
G01X249922Y453068D02*
X251297Y451693D01*
G01X251774Y452843D02*
X252497D01*
G01X251297Y451693D02*
X252020D01*
G01X252497Y452843D02*
X253872Y451468D01*
G01X252020Y451693D02*
X252722Y450991D01*
G01X253872Y451468D02*
Y449188D01*
G01X252722Y450991D02*
Y449665D01*
G01X253872Y449188D02*
X252497Y447813D01*
G01X252722Y449665D02*
X252020Y448963D01*
G01X252497Y447813D02*
X251982D01*
G01X252020Y448963D02*
X251505D01*
G01X251982Y447813D02*
X251442Y447273D01*
G01X251505Y448963D02*
X250292Y447750D01*
G01X251442Y447273D02*
Y443327D01*
G01X250292Y447750D02*
Y446650D01*
G01X251442Y447273D02*
Y443327D01*
G01X250292Y444550D02*
Y442850D01*
G01X251442Y443327D02*
X277360Y417409D01*
G01X250292Y442850D02*
X251921Y441221D01*
G01X251442Y443327D02*
X277360Y417409D01*
G01X253407Y439735D02*
X254184Y438958D01*
G01X251442Y443327D02*
X277360Y417409D01*
G01X255670Y437472D02*
X256447Y436695D01*
G01X251442Y443327D02*
X277360Y417409D01*
G01X257933Y435209D02*
X258710Y434432D01*
G01X251442Y443327D02*
X277360Y417409D01*
G01X260196Y432946D02*
X260973Y432169D01*
G01X251442Y443327D02*
X277360Y417409D01*
G01X262459Y430683D02*
X263236Y429906D01*
G01X251442Y443327D02*
X277360Y417409D01*
G01X264722Y428420D02*
X265499Y427643D01*
G01X251442Y443327D02*
X277360Y417409D01*
G01X266985Y426157D02*
X267831Y425311D01*
G01X251442Y443327D02*
X277360Y417409D01*
G01X269317Y423825D02*
X270094Y423048D01*
G01X251442Y443327D02*
X277360Y417409D01*
G01X271580Y421562D02*
X272357Y420785D01*
G01X251442Y443327D02*
X277360Y417409D01*
G01X273843Y419299D02*
X274620Y418522D01*
G01X251442Y443327D02*
X277360Y417409D01*
G01X276106Y417036D02*
X276883Y416259D01*
G01X277360Y417409D02*
X286648D01*
G01X276883Y416259D02*
X286648D01*
G01X293763Y461583D02*
X293108Y462238D01*
G01X293585Y463388D02*
X291858D01*
G01X293108Y462238D02*
X291381D01*
G01X293585Y463388D02*
X291858D01*
G01D02*
X291150Y464096D01*
G01X291381Y462238D02*
X290000Y463619D01*
G01X291150Y464096D02*
Y465585D01*
G01X290000Y463619D02*
Y466062D01*
G01X286647Y413700D02*
X273668D01*
G01X286648Y412549D02*
X286171D01*
G01X286647Y413700D02*
X273668D01*
G01X286170Y412550D02*
X273191D01*
G01X273668Y413700D02*
X247162Y440206D01*
G01X273191Y412550D02*
X272284Y413457D01*
G01X273668Y413700D02*
X247162Y440206D01*
G01X270799Y414942D02*
X270022Y415719D01*
G01X273668Y413700D02*
X247162Y440206D01*
G01X268536Y417205D02*
X246012Y439729D01*
G01X247162Y440206D02*
Y476401D01*
G01X246012Y439729D02*
Y476878D01*
G01X306969Y427165D02*
X287266Y446868D01*
G01X306192Y426314D02*
X286116Y446390D01*
G01X287266Y446868D02*
Y492848D01*
G01X286116Y446390D02*
Y478550D01*
G01X287266Y446868D02*
Y492848D01*
G01Y446868D02*
Y492848D01*
G01Y446868D02*
Y492848D01*
G01Y446868D02*
Y492848D01*
G01X249922Y474786D02*
Y460828D01*
G01X251072Y474309D02*
Y461305D01*
G01X249922Y460828D02*
X251297Y459453D01*
G01X251072Y461305D02*
X251774Y460603D01*
G01X251297Y459453D02*
X253584D01*
G01X251774Y460603D02*
X254061D01*
G01X253584Y459453D02*
X254101Y458936D01*
G01X254061Y460603D02*
X255251Y459413D01*
G01X254101Y458936D02*
Y457215D01*
G01X255251Y459413D02*
Y456738D01*
G01X254101Y457215D02*
X253609Y456723D01*
G01X255251Y456738D02*
X254086Y455573D01*
G01X253609Y456723D02*
X251297D01*
G01X254086Y455573D02*
X251774D01*
G01X251297Y456723D02*
X249922Y455348D01*
G01X251774Y455573D02*
X251072Y454871D01*
G01X249922Y455348D02*
Y453068D01*
G01X251072Y454871D02*
Y453545D01*
G01X249922Y453068D02*
X251297Y451693D01*
G01X251072Y453545D02*
X251774Y452843D01*
G01X251297Y451693D02*
X252020D01*
G01X251774Y452843D02*
X252497D01*
G01X252020Y451693D02*
X252722Y450991D01*
G01X252497Y452843D02*
X253872Y451468D01*
G01X252722Y450991D02*
Y449665D01*
G01X253872Y451468D02*
Y449188D01*
G01X252722Y449665D02*
X252020Y448963D01*
G01X253872Y449188D02*
X252497Y447813D01*
G01X252020Y448963D02*
X251505D01*
G01X252497Y447813D02*
X251982D01*
G01X251505Y448963D02*
X250292Y447750D01*
G01X251982Y447813D02*
X251442Y447273D01*
G01X250292Y447750D02*
Y446650D01*
G01Y444550D02*
Y442850D01*
G01X251442Y447273D02*
Y443327D01*
G01X250292Y442850D02*
X251921Y441221D01*
G01X253407Y439735D02*
X254184Y438958D01*
G01X255670Y437472D02*
X256447Y436695D01*
G01X257933Y435209D02*
X258710Y434432D01*
G01X260196Y432946D02*
X260973Y432169D01*
G01X262459Y430683D02*
X263236Y429906D01*
G01X264722Y428420D02*
X265499Y427643D01*
G01X266985Y426157D02*
X267831Y425311D01*
G01X269317Y423825D02*
X270094Y423048D01*
G01X271580Y421562D02*
X272357Y420785D01*
G01X273843Y419299D02*
X274620Y418522D01*
G01X276106Y417036D02*
X276883Y416259D01*
G01X251442Y443327D02*
X277360Y417409D01*
G01X276883Y416259D02*
X286648D01*
G01X277360Y417409D02*
X286648D01*
G01X293763Y461583D02*
X293108Y462238D01*
G01D02*
X291381D01*
G01X293108D02*
X291381D01*
G01D02*
X290000Y463619D01*
G01X293585Y463388D02*
X291858D01*
G01X291381Y462238D02*
X290000Y463619D01*
G01X291858Y463388D02*
X291150Y464096D01*
G01X290000Y463619D02*
Y466062D01*
G01X291150Y464096D02*
Y465585D01*
G01X286648Y412549D02*
X286171D01*
G01X286170Y412550D02*
X273191D01*
G01X286647Y413700D02*
X273668D01*
G01X273191Y412550D02*
X272284Y413457D01*
G01X270799Y414942D02*
X270022Y415719D01*
G01X268536Y417205D02*
X246012Y439729D01*
G01X273668Y413700D02*
X247162Y440206D01*
G01X246012Y439729D02*
Y476878D01*
G01X247162Y440206D02*
Y476401D01*
G01X306192Y426314D02*
X286116Y446390D01*
G01X306969Y427165D02*
X287266Y446868D01*
G01X286116Y446390D02*
Y478550D01*
G01X287266Y446868D02*
Y492848D01*
G01X251072Y474309D02*
Y461305D01*
G01X249922Y474786D02*
Y460828D01*
G01X251072Y461305D02*
X251774Y460603D01*
G01X249922Y460828D02*
X251297Y459453D01*
G01X251774Y460603D02*
X254061D01*
G01X251297Y459453D02*
X253584D01*
G01X254061Y460603D02*
X255251Y459413D01*
G01X253584Y459453D02*
X254101Y458936D01*
G01X255251Y459413D02*
Y456738D01*
G01X254101Y458936D02*
Y457215D01*
G01X255251Y456738D02*
X254086Y455573D01*
G01X254101Y457215D02*
X253609Y456723D01*
G01X254086Y455573D02*
X251774D01*
G01X253609Y456723D02*
X251297D01*
G01X251774Y455573D02*
X251072Y454871D01*
G01X251297Y456723D02*
X249922Y455348D01*
G01X251072Y454871D02*
Y453545D01*
G01X249922Y455348D02*
Y453068D01*
G01X251072Y453545D02*
X251774Y452843D01*
G01X249922Y453068D02*
X251297Y451693D01*
G01X251774Y452843D02*
X252497D01*
G01X251297Y451693D02*
X252020D01*
G01X252497Y452843D02*
X253872Y451468D01*
G01X252020Y451693D02*
X252722Y450991D01*
G01X253872Y451468D02*
Y449188D01*
G01X252722Y450991D02*
Y449665D01*
G01X253872Y449188D02*
X252497Y447813D01*
G01X252722Y449665D02*
X252020Y448963D01*
G01X252497Y447813D02*
X251982D01*
G01X252020Y448963D02*
X251505D01*
G01X251982Y447813D02*
X251442Y447273D01*
G01X251505Y448963D02*
X250292Y447750D01*
G01X251442Y447273D02*
Y443327D01*
G01X250292Y447750D02*
Y446650D01*
G01X251442Y447273D02*
Y443327D01*
G01X250292Y444550D02*
Y442850D01*
G01X251442Y443327D02*
X277360Y417409D01*
G01X250292Y442850D02*
X251921Y441221D01*
G01X251442Y443327D02*
X277360Y417409D01*
G01X253407Y439735D02*
X254184Y438958D01*
G01X251442Y443327D02*
X277360Y417409D01*
G01X255670Y437472D02*
X256447Y436695D01*
G01X251442Y443327D02*
X277360Y417409D01*
G01X257933Y435209D02*
X258710Y434432D01*
G01X251442Y443327D02*
X277360Y417409D01*
G01X260196Y432946D02*
X260973Y432169D01*
G01X251442Y443327D02*
X277360Y417409D01*
G01X262459Y430683D02*
X263236Y429906D01*
G01X251442Y443327D02*
X277360Y417409D01*
G01X264722Y428420D02*
X265499Y427643D01*
G01X251442Y443327D02*
X277360Y417409D01*
G01X266985Y426157D02*
X267831Y425311D01*
G01X251442Y443327D02*
X277360Y417409D01*
G01X269317Y423825D02*
X270094Y423048D01*
G01X251442Y443327D02*
X277360Y417409D01*
G01X271580Y421562D02*
X272357Y420785D01*
G01X251442Y443327D02*
X277360Y417409D01*
G01X273843Y419299D02*
X274620Y418522D01*
G01X251442Y443327D02*
X277360Y417409D01*
G01X276106Y417036D02*
X276883Y416259D01*
G01X277360Y417409D02*
X286648D01*
G01X276883Y416259D02*
X286648D01*
G01X293763Y461583D02*
X293108Y462238D01*
G01X293585Y463388D02*
X291858D01*
G01X293108Y462238D02*
X291381D01*
G01X293585Y463388D02*
X291858D01*
G01D02*
X291150Y464096D01*
G01X291381Y462238D02*
X290000Y463619D01*
G01X291150Y464096D02*
Y465585D01*
G01X290000Y463619D02*
Y466062D01*
G01X286647Y413700D02*
X273668D01*
G01X286648Y412549D02*
X286171D01*
G01X286647Y413700D02*
X273668D01*
G01X286170Y412550D02*
X273191D01*
G01X273668Y413700D02*
X247162Y440206D01*
G01X273191Y412550D02*
X272284Y413457D01*
G01X273668Y413700D02*
X247162Y440206D01*
G01X270799Y414942D02*
X270022Y415719D01*
G01X273668Y413700D02*
X247162Y440206D01*
G01X268536Y417205D02*
X246012Y439729D01*
G01X247162Y440206D02*
Y476401D01*
G01X246012Y439729D02*
Y476878D01*
G01X306969Y427165D02*
X287266Y446868D01*
G01X306192Y426314D02*
X286116Y446390D01*
G01X287266Y446868D02*
Y492848D01*
G01X286116Y446390D02*
Y478550D01*
G01X287266Y446868D02*
Y492848D01*
G01Y446868D02*
Y492848D01*
G01Y446868D02*
Y492848D01*
G01Y446868D02*
Y492848D01*
G01X249922Y474786D02*
Y460828D01*
G01X251072Y474309D02*
Y461305D01*
G01X249922Y460828D02*
X251297Y459453D01*
G01X251072Y461305D02*
X251774Y460603D01*
G01X251297Y459453D02*
X253584D01*
G01X251774Y460603D02*
X254061D01*
G01X253584Y459453D02*
X254101Y458936D01*
G01X254061Y460603D02*
X255251Y459413D01*
G01X254101Y458936D02*
Y457215D01*
G01X255251Y459413D02*
Y456738D01*
G01X254101Y457215D02*
X253609Y456723D01*
G01X255251Y456738D02*
X254086Y455573D01*
G01X253609Y456723D02*
X251297D01*
G01X254086Y455573D02*
X251774D01*
G01X251297Y456723D02*
X249922Y455348D01*
G01X251774Y455573D02*
X251072Y454871D01*
G01X249922Y455348D02*
Y453068D01*
G01X251072Y454871D02*
Y453545D01*
G01X249922Y453068D02*
X251297Y451693D01*
G01X251072Y453545D02*
X251774Y452843D01*
G01X251297Y451693D02*
X252020D01*
G01X251774Y452843D02*
X252497D01*
G01X252020Y451693D02*
X252722Y450991D01*
G01X252497Y452843D02*
X253872Y451468D01*
G01X252722Y450991D02*
Y449665D01*
G01X253872Y451468D02*
Y449188D01*
G01X252722Y449665D02*
X252020Y448963D01*
G01X253872Y449188D02*
X252497Y447813D01*
G01X252020Y448963D02*
X251505D01*
G01X252497Y447813D02*
X251982D01*
G01X251505Y448963D02*
X250292Y447750D01*
G01X251982Y447813D02*
X251442Y447273D01*
G01X250292Y447750D02*
Y446650D01*
G01Y444550D02*
Y442850D01*
G01X251442Y447273D02*
Y443327D01*
G01X250292Y442850D02*
X251921Y441221D01*
G01X253407Y439735D02*
X254184Y438958D01*
G01X255670Y437472D02*
X256447Y436695D01*
G01X257933Y435209D02*
X258710Y434432D01*
G01X260196Y432946D02*
X260973Y432169D01*
G01X262459Y430683D02*
X263236Y429906D01*
G01X264722Y428420D02*
X265499Y427643D01*
G01X266985Y426157D02*
X267831Y425311D01*
G01X269317Y423825D02*
X270094Y423048D01*
G01X271580Y421562D02*
X272357Y420785D01*
G01X273843Y419299D02*
X274620Y418522D01*
G01X276106Y417036D02*
X276883Y416259D01*
G01X251442Y443327D02*
X277360Y417409D01*
G01X276883Y416259D02*
X286648D01*
G01X277360Y417409D02*
X286648D01*
G01X293763Y461583D02*
X293108Y462238D01*
G01D02*
X291381D01*
G01X293108D02*
X291381D01*
G01D02*
X290000Y463619D01*
G01X293585Y463388D02*
X291858D01*
G01X291381Y462238D02*
X290000Y463619D01*
G01X291858Y463388D02*
X291150Y464096D01*
G01X290000Y463619D02*
Y466062D01*
G01X291150Y464096D02*
Y465585D01*
G01X246012Y476878D02*
X246642Y477508D01*
G01X247162Y476401D02*
X247792Y477031D01*
G01X246642Y477508D02*
Y481891D01*
G01X247792Y477031D02*
Y482368D01*
G01X246642Y481891D02*
X246012Y482521D01*
G01X247792Y482368D02*
X247162Y482998D01*
G01X246012Y482521D02*
Y486648D01*
G01X247162Y482998D02*
Y486171D01*
G01X246012Y486648D02*
X246650Y487286D01*
G01X247876Y488512D02*
X249116Y489752D01*
G01X247162Y486171D02*
X250266Y489275D01*
G01X249116Y489752D02*
Y492394D01*
G01X250266Y489275D02*
Y492871D01*
G01X249116Y492394D02*
X248301Y493209D01*
G01X250266Y492871D02*
X247228Y495909D01*
G01X286116Y480450D02*
Y481500D01*
G01Y483500D02*
Y484500D01*
G01Y486500D02*
Y487460D01*
G01Y489500D02*
Y492370D01*
G01D02*
X285111Y493375D01*
G01X287266Y492848D02*
X284170Y495944D01*
G01X252313Y495814D02*
X255366Y492761D01*
G01X253286Y493214D02*
X254216Y492284D01*
G01X255366Y492761D02*
Y489147D01*
G01X254216Y492284D02*
Y489624D01*
G01X255366Y489147D02*
X253192Y486973D01*
G01X254216Y489624D02*
X252042Y487450D01*
G01X253192Y486973D02*
Y476429D01*
G01X252042Y487450D02*
Y486350D01*
G01X253192Y486973D02*
Y476429D01*
G01X252042Y484150D02*
Y483150D01*
G01X253192Y486973D02*
Y476429D01*
G01X252042Y481050D02*
Y479850D01*
G01X253192Y486973D02*
Y476429D01*
G01X252042Y477750D02*
Y476906D01*
G01X253192Y476429D02*
X251072Y474309D01*
G01X252042Y476906D02*
X249922Y474786D01*
G01X291150Y465585D02*
X291844Y466279D01*
G01X290000Y466062D02*
X291367Y467429D01*
G01X291844Y466279D02*
X293669D01*
G01X291367Y467429D02*
X293192D01*
G01D02*
X293842Y468079D01*
G01Y469379D02*
X293192Y470029D01*
G01X293669Y471179D02*
X291731D01*
G01X293192Y470029D02*
X291254D01*
G01X291731Y471179D02*
X291081Y471829D01*
G01X291254Y470029D02*
X289931Y471352D01*
G01X291081Y471829D02*
Y473129D01*
G01X289931Y471352D02*
Y473606D01*
G01X291081Y473129D02*
X292266Y474314D01*
G01X289931Y473606D02*
X291116Y474791D01*
G01X292266Y474314D02*
Y492802D01*
G01X291116Y474791D02*
Y478361D01*
G01X292266Y474314D02*
Y492802D01*
G01X291116Y480333D02*
Y481400D01*
G01X292266Y474314D02*
Y492802D01*
G01X291116Y483400D02*
Y484400D01*
G01X292266Y474314D02*
Y492802D01*
G01X291116Y486400D02*
Y487400D01*
G01X292266Y474314D02*
Y492802D01*
G01X291116Y489400D02*
Y492325D01*
G01X292266Y492802D02*
X289124Y495944D01*
G01X291116Y492325D02*
X290097Y493344D01*
G01X292266Y492802D02*
X289124Y495944D01*
G01X290097Y493344D02*
X289124D01*
G01X247162Y476401D02*
X247792Y477031D01*
G01X246012Y476878D02*
X246642Y477508D01*
G01X247792Y477031D02*
Y482368D01*
G01X246642Y477508D02*
Y481891D01*
G01X247792Y482368D02*
X247162Y482998D01*
G01X246642Y481891D02*
X246012Y482521D01*
G01X247162Y482998D02*
Y486171D01*
G01X246012Y482521D02*
Y486648D01*
G01X247162Y486171D02*
X250266Y489275D01*
G01X246012Y486648D02*
X246650Y487286D01*
G01X247162Y486171D02*
X250266Y489275D01*
G01X247876Y488512D02*
X249116Y489752D01*
G01X250266Y489275D02*
Y492871D01*
G01X249116Y489752D02*
Y492394D01*
G01X250266Y492871D02*
X247228Y495909D01*
G01X249116Y492394D02*
X248301Y493209D01*
G01X286116Y480450D02*
Y481500D01*
G01Y483500D02*
Y484500D01*
G01Y486500D02*
Y487460D01*
G01Y489500D02*
Y492370D01*
G01X287266Y492848D02*
X284170Y495944D01*
G01X286116Y492370D02*
X285111Y493375D01*
G01X253286Y493214D02*
X254216Y492284D01*
G01X252313Y495814D02*
X255366Y492761D01*
G01X254216Y492284D02*
Y489624D01*
G01X255366Y492761D02*
Y489147D01*
G01X254216Y489624D02*
X252042Y487450D01*
G01X255366Y489147D02*
X253192Y486973D01*
G01X252042Y487450D02*
Y486350D01*
G01Y484150D02*
Y483150D01*
G01Y481050D02*
Y479850D01*
G01Y477750D02*
Y476906D01*
G01X253192Y486973D02*
Y476429D01*
G01X252042Y476906D02*
X249922Y474786D01*
G01X253192Y476429D02*
X251072Y474309D01*
G01X290000Y466062D02*
X291367Y467429D01*
G01X291150Y465585D02*
X291844Y466279D01*
G01X291367Y467429D02*
X293192D01*
G01X291844Y466279D02*
X293669D01*
G01X293192Y467429D02*
X293842Y468079D01*
G01Y469379D02*
X293192Y470029D01*
G01D02*
X291254D01*
G01X293669Y471179D02*
X291731D01*
G01X291254Y470029D02*
X289931Y471352D01*
G01X291731Y471179D02*
X291081Y471829D01*
G01X289931Y471352D02*
Y473606D01*
G01X291081Y471829D02*
Y473129D01*
G01X289931Y473606D02*
X291116Y474791D01*
G01X291081Y473129D02*
X292266Y474314D01*
G01X291116Y474791D02*
Y478361D01*
G01Y480333D02*
Y481400D01*
G01Y483400D02*
Y484400D01*
G01Y486400D02*
Y487400D01*
G01Y489400D02*
Y492325D01*
G01X292266Y474314D02*
Y492802D01*
G01X291116Y492325D02*
X290097Y493344D01*
G01D02*
X289124D01*
G01X292266Y492802D02*
X289124Y495944D01*
G01X246012Y476878D02*
X246642Y477508D01*
G01X247162Y476401D02*
X247792Y477031D01*
G01X246642Y477508D02*
Y481891D01*
G01X247792Y477031D02*
Y482368D01*
G01X246642Y481891D02*
X246012Y482521D01*
G01X247792Y482368D02*
X247162Y482998D01*
G01X246012Y482521D02*
Y486648D01*
G01X247162Y482998D02*
Y486171D01*
G01X246012Y486648D02*
X246650Y487286D01*
G01X247876Y488512D02*
X249116Y489752D01*
G01X247162Y486171D02*
X250266Y489275D01*
G01X249116Y489752D02*
Y492394D01*
G01X250266Y489275D02*
Y492871D01*
G01X249116Y492394D02*
X248301Y493209D01*
G01X250266Y492871D02*
X247228Y495909D01*
G01X286116Y480450D02*
Y481500D01*
G01Y483500D02*
Y484500D01*
G01Y486500D02*
Y487460D01*
G01Y489500D02*
Y492370D01*
G01D02*
X285111Y493375D01*
G01X287266Y492848D02*
X284170Y495944D01*
G01X252313Y495814D02*
X255366Y492761D01*
G01X253286Y493214D02*
X254216Y492284D01*
G01X255366Y492761D02*
Y489147D01*
G01X254216Y492284D02*
Y489624D01*
G01X255366Y489147D02*
X253192Y486973D01*
G01X254216Y489624D02*
X252042Y487450D01*
G01X253192Y486973D02*
Y476429D01*
G01X252042Y487450D02*
Y486350D01*
G01X253192Y486973D02*
Y476429D01*
G01X252042Y484150D02*
Y483150D01*
G01X253192Y486973D02*
Y476429D01*
G01X252042Y481050D02*
Y479850D01*
G01X253192Y486973D02*
Y476429D01*
G01X252042Y477750D02*
Y476906D01*
G01X253192Y476429D02*
X251072Y474309D01*
G01X252042Y476906D02*
X249922Y474786D01*
G01X291150Y465585D02*
X291844Y466279D01*
G01X290000Y466062D02*
X291367Y467429D01*
G01X291844Y466279D02*
X293669D01*
G01X291367Y467429D02*
X293192D01*
G01D02*
X293842Y468079D01*
G01Y469379D02*
X293192Y470029D01*
G01X293669Y471179D02*
X291731D01*
G01X293192Y470029D02*
X291254D01*
G01X291731Y471179D02*
X291081Y471829D01*
G01X291254Y470029D02*
X289931Y471352D01*
G01X291081Y471829D02*
Y473129D01*
G01X289931Y471352D02*
Y473606D01*
G01X291081Y473129D02*
X292266Y474314D01*
G01X289931Y473606D02*
X291116Y474791D01*
G01X292266Y474314D02*
Y492802D01*
G01X291116Y474791D02*
Y478361D01*
G01X292266Y474314D02*
Y492802D01*
G01X291116Y480333D02*
Y481400D01*
G01X292266Y474314D02*
Y492802D01*
G01X291116Y483400D02*
Y484400D01*
G01X292266Y474314D02*
Y492802D01*
G01X291116Y486400D02*
Y487400D01*
G01X292266Y474314D02*
Y492802D01*
G01X291116Y489400D02*
Y492325D01*
G01X292266Y492802D02*
X289124Y495944D01*
G01X291116Y492325D02*
X290097Y493344D01*
G01X292266Y492802D02*
X289124Y495944D01*
G01X290097Y493344D02*
X289124D01*
G01X247162Y476401D02*
X247792Y477031D01*
G01X246012Y476878D02*
X246642Y477508D01*
G01X247792Y477031D02*
Y482368D01*
G01X246642Y477508D02*
Y481891D01*
G01X247792Y482368D02*
X247162Y482998D01*
G01X246642Y481891D02*
X246012Y482521D01*
G01X247162Y482998D02*
Y486171D01*
G01X246012Y482521D02*
Y486648D01*
G01X247162Y486171D02*
X250266Y489275D01*
G01X246012Y486648D02*
X246650Y487286D01*
G01X247162Y486171D02*
X250266Y489275D01*
G01X247876Y488512D02*
X249116Y489752D01*
G01X250266Y489275D02*
Y492871D01*
G01X249116Y489752D02*
Y492394D01*
G01X250266Y492871D02*
X247228Y495909D01*
G01X249116Y492394D02*
X248301Y493209D01*
G01X286116Y480450D02*
Y481500D01*
G01Y483500D02*
Y484500D01*
G01Y486500D02*
Y487460D01*
G01Y489500D02*
Y492370D01*
G01X287266Y492848D02*
X284170Y495944D01*
G01X286116Y492370D02*
X285111Y493375D01*
G01X253286Y493214D02*
X254216Y492284D01*
G01X252313Y495814D02*
X255366Y492761D01*
G01X254216Y492284D02*
Y489624D01*
G01X255366Y492761D02*
Y489147D01*
G01X254216Y489624D02*
X252042Y487450D01*
G01X255366Y489147D02*
X253192Y486973D01*
G01X252042Y487450D02*
Y486350D01*
G01Y484150D02*
Y483150D01*
G01Y481050D02*
Y479850D01*
G01Y477750D02*
Y476906D01*
G01X253192Y486973D02*
Y476429D01*
G01X252042Y476906D02*
X249922Y474786D01*
G01X253192Y476429D02*
X251072Y474309D01*
G01X290000Y466062D02*
X291367Y467429D01*
G01X291150Y465585D02*
X291844Y466279D01*
G01X291367Y467429D02*
X293192D01*
G01X291844Y466279D02*
X293669D01*
G01X293192Y467429D02*
X293842Y468079D01*
G01Y469379D02*
X293192Y470029D01*
G01D02*
X291254D01*
G01X293669Y471179D02*
X291731D01*
G01X291254Y470029D02*
X289931Y471352D01*
G01X291731Y471179D02*
X291081Y471829D01*
G01X289931Y471352D02*
Y473606D01*
G01X291081Y471829D02*
Y473129D01*
G01X289931Y473606D02*
X291116Y474791D01*
G01X291081Y473129D02*
X292266Y474314D01*
G01X291116Y474791D02*
Y478361D01*
G01Y480333D02*
Y481400D01*
G01Y483400D02*
Y484400D01*
G01Y486400D02*
Y487400D01*
G01Y489400D02*
Y492325D01*
G01X292266Y474314D02*
Y492802D01*
G01X291116Y492325D02*
X290097Y493344D01*
G01D02*
X289124D01*
G01X292266Y492802D02*
X289124Y495944D01*
G01X293826Y142150D02*
X294542Y141434D01*
G01X294303Y143300D02*
X295692Y141911D01*
G01X294542Y141434D02*
Y138440D01*
G01X295692Y141911D02*
Y137963D01*
G01X294542Y138440D02*
X293892Y137790D01*
G01X295692Y137963D02*
X294369Y136640D01*
G01X293892Y132840D02*
X294542Y132190D01*
G01X294369Y133990D02*
X295692Y132667D01*
G01X294542Y132190D02*
Y129799D01*
G01X295692Y132667D02*
Y129322D01*
G01D02*
X294231Y127861D01*
G01X297042Y156717D02*
Y155717D01*
G01Y153717D02*
Y152717D01*
G01Y150717D02*
Y149463D01*
G01X295892Y160194D02*
Y148986D01*
G01X297042Y149463D02*
X298942Y147563D01*
G01X295892Y148986D02*
X297792Y147086D01*
G01X298942Y147563D02*
Y144177D01*
G01X297792Y147086D02*
Y143700D01*
G01X298942Y144177D02*
X299542Y143577D01*
G01X297792Y143700D02*
X298392Y143100D01*
G01X299542Y143577D02*
Y142577D01*
G01Y140577D02*
Y139577D01*
G01Y137577D02*
Y136577D01*
G01Y134577D02*
Y133537D01*
G01Y131739D02*
Y127023D01*
G01X298392Y143100D02*
Y127500D01*
G01X299542Y127023D02*
X296522Y124003D01*
G01X298392Y127500D02*
X295372Y124480D01*
G01X296522Y124003D02*
Y123271D01*
G01X295372Y124480D02*
Y123748D01*
G01X296522Y123271D02*
X293564Y120313D01*
G01X294303Y143300D02*
X295692Y141911D01*
G01X293826Y142150D02*
X294542Y141434D01*
G01X295692Y141911D02*
Y137963D01*
G01X294542Y141434D02*
Y138440D01*
G01X295692Y137963D02*
X294369Y136640D01*
G01X294542Y138440D02*
X293892Y137790D01*
G01X294369Y133990D02*
X295692Y132667D01*
G01X293892Y132840D02*
X294542Y132190D01*
G01X295692Y132667D02*
Y129322D01*
G01X294542Y132190D02*
Y129799D01*
G01X295692Y129322D02*
X294231Y127861D01*
G01X295892Y160194D02*
Y148986D01*
G01Y160194D02*
Y148986D01*
G01X297042Y156717D02*
Y155717D01*
G01X295892Y160194D02*
Y148986D01*
G01X297042Y153717D02*
Y152717D01*
G01X295892Y160194D02*
Y148986D01*
G01X297042Y150717D02*
Y149463D01*
G01X295892Y148986D02*
X297792Y147086D01*
G01X297042Y149463D02*
X298942Y147563D01*
G01X297792Y147086D02*
Y143700D01*
G01X298942Y147563D02*
Y144177D01*
G01X297792Y143700D02*
X298392Y143100D01*
G01X298942Y144177D02*
X299542Y143577D01*
G01X298392Y143100D02*
Y127500D01*
G01X299542Y143577D02*
Y142577D01*
G01X298392Y143100D02*
Y127500D01*
G01X299542Y140577D02*
Y139577D01*
G01X298392Y143100D02*
Y127500D01*
G01X299542Y137577D02*
Y136577D01*
G01X298392Y143100D02*
Y127500D01*
G01X299542Y134577D02*
Y133537D01*
G01X298392Y143100D02*
Y127500D01*
G01X299542Y131739D02*
Y127023D01*
G01X298392Y127500D02*
X295372Y124480D01*
G01X299542Y127023D02*
X296522Y124003D01*
G01X295372Y124480D02*
Y123748D01*
G01X296522Y124003D02*
Y123271D01*
G01D02*
X293564Y120313D01*
G01X293826Y142150D02*
X294542Y141434D01*
G01X294303Y143300D02*
X295692Y141911D01*
G01X294542Y141434D02*
Y138440D01*
G01X295692Y141911D02*
Y137963D01*
G01X294542Y138440D02*
X293892Y137790D01*
G01X295692Y137963D02*
X294369Y136640D01*
G01X293892Y132840D02*
X294542Y132190D01*
G01X294369Y133990D02*
X295692Y132667D01*
G01X294542Y132190D02*
Y129799D01*
G01X295692Y132667D02*
Y129322D01*
G01D02*
X294231Y127861D01*
G01X297042Y156717D02*
Y155717D01*
G01Y153717D02*
Y152717D01*
G01Y150717D02*
Y149463D01*
G01X295892Y160194D02*
Y148986D01*
G01X297042Y149463D02*
X298942Y147563D01*
G01X295892Y148986D02*
X297792Y147086D01*
G01X298942Y147563D02*
Y144177D01*
G01X297792Y147086D02*
Y143700D01*
G01X298942Y144177D02*
X299542Y143577D01*
G01X297792Y143700D02*
X298392Y143100D01*
G01X299542Y143577D02*
Y142577D01*
G01Y140577D02*
Y139577D01*
G01Y137577D02*
Y136577D01*
G01Y134577D02*
Y133537D01*
G01Y131739D02*
Y127023D01*
G01X298392Y143100D02*
Y127500D01*
G01X299542Y127023D02*
X296522Y124003D01*
G01X298392Y127500D02*
X295372Y124480D01*
G01X296522Y124003D02*
Y123271D01*
G01X295372Y124480D02*
Y123748D01*
G01X296522Y123271D02*
X293564Y120313D01*
G01X294303Y143300D02*
X295692Y141911D01*
G01X293826Y142150D02*
X294542Y141434D01*
G01X295692Y141911D02*
Y137963D01*
G01X294542Y141434D02*
Y138440D01*
G01X295692Y137963D02*
X294369Y136640D01*
G01X294542Y138440D02*
X293892Y137790D01*
G01X294369Y133990D02*
X295692Y132667D01*
G01X293892Y132840D02*
X294542Y132190D01*
G01X295692Y132667D02*
Y129322D01*
G01X294542Y132190D02*
Y129799D01*
G01X295692Y129322D02*
X294231Y127861D01*
G01X295892Y160194D02*
Y148986D01*
G01Y160194D02*
Y148986D01*
G01X297042Y156717D02*
Y155717D01*
G01X295892Y160194D02*
Y148986D01*
G01X297042Y153717D02*
Y152717D01*
G01X295892Y160194D02*
Y148986D01*
G01X297042Y150717D02*
Y149463D01*
G01X295892Y148986D02*
X297792Y147086D01*
G01X297042Y149463D02*
X298942Y147563D01*
G01X297792Y147086D02*
Y143700D01*
G01X298942Y147563D02*
Y144177D01*
G01X297792Y143700D02*
X298392Y143100D01*
G01X298942Y144177D02*
X299542Y143577D01*
G01X298392Y143100D02*
Y127500D01*
G01X299542Y143577D02*
Y142577D01*
G01X298392Y143100D02*
Y127500D01*
G01X299542Y140577D02*
Y139577D01*
G01X298392Y143100D02*
Y127500D01*
G01X299542Y137577D02*
Y136577D01*
G01X298392Y143100D02*
Y127500D01*
G01X299542Y134577D02*
Y133537D01*
G01X298392Y143100D02*
Y127500D01*
G01X299542Y131739D02*
Y127023D01*
G01X298392Y127500D02*
X295372Y124480D01*
G01X299542Y127023D02*
X296522Y124003D01*
G01X295372Y124480D02*
Y123748D01*
G01X296522Y124003D02*
Y123271D01*
G01D02*
X293564Y120313D01*
G01X298849Y169612D02*
X295236Y165999D01*
G01X301390Y166865D02*
X298942Y164417D01*
G01X300576Y167679D02*
X297792Y164895D01*
G01X298942Y164417D02*
Y161617D01*
G01X297792Y164895D02*
Y162094D01*
G01X298942Y161617D02*
X297042Y159717D01*
G01X297792Y162094D02*
X295892Y160194D01*
G01X297042Y159717D02*
Y158717D01*
G01X298849Y169612D02*
X295236Y165999D01*
G01X300576Y167679D02*
X297792Y164895D01*
G01X301390Y166865D02*
X298942Y164417D01*
G01X297792Y164895D02*
Y162094D01*
G01X298942Y164417D02*
Y161617D01*
G01X297792Y162094D02*
X295892Y160194D01*
G01X298942Y161617D02*
X297042Y159717D01*
G01D02*
Y158717D01*
G01X298849Y169612D02*
X295236Y165999D01*
G01X301390Y166865D02*
X298942Y164417D01*
G01X300576Y167679D02*
X297792Y164895D01*
G01X298942Y164417D02*
Y161617D01*
G01X297792Y164895D02*
Y162094D01*
G01X298942Y161617D02*
X297042Y159717D01*
G01X297792Y162094D02*
X295892Y160194D01*
G01X297042Y159717D02*
Y158717D01*
G01X298849Y169612D02*
X295236Y165999D01*
G01X300576Y167679D02*
X297792Y164895D01*
G01X301390Y166865D02*
X298942Y164417D01*
G01X297792Y164895D02*
Y162094D01*
G01X298942Y164417D02*
Y161617D01*
G01X297792Y162094D02*
X295892Y160194D01*
G01X298942Y161617D02*
X297042Y159717D01*
G01D02*
Y158717D01*
G01X309659Y430477D02*
X294913Y445223D01*
G01X308846Y429663D02*
X307050Y431459D01*
G01X309659Y430477D02*
X294913Y445223D01*
G01X307050Y431459D02*
X306285D01*
G01X309659Y430477D02*
X294913Y445223D01*
G01X305578Y432931D02*
X304653Y433856D01*
G01X309659Y430477D02*
X294913Y445223D01*
G01X304653Y433856D02*
X303889D01*
G01X309659Y430477D02*
X294913Y445223D01*
G01X303182Y435327D02*
X302475Y436034D01*
G01X309659Y430477D02*
X294913Y445223D01*
G01X302475Y436034D02*
X301711D01*
G01X309659Y430477D02*
X294913Y445223D01*
G01X301004Y437505D02*
X300297Y438212D01*
G01X309659Y430477D02*
X294913Y445223D01*
G01X300297Y438212D02*
X299533D01*
G01X309659Y430477D02*
X294913Y445223D01*
G01X298826Y439683D02*
X298119Y440390D01*
G01X309659Y430477D02*
X294913Y445223D01*
G01X298119Y440390D02*
X297355D01*
G01X309659Y430477D02*
X294913Y445223D01*
G01X296648Y441861D02*
X295941Y442568D01*
G01X309659Y430477D02*
X294913Y445223D01*
G01X295941Y442568D02*
X295177D01*
G01X309659Y430477D02*
X294913Y445223D01*
G01X294470Y444039D02*
X293763Y444746D01*
G01X294913Y445223D02*
Y462060D01*
G01X293763Y444746D02*
Y445677D01*
G01X294913Y445223D02*
Y462060D01*
G01X293763Y447539D02*
Y448615D01*
G01X294913Y445223D02*
Y462060D01*
G01X293763Y450855D02*
Y451855D01*
G01X294913Y445223D02*
Y462060D01*
G01X293763Y454095D02*
Y455095D01*
G01X294913Y445223D02*
Y462060D01*
G01X293763Y457335D02*
Y458335D01*
G01X294913Y445223D02*
Y462060D01*
G01X293763Y460575D02*
Y461583D01*
G01X294913Y462060D02*
X293585Y463388D01*
G01X294913Y462060D02*
X293585Y463388D01*
G01X308846Y429663D02*
X307050Y431459D01*
G01D02*
X306285D01*
G01X305578Y432931D02*
X304653Y433856D01*
G01D02*
X303889D01*
G01X303182Y435327D02*
X302475Y436034D01*
G01D02*
X301711D01*
G01X301004Y437505D02*
X300297Y438212D01*
G01D02*
X299533D01*
G01X298826Y439683D02*
X298119Y440390D01*
G01D02*
X297355D01*
G01X296648Y441861D02*
X295941Y442568D01*
G01D02*
X295177D01*
G01X294470Y444039D02*
X293763Y444746D01*
G01X309659Y430477D02*
X294913Y445223D01*
G01X293763Y444746D02*
Y445677D01*
G01Y447539D02*
Y448615D01*
G01Y450855D02*
Y451855D01*
G01Y454095D02*
Y455095D01*
G01Y457335D02*
Y458335D01*
G01Y460575D02*
Y461583D01*
G01X294913Y445223D02*
Y462060D01*
G01D02*
X293585Y463388D01*
G01X309659Y430477D02*
X294913Y445223D01*
G01X308846Y429663D02*
X307050Y431459D01*
G01X309659Y430477D02*
X294913Y445223D01*
G01X307050Y431459D02*
X306285D01*
G01X309659Y430477D02*
X294913Y445223D01*
G01X305578Y432931D02*
X304653Y433856D01*
G01X309659Y430477D02*
X294913Y445223D01*
G01X304653Y433856D02*
X303889D01*
G01X309659Y430477D02*
X294913Y445223D01*
G01X303182Y435327D02*
X302475Y436034D01*
G01X309659Y430477D02*
X294913Y445223D01*
G01X302475Y436034D02*
X301711D01*
G01X309659Y430477D02*
X294913Y445223D01*
G01X301004Y437505D02*
X300297Y438212D01*
G01X309659Y430477D02*
X294913Y445223D01*
G01X300297Y438212D02*
X299533D01*
G01X309659Y430477D02*
X294913Y445223D01*
G01X298826Y439683D02*
X298119Y440390D01*
G01X309659Y430477D02*
X294913Y445223D01*
G01X298119Y440390D02*
X297355D01*
G01X309659Y430477D02*
X294913Y445223D01*
G01X296648Y441861D02*
X295941Y442568D01*
G01X309659Y430477D02*
X294913Y445223D01*
G01X295941Y442568D02*
X295177D01*
G01X309659Y430477D02*
X294913Y445223D01*
G01X294470Y444039D02*
X293763Y444746D01*
G01X294913Y445223D02*
Y462060D01*
G01X293763Y444746D02*
Y445677D01*
G01X294913Y445223D02*
Y462060D01*
G01X293763Y447539D02*
Y448615D01*
G01X294913Y445223D02*
Y462060D01*
G01X293763Y450855D02*
Y451855D01*
G01X294913Y445223D02*
Y462060D01*
G01X293763Y454095D02*
Y455095D01*
G01X294913Y445223D02*
Y462060D01*
G01X293763Y457335D02*
Y458335D01*
G01X294913Y445223D02*
Y462060D01*
G01X293763Y460575D02*
Y461583D01*
G01X294913Y462060D02*
X293585Y463388D01*
G01X294913Y462060D02*
X293585Y463388D01*
G01X308846Y429663D02*
X307050Y431459D01*
G01D02*
X306285D01*
G01X305578Y432931D02*
X304653Y433856D01*
G01D02*
X303889D01*
G01X303182Y435327D02*
X302475Y436034D01*
G01D02*
X301711D01*
G01X301004Y437505D02*
X300297Y438212D01*
G01D02*
X299533D01*
G01X298826Y439683D02*
X298119Y440390D01*
G01D02*
X297355D01*
G01X296648Y441861D02*
X295941Y442568D01*
G01D02*
X295177D01*
G01X294470Y444039D02*
X293763Y444746D01*
G01X309659Y430477D02*
X294913Y445223D01*
G01X293763Y444746D02*
Y445677D01*
G01Y447539D02*
Y448615D01*
G01Y450855D02*
Y451855D01*
G01Y454095D02*
Y455095D01*
G01Y457335D02*
Y458335D01*
G01Y460575D02*
Y461583D01*
G01X294913Y445223D02*
Y462060D01*
G01D02*
X293585Y463388D01*
G01X293669Y466279D02*
X294992Y467602D01*
G01D02*
Y469856D01*
G01X293842Y468079D02*
Y469379D01*
G01X294992Y469856D02*
X293669Y471179D01*
G01Y466279D02*
X294992Y467602D01*
G01X293842Y468079D02*
Y469379D01*
G01X294992Y467602D02*
Y469856D01*
G01D02*
X293669Y471179D01*
G01Y466279D02*
X294992Y467602D01*
G01D02*
Y469856D01*
G01X293842Y468079D02*
Y469379D01*
G01X294992Y469856D02*
X293669Y471179D01*
G01Y466279D02*
X294992Y467602D01*
G01X293842Y468079D02*
Y469379D01*
G01X294992Y467602D02*
Y469856D01*
G01D02*
X293669Y471179D01*
G01X362316Y66325D02*
Y67778D01*
G01X363466Y66226D02*
Y67301D01*
G01X362316Y67778D02*
X363692Y69154D01*
G01X363466Y67301D02*
X364344Y68178D01*
G01X363692Y69154D02*
X366097Y70150D01*
G01X364344Y68178D02*
X366326Y69000D01*
G01X366097Y70150D02*
X369980D01*
G01X366326Y69000D02*
X370209D01*
G01X369980Y70150D02*
X375300Y72353D01*
G01X370209Y69000D02*
X375952Y71377D01*
G01X375300Y72353D02*
X376344Y73397D01*
G01X375952Y71377D02*
X377320Y72745D01*
G01X376344Y73397D02*
X377662Y76579D01*
G01X377320Y72745D02*
X378812Y76350D01*
G01X377662Y76579D02*
Y78869D01*
G01Y81779D02*
Y86510D01*
G01X378812Y76350D02*
Y86739D01*
G01X377662Y86510D02*
X377349Y87266D01*
G01X378812Y86739D02*
X378594Y87266D01*
G01X377662Y86510D02*
X377349Y87266D01*
G01D02*
X376190Y90064D01*
G01X378594Y87266D02*
X377340Y90293D01*
G01X376190Y90064D02*
Y95341D01*
G01X377340Y90293D02*
Y99545D01*
G01X363186Y96460D02*
Y92894D01*
G01X364336Y109095D02*
Y93771D01*
G01X362316Y82509D02*
Y83827D01*
G01X363466Y82259D02*
Y83350D01*
G01X362316Y83827D02*
X363639Y85150D01*
G01X363466Y83350D02*
X364116Y84000D01*
G01X363639Y85150D02*
X370415D01*
G01X364116Y84000D02*
X370892D01*
G01X370415Y85150D02*
X371417Y86152D01*
G01X370892Y84000D02*
X372567Y85675D01*
G01X371417Y86152D02*
Y88853D01*
G01X372567Y85675D02*
Y88376D01*
G01X371417Y88853D02*
X373225Y90661D01*
G01X372567Y88376D02*
X374375Y90184D01*
G01X373225Y90661D02*
Y93826D01*
G01X374375Y90184D02*
Y94303D01*
G01X373225Y93826D02*
X372634Y94417D01*
G01X374375Y94303D02*
X373111Y95567D01*
G01X372634Y94417D02*
X367708D01*
G01D02*
X366385Y95740D01*
G01X359467Y94878D02*
X359867Y94478D01*
G01D02*
Y90610D01*
G01X361017Y94955D02*
Y91087D01*
G01X359867Y90610D02*
X361040Y89437D01*
G01X361017Y91087D02*
X361517Y90587D01*
G01X361040Y89437D02*
X362678D01*
G01X361517Y90587D02*
X363155D01*
G01X362678Y89437D02*
X363263Y88852D01*
G01X363155Y90587D02*
X364413Y89329D01*
G01X363263Y88852D02*
Y88328D01*
G01X364413Y89329D02*
Y88321D01*
G01X363466Y66226D02*
Y67301D01*
G01X362316Y66325D02*
Y67778D01*
G01X363466Y67301D02*
X364344Y68178D01*
G01X362316Y67778D02*
X363692Y69154D01*
G01X364344Y68178D02*
X366326Y69000D01*
G01X363692Y69154D02*
X366097Y70150D01*
G01X366326Y69000D02*
X370209D01*
G01X366097Y70150D02*
X369980D01*
G01X370209Y69000D02*
X375952Y71377D01*
G01X369980Y70150D02*
X375300Y72353D01*
G01X375952Y71377D02*
X377320Y72745D01*
G01X375300Y72353D02*
X376344Y73397D01*
G01X377320Y72745D02*
X378812Y76350D01*
G01X376344Y73397D02*
X377662Y76579D01*
G01X378812Y76350D02*
Y86739D01*
G01X377662Y76579D02*
Y78869D01*
G01X378812Y76350D02*
Y86739D01*
G01X377662Y81779D02*
Y86510D01*
G01X378812Y86739D02*
X378594Y87266D01*
G01D02*
X377340Y90293D01*
G01X377662Y86510D02*
X377349Y87266D01*
G01X378594D02*
X377340Y90293D01*
G01X377349Y87266D02*
X376190Y90064D01*
G01X377340Y90293D02*
Y99545D01*
G01X376190Y90064D02*
Y95341D01*
G01X377340Y90293D02*
Y99545D01*
G01X364336Y109095D02*
Y93771D01*
G01Y109095D02*
Y93771D01*
G01Y109095D02*
Y93771D01*
G01Y109095D02*
Y93771D01*
G01X363186Y96460D02*
Y92894D01*
G01X363466Y82259D02*
Y83350D01*
G01X362316Y82509D02*
Y83827D01*
G01X363466Y83350D02*
X364116Y84000D01*
G01X362316Y83827D02*
X363639Y85150D01*
G01X364116Y84000D02*
X370892D01*
G01X363639Y85150D02*
X370415D01*
G01X370892Y84000D02*
X372567Y85675D01*
G01X370415Y85150D02*
X371417Y86152D01*
G01X372567Y85675D02*
Y88376D01*
G01X371417Y86152D02*
Y88853D01*
G01X372567Y88376D02*
X374375Y90184D01*
G01X371417Y88853D02*
X373225Y90661D01*
G01X374375Y90184D02*
Y94303D01*
G01X373225Y90661D02*
Y93826D01*
G01X374375Y94303D02*
X373111Y95567D01*
G01X373225Y93826D02*
X372634Y94417D01*
G01D02*
X367708D01*
G01D02*
X366385Y95740D01*
G01X359467Y94878D02*
X359867Y94478D01*
G01X361017Y94955D02*
Y91087D01*
G01X359867Y94478D02*
Y90610D01*
G01X361017Y91087D02*
X361517Y90587D01*
G01X359867Y90610D02*
X361040Y89437D01*
G01X361517Y90587D02*
X363155D01*
G01X361040Y89437D02*
X362678D01*
G01X363155Y90587D02*
X364413Y89329D01*
G01X362678Y89437D02*
X363263Y88852D01*
G01X364413Y89329D02*
Y88321D01*
G01X363263Y88852D02*
Y88328D01*
G01X362316Y66325D02*
Y67778D01*
G01X363466Y66226D02*
Y67301D01*
G01X362316Y67778D02*
X363692Y69154D01*
G01X363466Y67301D02*
X364344Y68178D01*
G01X363692Y69154D02*
X366097Y70150D01*
G01X364344Y68178D02*
X366326Y69000D01*
G01X366097Y70150D02*
X369980D01*
G01X366326Y69000D02*
X370209D01*
G01X369980Y70150D02*
X375300Y72353D01*
G01X370209Y69000D02*
X375952Y71377D01*
G01X375300Y72353D02*
X376344Y73397D01*
G01X375952Y71377D02*
X377320Y72745D01*
G01X376344Y73397D02*
X377662Y76579D01*
G01X377320Y72745D02*
X378812Y76350D01*
G01X377662Y76579D02*
Y78869D01*
G01Y81779D02*
Y86510D01*
G01X378812Y76350D02*
Y86739D01*
G01X377662Y86510D02*
X377349Y87266D01*
G01X378812Y86739D02*
X378594Y87266D01*
G01X377662Y86510D02*
X377349Y87266D01*
G01D02*
X376190Y90064D01*
G01X378594Y87266D02*
X377340Y90293D01*
G01X376190Y90064D02*
Y95341D01*
G01X377340Y90293D02*
Y99545D01*
G01X363186Y96460D02*
Y92894D01*
G01X364336Y109095D02*
Y93771D01*
G01X362316Y82509D02*
Y83827D01*
G01X363466Y82259D02*
Y83350D01*
G01X362316Y83827D02*
X363639Y85150D01*
G01X363466Y83350D02*
X364116Y84000D01*
G01X363639Y85150D02*
X370415D01*
G01X364116Y84000D02*
X370892D01*
G01X370415Y85150D02*
X371417Y86152D01*
G01X370892Y84000D02*
X372567Y85675D01*
G01X371417Y86152D02*
Y88853D01*
G01X372567Y85675D02*
Y88376D01*
G01X371417Y88853D02*
X373225Y90661D01*
G01X372567Y88376D02*
X374375Y90184D01*
G01X373225Y90661D02*
Y93826D01*
G01X374375Y90184D02*
Y94303D01*
G01X373225Y93826D02*
X372634Y94417D01*
G01X374375Y94303D02*
X373111Y95567D01*
G01X372634Y94417D02*
X367708D01*
G01D02*
X366385Y95740D01*
G01X359467Y94878D02*
X359867Y94478D01*
G01D02*
Y90610D01*
G01X361017Y94955D02*
Y91087D01*
G01X359867Y90610D02*
X361040Y89437D01*
G01X361017Y91087D02*
X361517Y90587D01*
G01X361040Y89437D02*
X362678D01*
G01X361517Y90587D02*
X363155D01*
G01X362678Y89437D02*
X363263Y88852D01*
G01X363155Y90587D02*
X364413Y89329D01*
G01X363263Y88852D02*
Y88328D01*
G01X364413Y89329D02*
Y88321D01*
G01X363466Y66226D02*
Y67301D01*
G01X362316Y66325D02*
Y67778D01*
G01X363466Y67301D02*
X364344Y68178D01*
G01X362316Y67778D02*
X363692Y69154D01*
G01X364344Y68178D02*
X366326Y69000D01*
G01X363692Y69154D02*
X366097Y70150D01*
G01X366326Y69000D02*
X370209D01*
G01X366097Y70150D02*
X369980D01*
G01X370209Y69000D02*
X375952Y71377D01*
G01X369980Y70150D02*
X375300Y72353D01*
G01X375952Y71377D02*
X377320Y72745D01*
G01X375300Y72353D02*
X376344Y73397D01*
G01X377320Y72745D02*
X378812Y76350D01*
G01X376344Y73397D02*
X377662Y76579D01*
G01X378812Y76350D02*
Y86739D01*
G01X377662Y76579D02*
Y78869D01*
G01X378812Y76350D02*
Y86739D01*
G01X377662Y81779D02*
Y86510D01*
G01X378812Y86739D02*
X378594Y87266D01*
G01D02*
X377340Y90293D01*
G01X377662Y86510D02*
X377349Y87266D01*
G01X378594D02*
X377340Y90293D01*
G01X377349Y87266D02*
X376190Y90064D01*
G01X377340Y90293D02*
Y99545D01*
G01X376190Y90064D02*
Y95341D01*
G01X377340Y90293D02*
Y99545D01*
G01X364336Y109095D02*
Y93771D01*
G01Y109095D02*
Y93771D01*
G01Y109095D02*
Y93771D01*
G01Y109095D02*
Y93771D01*
G01X363186Y96460D02*
Y92894D01*
G01X363466Y82259D02*
Y83350D01*
G01X362316Y82509D02*
Y83827D01*
G01X363466Y83350D02*
X364116Y84000D01*
G01X362316Y83827D02*
X363639Y85150D01*
G01X364116Y84000D02*
X370892D01*
G01X363639Y85150D02*
X370415D01*
G01X370892Y84000D02*
X372567Y85675D01*
G01X370415Y85150D02*
X371417Y86152D01*
G01X372567Y85675D02*
Y88376D01*
G01X371417Y86152D02*
Y88853D01*
G01X372567Y88376D02*
X374375Y90184D01*
G01X371417Y88853D02*
X373225Y90661D01*
G01X374375Y90184D02*
Y94303D01*
G01X373225Y90661D02*
Y93826D01*
G01X374375Y94303D02*
X373111Y95567D01*
G01X373225Y93826D02*
X372634Y94417D01*
G01D02*
X367708D01*
G01D02*
X366385Y95740D01*
G01X359467Y94878D02*
X359867Y94478D01*
G01X361017Y94955D02*
Y91087D01*
G01X359867Y94478D02*
Y90610D01*
G01X361017Y91087D02*
X361517Y90587D01*
G01X359867Y90610D02*
X361040Y89437D01*
G01X361517Y90587D02*
X363155D01*
G01X361040Y89437D02*
X362678D01*
G01X363155Y90587D02*
X364413Y89329D01*
G01X362678Y89437D02*
X363263Y88852D01*
G01X364413Y89329D02*
Y88321D01*
G01X363263Y88852D02*
Y88328D01*
G01X377272Y116996D02*
Y181268D01*
G01Y108017D02*
Y116996D01*
G01X378422Y106505D02*
Y181266D01*
G01X376190Y98179D02*
Y100022D01*
G01D02*
X377272Y101104D01*
G01X377340Y99545D02*
X378422Y100627D01*
G01X377272Y101104D02*
Y105839D01*
G01X378422Y100627D02*
Y106505D01*
G01X371002Y182686D02*
Y117388D01*
G01X372152Y182706D02*
Y116911D01*
G01X371002Y117388D02*
X369516Y115902D01*
G01D02*
X368823D01*
G01X372152Y116911D02*
X370193Y114952D01*
G01X367647Y114033D02*
X363186Y109572D01*
G01X370193Y114952D02*
X364336Y109095D01*
G01X363186Y109572D02*
Y108014D01*
G01D02*
Y102731D01*
G01Y100263D02*
Y98838D01*
G01X374137Y183105D02*
Y140732D01*
G01X375287Y183105D02*
Y127696D01*
G01X373111Y95567D02*
X368185D01*
G01D02*
X367535Y96217D01*
G01X366385Y95740D02*
Y100002D01*
G01X367535Y96217D02*
Y99525D01*
G01X366385Y100002D02*
X367708Y101325D01*
G01X367535Y99525D02*
X368185Y100175D01*
G01X367708Y101325D02*
X370292D01*
G01X368185Y100175D02*
X369815D01*
G01X370292Y101325D02*
X370717Y100900D01*
G01X369815Y100175D02*
X370240Y99750D01*
G01X370717Y100900D02*
X372600D01*
G01X370240Y99750D02*
X373077D01*
G01X372600Y100900D02*
X374137Y102437D01*
G01X373077Y99750D02*
X375287Y101960D01*
G01X374137Y102437D02*
Y103415D01*
G01X375287Y101960D02*
Y103892D01*
G01X374137Y103415D02*
X373487Y104065D01*
G01X375287Y103892D02*
X373964Y105215D01*
G01X373487Y104065D02*
X367644D01*
G01X373964Y105215D02*
X368121D01*
G01X367644Y104065D02*
X366321Y105388D01*
G01X368121Y105215D02*
X367471Y105865D01*
G01X366321Y105388D02*
Y107692D01*
G01X367471Y105865D02*
Y107215D01*
G01X366321Y107692D02*
X367644Y109015D01*
G01X367471Y107215D02*
X368121Y107865D01*
G01X367644Y109015D02*
X373487D01*
G01X368121Y107865D02*
X373964D01*
G01X373487Y109015D02*
X374137Y109665D01*
G01X373964Y107865D02*
X375287Y109188D01*
G01X374137Y109665D02*
Y140732D01*
G01X375287Y109188D02*
Y127696D01*
G01X367867Y184533D02*
Y119877D01*
G01X369017Y184533D02*
Y119400D01*
G01X367867Y119877D02*
X361803Y113813D01*
G01D02*
X359467Y111477D01*
G01X369017Y119400D02*
X360617Y111000D01*
G01X359467Y111477D02*
Y94878D01*
G01X360617Y111000D02*
Y103689D01*
G01X359467Y111477D02*
Y94878D01*
G01X360617Y103689D02*
Y95355D01*
G01D02*
X361017Y94955D01*
G01X378422Y106505D02*
Y181266D01*
G01X377272Y116996D02*
Y181268D01*
G01X376190Y98179D02*
Y100022D01*
G01X377340Y99545D02*
X378422Y100627D01*
G01X376190Y100022D02*
X377272Y101104D01*
G01X378422Y100627D02*
Y106505D01*
G01X377272Y101104D02*
Y105839D01*
G01X378422Y106505D02*
Y181266D01*
G01X377272Y108017D02*
Y116996D01*
G01X372152Y182706D02*
Y116911D01*
G01X371002Y182686D02*
Y117388D01*
G01X372152Y116911D02*
X370193Y114952D01*
G01X371002Y117388D02*
X369516Y115902D01*
G01X372152Y116911D02*
X370193Y114952D01*
G01X369516Y115902D02*
X368823D01*
G01X370193Y114952D02*
X364336Y109095D01*
G01X367647Y114033D02*
X363186Y109572D01*
G01D02*
Y108014D01*
G01D02*
Y102731D01*
G01Y100263D02*
Y98838D01*
G01X375287Y183105D02*
Y127696D01*
G01X374137Y183105D02*
Y140732D01*
G01X373111Y95567D02*
X368185D01*
G01D02*
X367535Y96217D01*
G01D02*
Y99525D01*
G01X366385Y95740D02*
Y100002D01*
G01X367535Y99525D02*
X368185Y100175D01*
G01X366385Y100002D02*
X367708Y101325D01*
G01X368185Y100175D02*
X369815D01*
G01X367708Y101325D02*
X370292D01*
G01X369815Y100175D02*
X370240Y99750D01*
G01X370292Y101325D02*
X370717Y100900D01*
G01X370240Y99750D02*
X373077D01*
G01X370717Y100900D02*
X372600D01*
G01X373077Y99750D02*
X375287Y101960D01*
G01X372600Y100900D02*
X374137Y102437D01*
G01X375287Y101960D02*
Y103892D01*
G01X374137Y102437D02*
Y103415D01*
G01X375287Y103892D02*
X373964Y105215D01*
G01X374137Y103415D02*
X373487Y104065D01*
G01X373964Y105215D02*
X368121D01*
G01X373487Y104065D02*
X367644D01*
G01X368121Y105215D02*
X367471Y105865D01*
G01X367644Y104065D02*
X366321Y105388D01*
G01X367471Y105865D02*
Y107215D01*
G01X366321Y105388D02*
Y107692D01*
G01X367471Y107215D02*
X368121Y107865D01*
G01X366321Y107692D02*
X367644Y109015D01*
G01X368121Y107865D02*
X373964D01*
G01X367644Y109015D02*
X373487D01*
G01X373964Y107865D02*
X375287Y109188D01*
G01X373487Y109015D02*
X374137Y109665D01*
G01X375287Y109188D02*
Y127696D01*
G01X374137Y109665D02*
Y140732D01*
G01X369017Y184533D02*
Y119400D01*
G01X367867Y184533D02*
Y119877D01*
G01X369017Y119400D02*
X360617Y111000D01*
G01X367867Y119877D02*
X361803Y113813D01*
G01X369017Y119400D02*
X360617Y111000D01*
G01X361803Y113813D02*
X359467Y111477D01*
G01X360617Y111000D02*
Y103689D01*
G01D02*
Y95355D01*
G01X359467Y111477D02*
Y94878D01*
G01X360617Y95355D02*
X361017Y94955D01*
G01X377272Y116996D02*
Y181268D01*
G01Y108017D02*
Y116996D01*
G01X378422Y106505D02*
Y181266D01*
G01X376190Y98179D02*
Y100022D01*
G01D02*
X377272Y101104D01*
G01X377340Y99545D02*
X378422Y100627D01*
G01X377272Y101104D02*
Y105839D01*
G01X378422Y100627D02*
Y106505D01*
G01X371002Y182686D02*
Y117388D01*
G01X372152Y182706D02*
Y116911D01*
G01X371002Y117388D02*
X369516Y115902D01*
G01D02*
X368823D01*
G01X372152Y116911D02*
X370193Y114952D01*
G01X367647Y114033D02*
X363186Y109572D01*
G01X370193Y114952D02*
X364336Y109095D01*
G01X363186Y109572D02*
Y108014D01*
G01D02*
Y102731D01*
G01Y100263D02*
Y98838D01*
G01X374137Y183105D02*
Y140732D01*
G01X375287Y183105D02*
Y127696D01*
G01X373111Y95567D02*
X368185D01*
G01D02*
X367535Y96217D01*
G01X366385Y95740D02*
Y100002D01*
G01X367535Y96217D02*
Y99525D01*
G01X366385Y100002D02*
X367708Y101325D01*
G01X367535Y99525D02*
X368185Y100175D01*
G01X367708Y101325D02*
X370292D01*
G01X368185Y100175D02*
X369815D01*
G01X370292Y101325D02*
X370717Y100900D01*
G01X369815Y100175D02*
X370240Y99750D01*
G01X370717Y100900D02*
X372600D01*
G01X370240Y99750D02*
X373077D01*
G01X372600Y100900D02*
X374137Y102437D01*
G01X373077Y99750D02*
X375287Y101960D01*
G01X374137Y102437D02*
Y103415D01*
G01X375287Y101960D02*
Y103892D01*
G01X374137Y103415D02*
X373487Y104065D01*
G01X375287Y103892D02*
X373964Y105215D01*
G01X373487Y104065D02*
X367644D01*
G01X373964Y105215D02*
X368121D01*
G01X367644Y104065D02*
X366321Y105388D01*
G01X368121Y105215D02*
X367471Y105865D01*
G01X366321Y105388D02*
Y107692D01*
G01X367471Y105865D02*
Y107215D01*
G01X366321Y107692D02*
X367644Y109015D01*
G01X367471Y107215D02*
X368121Y107865D01*
G01X367644Y109015D02*
X373487D01*
G01X368121Y107865D02*
X373964D01*
G01X373487Y109015D02*
X374137Y109665D01*
G01X373964Y107865D02*
X375287Y109188D01*
G01X374137Y109665D02*
Y140732D01*
G01X375287Y109188D02*
Y127696D01*
G01X367867Y184533D02*
Y119877D01*
G01X369017Y184533D02*
Y119400D01*
G01X367867Y119877D02*
X361803Y113813D01*
G01D02*
X359467Y111477D01*
G01X369017Y119400D02*
X360617Y111000D01*
G01X359467Y111477D02*
Y94878D01*
G01X360617Y111000D02*
Y103689D01*
G01X359467Y111477D02*
Y94878D01*
G01X360617Y103689D02*
Y95355D01*
G01D02*
X361017Y94955D01*
G01X378422Y106505D02*
Y181266D01*
G01X377272Y116996D02*
Y181268D01*
G01X376190Y98179D02*
Y100022D01*
G01X377340Y99545D02*
X378422Y100627D01*
G01X376190Y100022D02*
X377272Y101104D01*
G01X378422Y100627D02*
Y106505D01*
G01X377272Y101104D02*
Y105839D01*
G01X378422Y106505D02*
Y181266D01*
G01X377272Y108017D02*
Y116996D01*
G01X372152Y182706D02*
Y116911D01*
G01X371002Y182686D02*
Y117388D01*
G01X372152Y116911D02*
X370193Y114952D01*
G01X371002Y117388D02*
X369516Y115902D01*
G01X372152Y116911D02*
X370193Y114952D01*
G01X369516Y115902D02*
X368823D01*
G01X370193Y114952D02*
X364336Y109095D01*
G01X367647Y114033D02*
X363186Y109572D01*
G01D02*
Y108014D01*
G01D02*
Y102731D01*
G01Y100263D02*
Y98838D01*
G01X375287Y183105D02*
Y127696D01*
G01X374137Y183105D02*
Y140732D01*
G01X373111Y95567D02*
X368185D01*
G01D02*
X367535Y96217D01*
G01D02*
Y99525D01*
G01X366385Y95740D02*
Y100002D01*
G01X367535Y99525D02*
X368185Y100175D01*
G01X366385Y100002D02*
X367708Y101325D01*
G01X368185Y100175D02*
X369815D01*
G01X367708Y101325D02*
X370292D01*
G01X369815Y100175D02*
X370240Y99750D01*
G01X370292Y101325D02*
X370717Y100900D01*
G01X370240Y99750D02*
X373077D01*
G01X370717Y100900D02*
X372600D01*
G01X373077Y99750D02*
X375287Y101960D01*
G01X372600Y100900D02*
X374137Y102437D01*
G01X375287Y101960D02*
Y103892D01*
G01X374137Y102437D02*
Y103415D01*
G01X375287Y103892D02*
X373964Y105215D01*
G01X374137Y103415D02*
X373487Y104065D01*
G01X373964Y105215D02*
X368121D01*
G01X373487Y104065D02*
X367644D01*
G01X368121Y105215D02*
X367471Y105865D01*
G01X367644Y104065D02*
X366321Y105388D01*
G01X367471Y105865D02*
Y107215D01*
G01X366321Y105388D02*
Y107692D01*
G01X367471Y107215D02*
X368121Y107865D01*
G01X366321Y107692D02*
X367644Y109015D01*
G01X368121Y107865D02*
X373964D01*
G01X367644Y109015D02*
X373487D01*
G01X373964Y107865D02*
X375287Y109188D01*
G01X373487Y109015D02*
X374137Y109665D01*
G01X375287Y109188D02*
Y127696D01*
G01X374137Y109665D02*
Y140732D01*
G01X369017Y184533D02*
Y119400D01*
G01X367867Y184533D02*
Y119877D01*
G01X369017Y119400D02*
X360617Y111000D01*
G01X367867Y119877D02*
X361803Y113813D01*
G01X369017Y119400D02*
X360617Y111000D01*
G01X361803Y113813D02*
X359467Y111477D01*
G01X360617Y111000D02*
Y103689D01*
G01D02*
Y95355D01*
G01X359467Y111477D02*
Y94878D01*
G01X360617Y95355D02*
X361017Y94955D01*
G01X377149Y464883D02*
Y462175D01*
G01Y410073D02*
Y462175D01*
G01X378299Y410053D02*
Y465360D01*
G01X372042Y469990D02*
X377149Y464883D01*
G01X372042Y469990D02*
X377149Y464883D01*
G01X368888Y464011D02*
X371573Y461326D01*
G01X357442Y473830D02*
X370423Y460849D01*
G01X371573Y461326D02*
Y434333D01*
G01Y431483D02*
Y429533D01*
G01Y426683D02*
Y424733D01*
G01Y421883D02*
Y419933D01*
G01Y417083D02*
Y410262D01*
G01X370423Y460849D02*
Y410490D01*
G01X380350Y453103D02*
Y467221D01*
G01Y410133D02*
Y453103D01*
G01X381500Y410133D02*
Y467698D01*
G01X375160Y410161D02*
Y463771D01*
G01X374010Y410158D02*
Y435094D01*
G01X375160Y410161D02*
Y463771D01*
G01X374010Y437844D02*
Y439794D01*
G01X375160Y410161D02*
Y463771D01*
G01X374010Y442544D02*
Y444494D01*
G01X375160Y410161D02*
Y463771D01*
G01X374010Y447244D02*
Y449194D01*
G01X375160Y410161D02*
Y463771D01*
G01X374010Y451944D02*
Y453894D01*
G01X375160Y410161D02*
Y463771D01*
G01X374010Y456644D02*
Y458594D01*
G01X375160Y410161D02*
Y463771D01*
G01X374010Y461344D02*
Y463294D01*
G01X375160Y463771D02*
X362967Y475964D01*
G01X374010Y463294D02*
X371808Y465496D01*
G01X375160Y463771D02*
X362967Y475964D01*
G01X375160Y463771D02*
X362967Y475964D01*
G01X375160Y463771D02*
X362967Y475964D01*
G01X372042Y469990D02*
X377149Y464883D01*
G01X378299Y410053D02*
Y465360D01*
G01X377149Y464883D02*
Y462175D01*
G01X378299Y410053D02*
Y465360D01*
G01X377149Y410073D02*
Y462175D01*
G01X357442Y473830D02*
X370423Y460849D01*
G01X357442Y473830D02*
X370423Y460849D01*
G01X357442Y473830D02*
X370423Y460849D01*
G01X357442Y473830D02*
X370423Y460849D01*
G01X368888Y464011D02*
X371573Y461326D01*
G01X370423Y460849D02*
Y410490D01*
G01X371573Y461326D02*
Y434333D01*
G01X370423Y460849D02*
Y410490D01*
G01X371573Y431483D02*
Y429533D01*
G01X370423Y460849D02*
Y410490D01*
G01X371573Y426683D02*
Y424733D01*
G01X370423Y460849D02*
Y410490D01*
G01X371573Y421883D02*
Y419933D01*
G01X370423Y460849D02*
Y410490D01*
G01X371573Y417083D02*
Y410262D01*
G01X381500Y410133D02*
Y467698D01*
G01X380350Y453103D02*
Y467221D01*
G01X381500Y410133D02*
Y467698D01*
G01X380350Y410133D02*
Y453103D01*
G01X374010Y410158D02*
Y435094D01*
G01Y437844D02*
Y439794D01*
G01Y442544D02*
Y444494D01*
G01Y447244D02*
Y449194D01*
G01Y451944D02*
Y453894D01*
G01Y456644D02*
Y458594D01*
G01Y461344D02*
Y463294D01*
G01X375160Y410161D02*
Y463771D01*
G01X374010Y463294D02*
X371808Y465496D01*
G01X375160Y463771D02*
X362967Y475964D01*
G01X372042Y469990D02*
X377149Y464883D01*
G01X378299Y410053D02*
Y465360D01*
G01X377149Y464883D02*
Y462175D01*
G01X378299Y410053D02*
Y465360D01*
G01X377149Y410073D02*
Y462175D01*
G01X381500Y410133D02*
Y467698D01*
G01X380350Y453103D02*
Y467221D01*
G01X381500Y410133D02*
Y467698D01*
G01X380350Y410133D02*
Y453103D01*
G01X377149Y464883D02*
Y462175D01*
G01Y410073D02*
Y462175D01*
G01X378299Y410053D02*
Y465360D01*
G01X372042Y469990D02*
X377149Y464883D01*
G01X372042Y469990D02*
X377149Y464883D01*
G01X380350Y453103D02*
Y467221D01*
G01Y410133D02*
Y453103D01*
G01X381500Y410133D02*
Y467698D01*
G01X371631Y512987D02*
Y488356D01*
G01X372781Y491333D02*
Y494182D01*
G01X371631Y512987D02*
Y488356D01*
G01X372781Y496820D02*
Y498878D01*
G01X371631Y512987D02*
Y488356D01*
G01X372781Y501516D02*
Y503539D01*
G01X371631Y512987D02*
Y488356D01*
G01X372781Y506247D02*
Y513464D01*
G01X366337Y518281D02*
X371631Y512987D01*
G01X372781Y513464D02*
X366814Y519431D01*
G01X364539Y518281D02*
X366337D01*
G01X366814Y519431D02*
X365016D01*
G01X363415Y519405D02*
X364539Y518281D01*
G01X365016Y519431D02*
X364565Y519882D01*
G01X378299Y465360D02*
X376460Y467199D01*
G01X374624Y469035D02*
X373192Y470467D01*
G01X372042Y474099D02*
Y469990D01*
G01X373192Y470467D02*
Y474576D01*
G01X371392Y474749D02*
X372042Y474099D01*
G01X373192Y474576D02*
X371869Y475899D01*
G01X367299Y474749D02*
X371392D01*
G01X371869Y475899D02*
X367776D01*
G01X365976Y476072D02*
X367299Y474749D01*
G01X367776Y475899D02*
X367126Y476549D01*
G01X365976Y478376D02*
Y476072D01*
G01X367126Y476549D02*
Y477899D01*
G01X367299Y479699D02*
X365976Y478376D01*
G01X367126Y477899D02*
X367776Y478549D01*
G01X374043Y479699D02*
X367299D01*
G01X367776Y478549D02*
X374520D01*
G01X374693Y480349D02*
X374043Y479699D01*
G01X374520Y478549D02*
X375843Y479872D01*
G01X374693Y481699D02*
Y480349D01*
G01X375843Y479872D02*
Y482176D01*
G01X374043Y482349D02*
X374693Y481699D01*
G01X375843Y482176D02*
X374520Y483499D01*
G01X367299Y482349D02*
X374043D01*
G01X374520Y483499D02*
X367776D01*
G01X365976Y483672D02*
X367299Y482349D01*
G01X367776Y483499D02*
X367126Y484149D01*
G01X365976Y485976D02*
Y483672D01*
G01X367126Y484149D02*
Y485499D01*
G01X367299Y487299D02*
X365976Y485976D01*
G01X367126Y485499D02*
X367776Y486149D01*
G01X370574Y487299D02*
X367299D01*
G01X367776Y486149D02*
X371051D01*
G01X371631Y488356D02*
X370574Y487299D01*
G01X371051Y486149D02*
X372781Y487879D01*
G01X371631Y512987D02*
Y488356D01*
G01X372781Y487879D02*
Y491333D01*
G01X362199Y515757D02*
Y516315D01*
G01X363349Y516068D02*
Y516792D01*
G01X362199Y516315D02*
X361426Y517088D01*
G01X363349Y516792D02*
X361903Y518238D01*
G01X361426Y517088D02*
X357956D01*
G01X361903Y518238D02*
X357479D01*
G01X357956Y517088D02*
X357222Y516354D01*
G01X357479Y518238D02*
X356072Y516831D01*
G01X357222Y516354D02*
Y514491D01*
G01X356072Y516831D02*
Y514014D01*
G01X357501Y514212D02*
Y511448D01*
G01X356351Y513735D02*
Y511925D01*
G01X357501Y511448D02*
X357117Y511064D01*
G01X356351Y511925D02*
X355967Y511541D01*
G01X357117Y511064D02*
Y508170D01*
G01X355967Y511541D02*
Y507693D01*
G01X357117Y508170D02*
X358592Y506695D01*
G01X355967Y507693D02*
X357442Y506218D01*
G01X358592Y506695D02*
Y505985D01*
G01Y502951D02*
Y501372D01*
G01Y498426D02*
Y496476D01*
G01Y493530D02*
Y491580D01*
G01Y488634D02*
Y486684D01*
G01Y483738D02*
Y481788D01*
G01Y478842D02*
Y477399D01*
G01Y475483D02*
Y474307D01*
G01X357442Y506218D02*
Y473830D01*
G01X358592Y474307D02*
X359970Y472929D01*
G01X362054Y470845D02*
X363476Y469423D01*
G01X365445Y467454D02*
X366965Y465934D01*
G01X377992Y523572D02*
X376506Y525058D01*
G01X369537Y533654D02*
X379142Y524049D01*
G01X377992Y515200D02*
Y523572D01*
G01X379142Y524049D02*
Y514723D01*
G01X376042Y513250D02*
X377992Y515200D01*
G01X379142Y514723D02*
X377192Y512773D01*
G01X376042Y501700D02*
Y503650D01*
G01Y506500D02*
Y508450D01*
G01Y511300D02*
Y513250D01*
G01X377192Y512773D02*
Y498249D01*
G01X380350Y467221D02*
X378011Y469560D01*
G01X381500Y467698D02*
X379161Y470037D01*
G01X378011Y469560D02*
Y473044D01*
G01Y475990D02*
Y484101D01*
G01X379161Y470037D02*
Y484578D01*
G01X378011Y484101D02*
X376042Y486070D01*
G01X379161Y484578D02*
X377192Y486547D01*
G01X376042Y486070D02*
Y498850D01*
G01X377192Y486547D02*
Y498249D01*
G01X369977Y467327D02*
X368705Y468599D01*
G01X366729Y470575D02*
X365270Y472034D01*
G01X363222Y474082D02*
X361817Y475487D01*
G01X362967Y475964D02*
Y488570D01*
G01X361817Y475487D02*
Y479255D01*
G01X362967Y475964D02*
Y488570D01*
G01X361817Y482201D02*
Y484151D01*
G01X362967Y475964D02*
Y488570D01*
G01X361817Y487097D02*
Y489047D01*
G01X362967Y488570D02*
X363617Y489220D01*
G01X361817Y489047D02*
X363140Y490370D01*
G01X363617Y489220D02*
X366765D01*
G01X363140Y490370D02*
X366288D01*
G01X366765Y489220D02*
X368088Y490543D01*
G01X366288Y490370D02*
X366938Y491020D01*
G01X368088Y490543D02*
Y492847D01*
G01X366938Y491020D02*
Y492370D01*
G01X368088Y492847D02*
X366765Y494170D01*
G01X366938Y492370D02*
X366288Y493020D01*
G01X366765Y494170D02*
X363617D01*
G01X366288Y493020D02*
X363140D01*
G01X363617Y494170D02*
X362967Y494820D01*
G01X363140Y493020D02*
X361817Y494343D01*
G01X362967Y494820D02*
Y496170D01*
G01X361817Y494343D02*
Y496647D01*
G01X362967Y496170D02*
X363617Y496820D01*
G01X361817Y496647D02*
X363140Y497970D01*
G01X363617Y496820D02*
X366765D01*
G01X363140Y497970D02*
X366288D01*
G01X366765Y496820D02*
X368088Y498143D01*
G01X366288Y497970D02*
X366938Y498620D01*
G01X368088Y498143D02*
Y500447D01*
G01X366938Y498620D02*
Y499970D01*
G01X368088Y500447D02*
X366765Y501770D01*
G01X366938Y499970D02*
X366288Y500620D01*
G01X366765Y501770D02*
X363617D01*
G01X366288Y500620D02*
X363140D01*
G01X363617Y501770D02*
X362967Y502420D01*
G01X363140Y500620D02*
X361817Y501943D01*
G01X362967Y502420D02*
Y504769D01*
G01X361817Y501943D02*
Y505246D01*
G01X362967Y504769D02*
X364053Y505855D01*
G01X361817Y505246D02*
X363576Y507005D01*
G01X364053Y505855D02*
X367619D01*
G01X363576Y507005D02*
X367142D01*
G01X367619Y505855D02*
X369880Y508116D01*
G01X367142Y507005D02*
X368730Y508593D01*
G01X369880Y508116D02*
Y511303D01*
G01X368730Y508593D02*
Y510826D01*
G01X369880Y511303D02*
X367883Y513300D01*
G01X368730Y510826D02*
X367406Y512150D01*
G01X367883Y513300D02*
X363533D01*
G01X367406Y512150D02*
X364010D01*
G01X363533Y513300D02*
X362337Y512104D01*
G01X364010Y512150D02*
X363487Y511627D01*
G01X362337Y512104D02*
Y510933D01*
G01X363487Y511627D02*
Y510892D01*
G01X365016Y519431D02*
X364565Y519882D01*
G01X363415Y519405D02*
X364539Y518281D01*
G01X366814Y519431D02*
X365016D01*
G01X364539Y518281D02*
X366337D01*
G01X372781Y513464D02*
X366814Y519431D01*
G01X366337Y518281D02*
X371631Y512987D01*
G01X372781Y491333D02*
Y494182D01*
G01Y496820D02*
Y498878D01*
G01Y501516D02*
Y503539D01*
G01Y506247D02*
Y513464D01*
G01Y487879D02*
Y491333D01*
G01X371631Y512987D02*
Y488356D01*
G01X371051Y486149D02*
X372781Y487879D01*
G01X371631Y488356D02*
X370574Y487299D01*
G01X367776Y486149D02*
X371051D01*
G01X370574Y487299D02*
X367299D01*
G01X367126Y485499D02*
X367776Y486149D01*
G01X367299Y487299D02*
X365976Y485976D01*
G01X367126Y484149D02*
Y485499D01*
G01X365976Y485976D02*
Y483672D01*
G01X367776Y483499D02*
X367126Y484149D01*
G01X365976Y483672D02*
X367299Y482349D01*
G01X374520Y483499D02*
X367776D01*
G01X367299Y482349D02*
X374043D01*
G01X375843Y482176D02*
X374520Y483499D01*
G01X374043Y482349D02*
X374693Y481699D01*
G01X375843Y479872D02*
Y482176D01*
G01X374693Y481699D02*
Y480349D01*
G01X374520Y478549D02*
X375843Y479872D01*
G01X374693Y480349D02*
X374043Y479699D01*
G01X367776Y478549D02*
X374520D01*
G01X374043Y479699D02*
X367299D01*
G01X367126Y477899D02*
X367776Y478549D01*
G01X367299Y479699D02*
X365976Y478376D01*
G01X367126Y476549D02*
Y477899D01*
G01X365976Y478376D02*
Y476072D01*
G01X367776Y475899D02*
X367126Y476549D01*
G01X365976Y476072D02*
X367299Y474749D01*
G01X371869Y475899D02*
X367776D01*
G01X367299Y474749D02*
X371392D01*
G01X373192Y474576D02*
X371869Y475899D01*
G01X371392Y474749D02*
X372042Y474099D01*
G01X373192Y470467D02*
Y474576D01*
G01X372042Y474099D02*
Y469990D01*
G01X378299Y465360D02*
X376460Y467199D01*
G01X374624Y469035D02*
X373192Y470467D01*
G01X363349Y516068D02*
Y516792D01*
G01X362199Y515757D02*
Y516315D01*
G01X363349Y516792D02*
X361903Y518238D01*
G01X362199Y516315D02*
X361426Y517088D01*
G01X361903Y518238D02*
X357479D01*
G01X361426Y517088D02*
X357956D01*
G01X357479Y518238D02*
X356072Y516831D01*
G01X357956Y517088D02*
X357222Y516354D01*
G01X356072Y516831D02*
Y514014D01*
G01X357222Y516354D02*
Y514491D01*
G01X356351Y513735D02*
Y511925D01*
G01X357501Y514212D02*
Y511448D01*
G01X356351Y511925D02*
X355967Y511541D01*
G01X357501Y511448D02*
X357117Y511064D01*
G01X355967Y511541D02*
Y507693D01*
G01X357117Y511064D02*
Y508170D01*
G01X355967Y507693D02*
X357442Y506218D01*
G01X357117Y508170D02*
X358592Y506695D01*
G01X357442Y506218D02*
Y473830D01*
G01X358592Y506695D02*
Y505985D01*
G01X357442Y506218D02*
Y473830D01*
G01X358592Y502951D02*
Y501372D01*
G01X357442Y506218D02*
Y473830D01*
G01X358592Y498426D02*
Y496476D01*
G01X357442Y506218D02*
Y473830D01*
G01X358592Y493530D02*
Y491580D01*
G01X357442Y506218D02*
Y473830D01*
G01X358592Y488634D02*
Y486684D01*
G01X357442Y506218D02*
Y473830D01*
G01X358592Y483738D02*
Y481788D01*
G01X357442Y506218D02*
Y473830D01*
G01X358592Y478842D02*
Y477399D01*
G01X357442Y506218D02*
Y473830D01*
G01X358592Y475483D02*
Y474307D01*
G01D02*
X359970Y472929D01*
G01X362054Y470845D02*
X363476Y469423D01*
G01X365445Y467454D02*
X366965Y465934D01*
G01X381500Y467698D02*
X379161Y470037D01*
G01X380350Y467221D02*
X378011Y469560D01*
G01X379161Y470037D02*
Y484578D01*
G01X378011Y469560D02*
Y473044D01*
G01X379161Y470037D02*
Y484578D01*
G01X378011Y475990D02*
Y484101D01*
G01X379161Y484578D02*
X377192Y486547D01*
G01X378011Y484101D02*
X376042Y486070D01*
G01X377192Y486547D02*
Y498249D01*
G01X376042Y486070D02*
Y498850D01*
G01X377192Y512773D02*
Y498249D01*
G01X376042Y501700D02*
Y503650D01*
G01X377192Y512773D02*
Y498249D01*
G01X376042Y506500D02*
Y508450D01*
G01X377192Y512773D02*
Y498249D01*
G01X376042Y511300D02*
Y513250D01*
G01X379142Y514723D02*
X377192Y512773D01*
G01X376042Y513250D02*
X377992Y515200D01*
G01X379142Y524049D02*
Y514723D01*
G01X377992Y515200D02*
Y523572D01*
G01X369537Y533654D02*
X379142Y524049D01*
G01X377992Y523572D02*
X376506Y525058D01*
G01X369537Y533654D02*
X379142Y524049D01*
G01X369537Y533654D02*
X379142Y524049D01*
G01X369977Y467327D02*
X368705Y468599D01*
G01X366729Y470575D02*
X365270Y472034D01*
G01X363222Y474082D02*
X361817Y475487D01*
G01D02*
Y479255D01*
G01Y482201D02*
Y484151D01*
G01Y487097D02*
Y489047D01*
G01X362967Y475964D02*
Y488570D01*
G01X361817Y489047D02*
X363140Y490370D01*
G01X362967Y488570D02*
X363617Y489220D01*
G01X363140Y490370D02*
X366288D01*
G01X363617Y489220D02*
X366765D01*
G01X366288Y490370D02*
X366938Y491020D01*
G01X366765Y489220D02*
X368088Y490543D01*
G01X366938Y491020D02*
Y492370D01*
G01X368088Y490543D02*
Y492847D01*
G01X366938Y492370D02*
X366288Y493020D01*
G01X368088Y492847D02*
X366765Y494170D01*
G01X366288Y493020D02*
X363140D01*
G01X366765Y494170D02*
X363617D01*
G01X363140Y493020D02*
X361817Y494343D01*
G01X363617Y494170D02*
X362967Y494820D01*
G01X361817Y494343D02*
Y496647D01*
G01X362967Y494820D02*
Y496170D01*
G01X361817Y496647D02*
X363140Y497970D01*
G01X362967Y496170D02*
X363617Y496820D01*
G01X363140Y497970D02*
X366288D01*
G01X363617Y496820D02*
X366765D01*
G01X366288Y497970D02*
X366938Y498620D01*
G01X366765Y496820D02*
X368088Y498143D01*
G01X366938Y498620D02*
Y499970D01*
G01X368088Y498143D02*
Y500447D01*
G01X366938Y499970D02*
X366288Y500620D01*
G01X368088Y500447D02*
X366765Y501770D01*
G01X366288Y500620D02*
X363140D01*
G01X366765Y501770D02*
X363617D01*
G01X363140Y500620D02*
X361817Y501943D01*
G01X363617Y501770D02*
X362967Y502420D01*
G01X361817Y501943D02*
Y505246D01*
G01X362967Y502420D02*
Y504769D01*
G01X361817Y505246D02*
X363576Y507005D01*
G01X362967Y504769D02*
X364053Y505855D01*
G01X363576Y507005D02*
X367142D01*
G01X364053Y505855D02*
X367619D01*
G01X367142Y507005D02*
X368730Y508593D01*
G01X367619Y505855D02*
X369880Y508116D01*
G01X368730Y508593D02*
Y510826D01*
G01X369880Y508116D02*
Y511303D01*
G01X368730Y510826D02*
X367406Y512150D01*
G01X369880Y511303D02*
X367883Y513300D01*
G01X367406Y512150D02*
X364010D01*
G01X367883Y513300D02*
X363533D01*
G01X364010Y512150D02*
X363487Y511627D01*
G01X363533Y513300D02*
X362337Y512104D01*
G01X363487Y511627D02*
Y510892D01*
G01X362337Y512104D02*
Y510933D01*
G01X365016Y519431D02*
X364565Y519882D01*
G01X363415Y519405D02*
X364539Y518281D01*
G01X366814Y519431D02*
X365016D01*
G01X364539Y518281D02*
X366337D01*
G01X372781Y513464D02*
X366814Y519431D01*
G01X366337Y518281D02*
X371631Y512987D01*
G01X372781Y491333D02*
Y494182D01*
G01Y496820D02*
Y498878D01*
G01Y501516D02*
Y503539D01*
G01Y506247D02*
Y513464D01*
G01Y487879D02*
Y491333D01*
G01X371631Y512987D02*
Y488356D01*
G01X371051Y486149D02*
X372781Y487879D01*
G01X371631Y488356D02*
X370574Y487299D01*
G01X367776Y486149D02*
X371051D01*
G01X370574Y487299D02*
X367299D01*
G01X367126Y485499D02*
X367776Y486149D01*
G01X367299Y487299D02*
X365976Y485976D01*
G01X367126Y484149D02*
Y485499D01*
G01X365976Y485976D02*
Y483672D01*
G01X367776Y483499D02*
X367126Y484149D01*
G01X365976Y483672D02*
X367299Y482349D01*
G01X374520Y483499D02*
X367776D01*
G01X367299Y482349D02*
X374043D01*
G01X375843Y482176D02*
X374520Y483499D01*
G01X374043Y482349D02*
X374693Y481699D01*
G01X375843Y479872D02*
Y482176D01*
G01X374693Y481699D02*
Y480349D01*
G01X374520Y478549D02*
X375843Y479872D01*
G01X374693Y480349D02*
X374043Y479699D01*
G01X367776Y478549D02*
X374520D01*
G01X374043Y479699D02*
X367299D01*
G01X367126Y477899D02*
X367776Y478549D01*
G01X367299Y479699D02*
X365976Y478376D01*
G01X367126Y476549D02*
Y477899D01*
G01X365976Y478376D02*
Y476072D01*
G01X367776Y475899D02*
X367126Y476549D01*
G01X365976Y476072D02*
X367299Y474749D01*
G01X371869Y475899D02*
X367776D01*
G01X367299Y474749D02*
X371392D01*
G01X373192Y474576D02*
X371869Y475899D01*
G01X371392Y474749D02*
X372042Y474099D01*
G01X373192Y470467D02*
Y474576D01*
G01X372042Y474099D02*
Y469990D01*
G01X378299Y465360D02*
X376460Y467199D01*
G01X374624Y469035D02*
X373192Y470467D01*
G01X381500Y467698D02*
X379161Y470037D01*
G01X380350Y467221D02*
X378011Y469560D01*
G01X379161Y470037D02*
Y484578D01*
G01X378011Y469560D02*
Y473044D01*
G01X379161Y470037D02*
Y484578D01*
G01X378011Y475990D02*
Y484101D01*
G01X379161Y484578D02*
X377192Y486547D01*
G01X378011Y484101D02*
X376042Y486070D01*
G01X377192Y486547D02*
Y498249D01*
G01X376042Y486070D02*
Y498850D01*
G01X377192Y512773D02*
Y498249D01*
G01X376042Y501700D02*
Y503650D01*
G01X377192Y512773D02*
Y498249D01*
G01X376042Y506500D02*
Y508450D01*
G01X377192Y512773D02*
Y498249D01*
G01X376042Y511300D02*
Y513250D01*
G01X379142Y514723D02*
X377192Y512773D01*
G01X376042Y513250D02*
X377992Y515200D01*
G01X379142Y524049D02*
Y514723D01*
G01X377992Y515200D02*
Y523572D01*
G01X369537Y533654D02*
X379142Y524049D01*
G01X377992Y523572D02*
X376506Y525058D01*
G01X369537Y533654D02*
X379142Y524049D01*
G01X369537Y533654D02*
X379142Y524049D01*
G01X371631Y512987D02*
Y488356D01*
G01X372781Y491333D02*
Y494182D01*
G01X371631Y512987D02*
Y488356D01*
G01X372781Y496820D02*
Y498878D01*
G01X371631Y512987D02*
Y488356D01*
G01X372781Y501516D02*
Y503539D01*
G01X371631Y512987D02*
Y488356D01*
G01X372781Y506247D02*
Y513464D01*
G01X366337Y518281D02*
X371631Y512987D01*
G01X372781Y513464D02*
X366814Y519431D01*
G01X364539Y518281D02*
X366337D01*
G01X366814Y519431D02*
X365016D01*
G01X363415Y519405D02*
X364539Y518281D01*
G01X365016Y519431D02*
X364565Y519882D01*
G01X378299Y465360D02*
X376460Y467199D01*
G01X374624Y469035D02*
X373192Y470467D01*
G01X372042Y474099D02*
Y469990D01*
G01X373192Y470467D02*
Y474576D01*
G01X371392Y474749D02*
X372042Y474099D01*
G01X373192Y474576D02*
X371869Y475899D01*
G01X367299Y474749D02*
X371392D01*
G01X371869Y475899D02*
X367776D01*
G01X365976Y476072D02*
X367299Y474749D01*
G01X367776Y475899D02*
X367126Y476549D01*
G01X365976Y478376D02*
Y476072D01*
G01X367126Y476549D02*
Y477899D01*
G01X367299Y479699D02*
X365976Y478376D01*
G01X367126Y477899D02*
X367776Y478549D01*
G01X374043Y479699D02*
X367299D01*
G01X367776Y478549D02*
X374520D01*
G01X374693Y480349D02*
X374043Y479699D01*
G01X374520Y478549D02*
X375843Y479872D01*
G01X374693Y481699D02*
Y480349D01*
G01X375843Y479872D02*
Y482176D01*
G01X374043Y482349D02*
X374693Y481699D01*
G01X375843Y482176D02*
X374520Y483499D01*
G01X367299Y482349D02*
X374043D01*
G01X374520Y483499D02*
X367776D01*
G01X365976Y483672D02*
X367299Y482349D01*
G01X367776Y483499D02*
X367126Y484149D01*
G01X365976Y485976D02*
Y483672D01*
G01X367126Y484149D02*
Y485499D01*
G01X367299Y487299D02*
X365976Y485976D01*
G01X367126Y485499D02*
X367776Y486149D01*
G01X370574Y487299D02*
X367299D01*
G01X367776Y486149D02*
X371051D01*
G01X371631Y488356D02*
X370574Y487299D01*
G01X371051Y486149D02*
X372781Y487879D01*
G01X371631Y512987D02*
Y488356D01*
G01X372781Y487879D02*
Y491333D01*
G01X377992Y523572D02*
X376506Y525058D01*
G01X369537Y533654D02*
X379142Y524049D01*
G01X377992Y515200D02*
Y523572D01*
G01X379142Y524049D02*
Y514723D01*
G01X376042Y513250D02*
X377992Y515200D01*
G01X379142Y514723D02*
X377192Y512773D01*
G01X376042Y501700D02*
Y503650D01*
G01Y506500D02*
Y508450D01*
G01Y511300D02*
Y513250D01*
G01X377192Y512773D02*
Y498249D01*
G01X380350Y467221D02*
X378011Y469560D01*
G01X381500Y467698D02*
X379161Y470037D01*
G01X378011Y469560D02*
Y473044D01*
G01Y475990D02*
Y484101D01*
G01X379161Y470037D02*
Y484578D01*
G01X378011Y484101D02*
X376042Y486070D01*
G01X379161Y484578D02*
X377192Y486547D01*
G01X376042Y486070D02*
Y498850D01*
G01X377192Y486547D02*
Y498249D01*
G01X362316Y534406D02*
Y536431D01*
G01X363466Y536530D02*
Y534883D01*
G01X364218Y532504D02*
X362316Y534406D01*
G01X363466Y534883D02*
X364695Y533654D01*
G01X369060Y532504D02*
X364218D01*
G01X364695Y533654D02*
X369537D01*
G01X374651Y526913D02*
X372388Y529176D01*
G01X370545Y531019D02*
X369060Y532504D01*
G01X374651Y526913D02*
X372388Y529176D01*
G01X370545Y531019D02*
X369060Y532504D01*
G01X364695Y533654D02*
X369537D01*
G01X369060Y532504D02*
X364218D01*
G01X363466Y534883D02*
X364695Y533654D01*
G01X364218Y532504D02*
X362316Y534406D01*
G01X363466Y536530D02*
Y534883D01*
G01X362316Y534406D02*
Y536431D01*
G01X374651Y526913D02*
X372388Y529176D01*
G01X370545Y531019D02*
X369060Y532504D01*
G01X364695Y533654D02*
X369537D01*
G01X369060Y532504D02*
X364218D01*
G01X363466Y534883D02*
X364695Y533654D01*
G01X364218Y532504D02*
X362316Y534406D01*
G01X363466Y536530D02*
Y534883D01*
G01X362316Y534406D02*
Y536431D01*
G01Y534406D02*
Y536431D01*
G01X363466Y536530D02*
Y534883D01*
G01X364218Y532504D02*
X362316Y534406D01*
G01X363466Y534883D02*
X364695Y533654D01*
G01X369060Y532504D02*
X364218D01*
G01X364695Y533654D02*
X369537D01*
G01X374651Y526913D02*
X372388Y529176D01*
G01X370545Y531019D02*
X369060Y532504D01*
G01X573063Y-46726D02*
X471671D01*
G01X572586Y-47876D02*
X471671D01*
G01X572586D02*
X471671D01*
G01X573063Y-46726D02*
X471671D01*
G01X462142Y95151D02*
X462842Y94451D01*
G01X462142Y95151D02*
X462842Y94451D01*
G01X467262Y96657D02*
X469319Y94600D01*
G01X466112Y96180D02*
X468037Y94255D01*
G01X467262Y96657D02*
X469319Y94600D01*
G01X466112Y96180D02*
X468037Y94255D01*
G01X462142Y95151D02*
X462842Y94451D01*
G01X462142Y95151D02*
X462842Y94451D01*
G01X466112Y96180D02*
X468037Y94255D01*
G01X467262Y96657D02*
X469319Y94600D01*
G01X466112Y96180D02*
X468037Y94255D01*
G01X467262Y96657D02*
X469319Y94600D01*
G01X467262Y96657D02*
X469319Y94600D01*
G01X466112Y96180D02*
X468037Y94255D01*
G01X462142Y95151D02*
X462842Y94451D01*
G01X466112Y96180D02*
X468037Y94255D01*
G01X467262Y96657D02*
X469319Y94600D01*
G01X426093Y158861D02*
Y148508D01*
G01X427243Y158861D02*
Y148985D01*
G01X426093Y148508D02*
X435524Y139077D01*
G01X427243Y148985D02*
X429254Y146974D01*
G01X426093Y148508D02*
X435524Y139077D01*
G01X430669Y145559D02*
X431686Y144542D01*
G01X426093Y148508D02*
X435524Y139077D01*
G01X433101Y143127D02*
X436001Y140227D01*
G01X435524Y139077D02*
X438861D01*
G01X436001Y140227D02*
X439338D01*
G01X438861Y139077D02*
X440339Y137599D01*
G01X439338Y140227D02*
X441489Y138076D01*
G01X440339Y137599D02*
Y136607D01*
G01X441489Y138076D02*
Y136130D01*
G01X440339Y136607D02*
X439999Y136267D01*
G01X441489Y136130D02*
X441149Y135790D01*
G01X439999Y136267D02*
Y134321D01*
G01X441149Y135790D02*
Y134798D01*
G01X439999Y134321D02*
X442148Y132172D01*
G01X441149Y134798D02*
X442625Y133322D01*
G01X442148Y132172D02*
X444094D01*
G01D02*
X444434Y132512D01*
G01X442625Y133322D02*
X443617D01*
G01X444094Y132172D02*
X444434Y132512D01*
G01X443617Y133322D02*
X443957Y133662D01*
G01X444434Y132512D02*
X445426D01*
G01X443957Y133662D02*
X445903D01*
G01X444434Y132512D02*
X445426D01*
G01D02*
X446904Y131034D01*
G01X445903Y133662D02*
X448054Y131511D01*
G01X446904Y131034D02*
Y130042D01*
G01X448054Y131511D02*
Y129565D01*
G01X446904Y130042D02*
X446564Y129702D01*
G01X448054Y129565D02*
X447714Y129225D01*
G01X446564Y129702D02*
Y127756D01*
G01X447714Y129225D02*
Y128233D01*
G01X446564Y127756D02*
X448713Y125607D01*
G01X447714Y128233D02*
X449190Y126757D01*
G01X448713Y125607D02*
X450659D01*
G01X449190Y126757D02*
X450182D01*
G01X450659Y125607D02*
X450999Y125947D01*
G01D02*
X451991D01*
G01X450182Y126757D02*
X450522Y127097D01*
G01X450999Y125947D02*
X451991D01*
G01X450522Y127097D02*
X452468D01*
G01X451991Y125947D02*
X453469Y124469D01*
G01X452468Y127097D02*
X454619Y124946D01*
G01X453469Y124469D02*
Y123477D01*
G01X454619Y124946D02*
Y123000D01*
G01X453469Y123477D02*
X453129Y123137D01*
G01X454619Y123000D02*
X454279Y122660D01*
G01X453129Y123137D02*
Y121191D01*
G01X454279Y122660D02*
Y121668D01*
G01X453129Y121191D02*
X455278Y119042D01*
G01X454279Y121668D02*
X455755Y120192D01*
G01X455278Y119042D02*
X457224D01*
G01D02*
X457564Y119382D01*
G01X455755Y120192D02*
X456747D01*
G01X457224Y119042D02*
X457564Y119382D01*
G01X456747Y120192D02*
X457087Y120532D01*
G01X457564Y119382D02*
X458556D01*
G01X457087Y120532D02*
X459033D01*
G01X457564Y119382D02*
X458556D01*
G01D02*
X460292Y117646D01*
G01X459033Y120532D02*
X461442Y118123D01*
G01X460292Y117646D02*
Y115000D01*
G01D02*
Y111826D01*
G01X461442Y118123D02*
Y111349D01*
G01X460292Y111826D02*
X459492Y111026D01*
G01X461442Y111349D02*
X460642Y110549D01*
G01X459492Y111026D02*
Y108000D01*
G01X460642Y110549D02*
Y108477D01*
G01X459492Y108000D02*
X462142Y105350D01*
G01X460642Y108477D02*
X463292Y105827D01*
G01X462142Y105350D02*
Y95151D01*
G01X463292Y105827D02*
Y95628D01*
G01D02*
X463820Y95100D01*
G01X426093Y158861D02*
Y148508D01*
G01X427243Y158861D02*
Y148985D01*
G01X426093Y148508D02*
X435524Y139077D01*
G01X427243Y148985D02*
X429254Y146974D01*
G01X426093Y148508D02*
X435524Y139077D01*
G01X430669Y145559D02*
X431686Y144542D01*
G01X426093Y148508D02*
X435524Y139077D01*
G01X433101Y143127D02*
X436001Y140227D01*
G01X435524Y139077D02*
X438861D01*
G01X436001Y140227D02*
X439338D01*
G01X438861Y139077D02*
X440339Y137599D01*
G01X439338Y140227D02*
X441489Y138076D01*
G01X440339Y137599D02*
Y136607D01*
G01X441489Y138076D02*
Y136130D01*
G01X440339Y136607D02*
X439999Y136267D01*
G01X441489Y136130D02*
X441149Y135790D01*
G01X439999Y136267D02*
Y134321D01*
G01X441149Y135790D02*
Y134798D01*
G01X439999Y134321D02*
X442148Y132172D01*
G01X441149Y134798D02*
X442625Y133322D01*
G01X442148Y132172D02*
X444094D01*
G01D02*
X444434Y132512D01*
G01X442625Y133322D02*
X443617D01*
G01X444094Y132172D02*
X444434Y132512D01*
G01X443617Y133322D02*
X443957Y133662D01*
G01X444434Y132512D02*
X445426D01*
G01X443957Y133662D02*
X445903D01*
G01X444434Y132512D02*
X445426D01*
G01D02*
X446904Y131034D01*
G01X445903Y133662D02*
X448054Y131511D01*
G01X446904Y131034D02*
Y130042D01*
G01X448054Y131511D02*
Y129565D01*
G01X446904Y130042D02*
X446564Y129702D01*
G01X448054Y129565D02*
X447714Y129225D01*
G01X446564Y129702D02*
Y127756D01*
G01X447714Y129225D02*
Y128233D01*
G01X446564Y127756D02*
X448713Y125607D01*
G01X447714Y128233D02*
X449190Y126757D01*
G01X448713Y125607D02*
X450659D01*
G01X449190Y126757D02*
X450182D01*
G01X450659Y125607D02*
X450999Y125947D01*
G01D02*
X451991D01*
G01X450182Y126757D02*
X450522Y127097D01*
G01X450999Y125947D02*
X451991D01*
G01X450522Y127097D02*
X452468D01*
G01X451991Y125947D02*
X453469Y124469D01*
G01X452468Y127097D02*
X454619Y124946D01*
G01X453469Y124469D02*
Y123477D01*
G01X454619Y124946D02*
Y123000D01*
G01X453469Y123477D02*
X453129Y123137D01*
G01X454619Y123000D02*
X454279Y122660D01*
G01X453129Y123137D02*
Y121191D01*
G01X454279Y122660D02*
Y121668D01*
G01X453129Y121191D02*
X455278Y119042D01*
G01X454279Y121668D02*
X455755Y120192D01*
G01X455278Y119042D02*
X457224D01*
G01D02*
X457564Y119382D01*
G01X455755Y120192D02*
X456747D01*
G01X457224Y119042D02*
X457564Y119382D01*
G01X456747Y120192D02*
X457087Y120532D01*
G01X457564Y119382D02*
X458556D01*
G01X457087Y120532D02*
X459033D01*
G01X457564Y119382D02*
X458556D01*
G01D02*
X460292Y117646D01*
G01X459033Y120532D02*
X461442Y118123D01*
G01X460292Y117646D02*
Y115000D01*
G01D02*
Y111826D01*
G01X461442Y118123D02*
Y111349D01*
G01X460292Y111826D02*
X459492Y111026D01*
G01X461442Y111349D02*
X460642Y110549D01*
G01X459492Y111026D02*
Y108000D01*
G01X460642Y110549D02*
Y108477D01*
G01X459492Y108000D02*
X462142Y105350D01*
G01X460642Y108477D02*
X463292Y105827D01*
G01X462142Y105350D02*
Y95151D01*
G01X463292Y105827D02*
Y95628D01*
G01D02*
X463820Y95100D01*
G01X430912Y158726D02*
Y154135D01*
G01X429762Y158760D02*
Y153658D01*
G01X430912Y154135D02*
X467262Y117785D01*
G01X429762Y153658D02*
X466112Y117308D01*
G01X467262Y117785D02*
Y109000D01*
G01X466112Y117308D02*
Y114000D01*
G01X467262Y109000D02*
Y96657D01*
G01X466112Y114000D02*
Y96180D01*
G01X430912Y158726D02*
Y154135D01*
G01X429762Y158760D02*
Y153658D01*
G01X430912Y154135D02*
X467262Y117785D01*
G01X429762Y153658D02*
X466112Y117308D01*
G01X467262Y117785D02*
Y109000D01*
G01X466112Y117308D02*
Y114000D01*
G01X467262Y109000D02*
Y96657D01*
G01X466112Y114000D02*
Y96180D01*
G01X427243Y158861D02*
Y148985D01*
G01X426093Y158861D02*
Y148508D01*
G01X427243Y148985D02*
X429254Y146974D01*
G01X430669Y145559D02*
X431686Y144542D01*
G01X433101Y143127D02*
X436001Y140227D01*
G01X426093Y148508D02*
X435524Y139077D01*
G01X436001Y140227D02*
X439338D01*
G01X435524Y139077D02*
X438861D01*
G01X439338Y140227D02*
X441489Y138076D01*
G01X438861Y139077D02*
X440339Y137599D01*
G01X441489Y138076D02*
Y136130D01*
G01X440339Y137599D02*
Y136607D01*
G01X441489Y136130D02*
X441149Y135790D01*
G01X440339Y136607D02*
X439999Y136267D01*
G01X441149Y135790D02*
Y134798D01*
G01X439999Y136267D02*
Y134321D01*
G01X441149Y134798D02*
X442625Y133322D01*
G01X439999Y134321D02*
X442148Y132172D01*
G01X442625Y133322D02*
X443617D01*
G01X442148Y132172D02*
X444094D01*
G01X442625Y133322D02*
X443617D01*
G01D02*
X443957Y133662D01*
G01X444094Y132172D02*
X444434Y132512D01*
G01X443957Y133662D02*
X445903D01*
G01D02*
X448054Y131511D01*
G01X444434Y132512D02*
X445426D01*
G01X445903Y133662D02*
X448054Y131511D01*
G01X445426Y132512D02*
X446904Y131034D01*
G01X448054Y131511D02*
Y129565D01*
G01X446904Y131034D02*
Y130042D01*
G01X448054Y129565D02*
X447714Y129225D01*
G01X446904Y130042D02*
X446564Y129702D01*
G01X447714Y129225D02*
Y128233D01*
G01X446564Y129702D02*
Y127756D01*
G01X447714Y128233D02*
X449190Y126757D01*
G01X446564Y127756D02*
X448713Y125607D01*
G01X449190Y126757D02*
X450182D01*
G01X448713Y125607D02*
X450659D01*
G01X450182Y126757D02*
X450522Y127097D01*
G01X450659Y125607D02*
X450999Y125947D01*
G01X450182Y126757D02*
X450522Y127097D01*
G01D02*
X452468D01*
G01X450999Y125947D02*
X451991D01*
G01X452468Y127097D02*
X454619Y124946D01*
G01X451991Y125947D02*
X453469Y124469D01*
G01X454619Y124946D02*
Y123000D01*
G01X453469Y124469D02*
Y123477D01*
G01X454619Y123000D02*
X454279Y122660D01*
G01X453469Y123477D02*
X453129Y123137D01*
G01X454279Y122660D02*
Y121668D01*
G01X453129Y123137D02*
Y121191D01*
G01X454279Y121668D02*
X455755Y120192D01*
G01X453129Y121191D02*
X455278Y119042D01*
G01X455755Y120192D02*
X456747D01*
G01X455278Y119042D02*
X457224D01*
G01X455755Y120192D02*
X456747D01*
G01D02*
X457087Y120532D01*
G01X457224Y119042D02*
X457564Y119382D01*
G01X457087Y120532D02*
X459033D01*
G01D02*
X461442Y118123D01*
G01X457564Y119382D02*
X458556D01*
G01X459033Y120532D02*
X461442Y118123D01*
G01X458556Y119382D02*
X460292Y117646D01*
G01X461442Y118123D02*
Y111349D01*
G01X460292Y117646D02*
Y115000D01*
G01X461442Y118123D02*
Y111349D01*
G01X460292Y115000D02*
Y111826D01*
G01X461442Y111349D02*
X460642Y110549D01*
G01X460292Y111826D02*
X459492Y111026D01*
G01X460642Y110549D02*
Y108477D01*
G01X459492Y111026D02*
Y108000D01*
G01X460642Y108477D02*
X463292Y105827D01*
G01X459492Y108000D02*
X462142Y105350D01*
G01X463292Y105827D02*
Y95628D01*
G01X462142Y105350D02*
Y95151D01*
G01X463292Y95628D02*
X463820Y95100D01*
G01X427243Y158861D02*
Y148985D01*
G01X426093Y158861D02*
Y148508D01*
G01X427243Y148985D02*
X429254Y146974D01*
G01X430669Y145559D02*
X431686Y144542D01*
G01X433101Y143127D02*
X436001Y140227D01*
G01X426093Y148508D02*
X435524Y139077D01*
G01X436001Y140227D02*
X439338D01*
G01X435524Y139077D02*
X438861D01*
G01X439338Y140227D02*
X441489Y138076D01*
G01X438861Y139077D02*
X440339Y137599D01*
G01X441489Y138076D02*
Y136130D01*
G01X440339Y137599D02*
Y136607D01*
G01X441489Y136130D02*
X441149Y135790D01*
G01X440339Y136607D02*
X439999Y136267D01*
G01X441149Y135790D02*
Y134798D01*
G01X439999Y136267D02*
Y134321D01*
G01X441149Y134798D02*
X442625Y133322D01*
G01X439999Y134321D02*
X442148Y132172D01*
G01X442625Y133322D02*
X443617D01*
G01X442148Y132172D02*
X444094D01*
G01X442625Y133322D02*
X443617D01*
G01D02*
X443957Y133662D01*
G01X444094Y132172D02*
X444434Y132512D01*
G01X443957Y133662D02*
X445903D01*
G01D02*
X448054Y131511D01*
G01X444434Y132512D02*
X445426D01*
G01X445903Y133662D02*
X448054Y131511D01*
G01X445426Y132512D02*
X446904Y131034D01*
G01X448054Y131511D02*
Y129565D01*
G01X446904Y131034D02*
Y130042D01*
G01X448054Y129565D02*
X447714Y129225D01*
G01X446904Y130042D02*
X446564Y129702D01*
G01X447714Y129225D02*
Y128233D01*
G01X446564Y129702D02*
Y127756D01*
G01X447714Y128233D02*
X449190Y126757D01*
G01X446564Y127756D02*
X448713Y125607D01*
G01X449190Y126757D02*
X450182D01*
G01X448713Y125607D02*
X450659D01*
G01X450182Y126757D02*
X450522Y127097D01*
G01X450659Y125607D02*
X450999Y125947D01*
G01X450182Y126757D02*
X450522Y127097D01*
G01D02*
X452468D01*
G01X450999Y125947D02*
X451991D01*
G01X452468Y127097D02*
X454619Y124946D01*
G01X451991Y125947D02*
X453469Y124469D01*
G01X454619Y124946D02*
Y123000D01*
G01X453469Y124469D02*
Y123477D01*
G01X454619Y123000D02*
X454279Y122660D01*
G01X453469Y123477D02*
X453129Y123137D01*
G01X454279Y122660D02*
Y121668D01*
G01X453129Y123137D02*
Y121191D01*
G01X454279Y121668D02*
X455755Y120192D01*
G01X453129Y121191D02*
X455278Y119042D01*
G01X455755Y120192D02*
X456747D01*
G01X455278Y119042D02*
X457224D01*
G01X455755Y120192D02*
X456747D01*
G01D02*
X457087Y120532D01*
G01X457224Y119042D02*
X457564Y119382D01*
G01X457087Y120532D02*
X459033D01*
G01D02*
X461442Y118123D01*
G01X457564Y119382D02*
X458556D01*
G01X459033Y120532D02*
X461442Y118123D01*
G01X458556Y119382D02*
X460292Y117646D01*
G01X461442Y118123D02*
Y111349D01*
G01X460292Y117646D02*
Y115000D01*
G01X461442Y118123D02*
Y111349D01*
G01X460292Y115000D02*
Y111826D01*
G01X461442Y111349D02*
X460642Y110549D01*
G01X460292Y111826D02*
X459492Y111026D01*
G01X460642Y110549D02*
Y108477D01*
G01X459492Y111026D02*
Y108000D01*
G01X460642Y108477D02*
X463292Y105827D01*
G01X459492Y108000D02*
X462142Y105350D01*
G01X463292Y105827D02*
Y95628D01*
G01X462142Y105350D02*
Y95151D01*
G01X463292Y95628D02*
X463820Y95100D01*
G01X429762Y158760D02*
Y153658D01*
G01X430912Y158726D02*
Y154135D01*
G01X429762Y153658D02*
X466112Y117308D01*
G01X430912Y154135D02*
X467262Y117785D01*
G01X466112Y117308D02*
Y114000D01*
G01X467262Y117785D02*
Y109000D01*
G01X466112Y114000D02*
Y96180D01*
G01X467262Y109000D02*
Y96657D01*
G01X429762Y158760D02*
Y153658D01*
G01X430912Y158726D02*
Y154135D01*
G01X429762Y153658D02*
X466112Y117308D01*
G01X430912Y154135D02*
X467262Y117785D01*
G01X466112Y117308D02*
Y114000D01*
G01X467262Y117785D02*
Y109000D01*
G01X466112Y114000D02*
Y96180D01*
G01X467262Y109000D02*
Y96657D01*
G01X430912Y158726D02*
Y154135D01*
G01X429762Y158760D02*
Y153658D01*
G01X430912Y154135D02*
X467262Y117785D01*
G01X429762Y153658D02*
X466112Y117308D01*
G01X467262Y117785D02*
Y109000D01*
G01X466112Y117308D02*
Y114000D01*
G01X467262Y109000D02*
Y96657D01*
G01X466112Y114000D02*
Y96180D01*
G01X427243Y158861D02*
Y148985D01*
G01X426093Y158861D02*
Y148508D01*
G01X427243Y148985D02*
X429254Y146974D01*
G01X430669Y145559D02*
X431686Y144542D01*
G01X433101Y143127D02*
X436001Y140227D01*
G01X426093Y148508D02*
X435524Y139077D01*
G01X436001Y140227D02*
X439338D01*
G01X435524Y139077D02*
X438861D01*
G01X439338Y140227D02*
X441489Y138076D01*
G01X438861Y139077D02*
X440339Y137599D01*
G01X441489Y138076D02*
Y136130D01*
G01X440339Y137599D02*
Y136607D01*
G01X441489Y136130D02*
X441149Y135790D01*
G01X440339Y136607D02*
X439999Y136267D01*
G01X441149Y135790D02*
Y134798D01*
G01X439999Y136267D02*
Y134321D01*
G01X441149Y134798D02*
X442625Y133322D01*
G01X439999Y134321D02*
X442148Y132172D01*
G01X442625Y133322D02*
X443617D01*
G01X442148Y132172D02*
X444094D01*
G01X442625Y133322D02*
X443617D01*
G01D02*
X443957Y133662D01*
G01X444094Y132172D02*
X444434Y132512D01*
G01X443957Y133662D02*
X445903D01*
G01D02*
X448054Y131511D01*
G01X444434Y132512D02*
X445426D01*
G01X445903Y133662D02*
X448054Y131511D01*
G01X445426Y132512D02*
X446904Y131034D01*
G01X448054Y131511D02*
Y129565D01*
G01X446904Y131034D02*
Y130042D01*
G01X448054Y129565D02*
X447714Y129225D01*
G01X446904Y130042D02*
X446564Y129702D01*
G01X447714Y129225D02*
Y128233D01*
G01X446564Y129702D02*
Y127756D01*
G01X447714Y128233D02*
X449190Y126757D01*
G01X446564Y127756D02*
X448713Y125607D01*
G01X449190Y126757D02*
X450182D01*
G01X448713Y125607D02*
X450659D01*
G01X450182Y126757D02*
X450522Y127097D01*
G01X450659Y125607D02*
X450999Y125947D01*
G01X450182Y126757D02*
X450522Y127097D01*
G01D02*
X452468D01*
G01X450999Y125947D02*
X451991D01*
G01X452468Y127097D02*
X454619Y124946D01*
G01X451991Y125947D02*
X453469Y124469D01*
G01X454619Y124946D02*
Y123000D01*
G01X453469Y124469D02*
Y123477D01*
G01X454619Y123000D02*
X454279Y122660D01*
G01X453469Y123477D02*
X453129Y123137D01*
G01X454279Y122660D02*
Y121668D01*
G01X453129Y123137D02*
Y121191D01*
G01X454279Y121668D02*
X455755Y120192D01*
G01X453129Y121191D02*
X455278Y119042D01*
G01X455755Y120192D02*
X456747D01*
G01X455278Y119042D02*
X457224D01*
G01X455755Y120192D02*
X456747D01*
G01D02*
X457087Y120532D01*
G01X457224Y119042D02*
X457564Y119382D01*
G01X457087Y120532D02*
X459033D01*
G01D02*
X461442Y118123D01*
G01X457564Y119382D02*
X458556D01*
G01X459033Y120532D02*
X461442Y118123D01*
G01X458556Y119382D02*
X460292Y117646D01*
G01X461442Y118123D02*
Y111349D01*
G01X460292Y117646D02*
Y115000D01*
G01X461442Y118123D02*
Y111349D01*
G01X460292Y115000D02*
Y111826D01*
G01X461442Y111349D02*
X460642Y110549D01*
G01X460292Y111826D02*
X459492Y111026D01*
G01X460642Y110549D02*
Y108477D01*
G01X459492Y111026D02*
Y108000D01*
G01X460642Y108477D02*
X463292Y105827D01*
G01X459492Y108000D02*
X462142Y105350D01*
G01X463292Y105827D02*
Y95628D01*
G01X462142Y105350D02*
Y95151D01*
G01X463292Y95628D02*
X463820Y95100D01*
G01X429762Y158760D02*
Y153658D01*
G01X430912Y158726D02*
Y154135D01*
G01X429762Y153658D02*
X466112Y117308D01*
G01X430912Y154135D02*
X467262Y117785D01*
G01X466112Y117308D02*
Y114000D01*
G01X467262Y117785D02*
Y109000D01*
G01X466112Y114000D02*
Y96180D01*
G01X467262Y109000D02*
Y96657D01*
G01X464404Y157887D02*
X476791Y145500D01*
G01X464404Y157887D02*
X476791Y145500D01*
G01X467676Y156242D02*
X468383Y155535D01*
G01X464404Y157887D02*
X476791Y145500D01*
G01X469798Y154120D02*
X470997Y152921D01*
G01X464404Y157887D02*
X476791Y145500D01*
G01X472413Y151505D02*
X473120Y150798D01*
G01X464404Y157887D02*
X476791Y145500D01*
G01X474535Y149383D02*
X477268Y146650D01*
G01X476791Y145500D02*
X480692D01*
G01X477268Y146650D02*
X481169D01*
G01X474098Y156621D02*
X474805Y155914D01*
G01X476220Y154499D02*
X476927Y153792D01*
G01X468704Y160388D02*
X479592Y149500D01*
G01X467676Y156242D02*
X468383Y155535D01*
G01X469798Y154120D02*
X470997Y152921D01*
G01X472413Y151505D02*
X473120Y150798D01*
G01X474535Y149383D02*
X477268Y146650D01*
G01X464404Y157887D02*
X476791Y145500D01*
G01X477268Y146650D02*
X481169D01*
G01X476791Y145500D02*
X480692D01*
G01X468704Y160388D02*
X479592Y149500D01*
G01X468704Y160388D02*
X479592Y149500D01*
G01X468704Y160388D02*
X479592Y149500D01*
G01X474098Y156621D02*
X474805Y155914D01*
G01X468704Y160388D02*
X479592Y149500D01*
G01X476220Y154499D02*
X476927Y153792D01*
G01X468704Y160388D02*
X479592Y149500D01*
G01X464404Y157887D02*
X476791Y145500D01*
G01X464404Y157887D02*
X476791Y145500D01*
G01X467676Y156242D02*
X468383Y155535D01*
G01X464404Y157887D02*
X476791Y145500D01*
G01X469798Y154120D02*
X470997Y152921D01*
G01X464404Y157887D02*
X476791Y145500D01*
G01X472413Y151505D02*
X473120Y150798D01*
G01X464404Y157887D02*
X476791Y145500D01*
G01X474535Y149383D02*
X477268Y146650D01*
G01X476791Y145500D02*
X480692D01*
G01X477268Y146650D02*
X481169D01*
G01X474098Y156621D02*
X474805Y155914D01*
G01X476220Y154499D02*
X476927Y153792D01*
G01X468704Y160388D02*
X479592Y149500D01*
G01X467676Y156242D02*
X468383Y155535D01*
G01X469798Y154120D02*
X470997Y152921D01*
G01X472413Y151505D02*
X473120Y150798D01*
G01X474535Y149383D02*
X477268Y146650D01*
G01X464404Y157887D02*
X476791Y145500D01*
G01X477268Y146650D02*
X481169D01*
G01X476791Y145500D02*
X480692D01*
G01X468704Y160388D02*
X479592Y149500D01*
G01X468704Y160388D02*
X479592Y149500D01*
G01X468704Y160388D02*
X479592Y149500D01*
G01X474098Y156621D02*
X474805Y155914D01*
G01X468704Y160388D02*
X479592Y149500D01*
G01X476220Y154499D02*
X476927Y153792D01*
G01X468704Y160388D02*
X479592Y149500D01*
G01X464404Y161600D02*
Y157887D01*
G01X465554Y161600D02*
Y158364D01*
G01D02*
X466261Y157657D01*
G01X469854Y161700D02*
Y160865D01*
G01X468704Y161700D02*
Y160388D01*
G01X469854Y160865D02*
X470561Y160158D01*
G01X471976Y158743D02*
X472683Y158036D01*
G01X465554Y161600D02*
Y158364D01*
G01X464404Y161600D02*
Y157887D01*
G01X465554Y158364D02*
X466261Y157657D01*
G01X468704Y161700D02*
Y160388D01*
G01X469854Y161700D02*
Y160865D01*
G01D02*
X470561Y160158D01*
G01X471976Y158743D02*
X472683Y158036D01*
G01X464404Y161600D02*
Y157887D01*
G01X465554Y161600D02*
Y158364D01*
G01D02*
X466261Y157657D01*
G01X469854Y161700D02*
Y160865D01*
G01X468704Y161700D02*
Y160388D01*
G01X469854Y160865D02*
X470561Y160158D01*
G01X471976Y158743D02*
X472683Y158036D01*
G01X465554Y161600D02*
Y158364D01*
G01X464404Y161600D02*
Y157887D01*
G01X465554Y158364D02*
X466261Y157657D01*
G01X468704Y161700D02*
Y160388D01*
G01X469854Y161700D02*
Y160865D01*
G01D02*
X470561Y160158D01*
G01X471976Y158743D02*
X472683Y158036D01*
G01X430042Y448100D02*
Y450177D01*
G01X431192Y448100D02*
Y449700D01*
G01X430042Y450177D02*
X437612Y457747D01*
G01X431192Y449700D02*
X438762Y457270D01*
G01X437612Y457747D02*
Y461050D01*
G01Y463350D02*
Y466550D01*
G01X438762Y457270D02*
Y469914D01*
G01X431192Y448100D02*
Y449700D01*
G01X430042Y448100D02*
Y450177D01*
G01X431192Y449700D02*
X438762Y457270D01*
G01X430042Y450177D02*
X437612Y457747D01*
G01X438762Y457270D02*
Y469914D01*
G01X437612Y457747D02*
Y461050D01*
G01X438762Y457270D02*
Y469914D01*
G01X437612Y463350D02*
Y466550D01*
G01X438762Y457270D02*
Y469914D01*
G01X433953Y446411D02*
Y447987D01*
G01X435103Y446289D02*
Y447510D01*
G01X433953Y447987D02*
X435460Y449494D01*
G01X436168Y450909D02*
X436875D01*
G01D02*
X437582Y451616D01*
G01X438290Y453031D02*
X438997D01*
G01D02*
X439704Y453738D01*
G01X440412Y455153D02*
X441119D01*
G01D02*
X442205Y456239D01*
G01X435103Y447510D02*
X443355Y455762D01*
G01X442205Y456239D02*
Y460739D01*
G01Y462739D02*
Y465541D01*
G01X443355Y455762D02*
Y466018D01*
G01X474140Y451748D02*
X492362Y469970D01*
G01X474953Y450934D02*
X492839Y468820D01*
G01X474953Y450934D02*
X492839Y468820D01*
G01X474140Y451748D02*
X492362Y469970D01*
G01X476265Y447400D02*
X476759Y447895D01*
G01X477962Y449098D02*
X478456Y449592D01*
G01X476992Y446500D02*
X494692Y464200D01*
G01X435103Y446289D02*
Y447510D01*
G01X433953Y446411D02*
Y447987D01*
G01X435103Y447510D02*
X443355Y455762D01*
G01X433953Y447987D02*
X435460Y449494D01*
G01X435103Y447510D02*
X443355Y455762D01*
G01X436168Y450909D02*
X436875D01*
G01X435103Y447510D02*
X443355Y455762D01*
G01X436875Y450909D02*
X437582Y451616D01*
G01X435103Y447510D02*
X443355Y455762D01*
G01X438290Y453031D02*
X438997D01*
G01X435103Y447510D02*
X443355Y455762D01*
G01X438997Y453031D02*
X439704Y453738D01*
G01X435103Y447510D02*
X443355Y455762D01*
G01X440412Y455153D02*
X441119D01*
G01X435103Y447510D02*
X443355Y455762D01*
G01X441119Y455153D02*
X442205Y456239D01*
G01X443355Y455762D02*
Y466018D01*
G01X442205Y456239D02*
Y460739D01*
G01X443355Y455762D02*
Y466018D01*
G01X442205Y462739D02*
Y465541D01*
G01X476992Y446500D02*
X494692Y464200D01*
G01X476265Y447400D02*
X476759Y447895D01*
G01X476992Y446500D02*
X494692Y464200D01*
G01X477962Y449098D02*
X478456Y449592D01*
G01X476992Y446500D02*
X494692Y464200D01*
G01X476992Y446500D02*
X494692Y464200D01*
G01X476992Y446500D02*
X494692Y464200D01*
G01X476992Y446500D02*
X494692Y464200D01*
G01X476992Y446500D02*
X494692Y464200D01*
G01X476992Y446500D02*
X494692Y464200D01*
G01X476992Y446500D02*
X494692Y464200D01*
G01X476992Y446500D02*
X494692Y464200D01*
G01X476992Y446500D02*
X494692Y464200D01*
G01X430042Y448100D02*
Y450177D01*
G01X431192Y448100D02*
Y449700D01*
G01X430042Y450177D02*
X437612Y457747D01*
G01X431192Y449700D02*
X438762Y457270D01*
G01X437612Y457747D02*
Y461050D01*
G01Y463350D02*
Y466550D01*
G01X438762Y457270D02*
Y469914D01*
G01X431192Y448100D02*
Y449700D01*
G01X430042Y448100D02*
Y450177D01*
G01X431192Y449700D02*
X438762Y457270D01*
G01X430042Y450177D02*
X437612Y457747D01*
G01X438762Y457270D02*
Y469914D01*
G01X437612Y457747D02*
Y461050D01*
G01X438762Y457270D02*
Y469914D01*
G01X437612Y463350D02*
Y466550D01*
G01X438762Y457270D02*
Y469914D01*
G01X435103Y446289D02*
Y447510D01*
G01X433953Y446411D02*
Y447987D01*
G01X435103Y447510D02*
X443355Y455762D01*
G01X433953Y447987D02*
X435460Y449494D01*
G01X435103Y447510D02*
X443355Y455762D01*
G01X436168Y450909D02*
X436875D01*
G01X435103Y447510D02*
X443355Y455762D01*
G01X436875Y450909D02*
X437582Y451616D01*
G01X435103Y447510D02*
X443355Y455762D01*
G01X438290Y453031D02*
X438997D01*
G01X435103Y447510D02*
X443355Y455762D01*
G01X438997Y453031D02*
X439704Y453738D01*
G01X435103Y447510D02*
X443355Y455762D01*
G01X440412Y455153D02*
X441119D01*
G01X435103Y447510D02*
X443355Y455762D01*
G01X441119Y455153D02*
X442205Y456239D01*
G01X443355Y455762D02*
Y466018D01*
G01X442205Y456239D02*
Y460739D01*
G01X443355Y455762D02*
Y466018D01*
G01X442205Y462739D02*
Y465541D01*
G01X433953Y446411D02*
Y447987D01*
G01X435103Y446289D02*
Y447510D01*
G01X433953Y447987D02*
X435460Y449494D01*
G01X436168Y450909D02*
X436875D01*
G01D02*
X437582Y451616D01*
G01X438290Y453031D02*
X438997D01*
G01D02*
X439704Y453738D01*
G01X440412Y455153D02*
X441119D01*
G01D02*
X442205Y456239D01*
G01X435103Y447510D02*
X443355Y455762D01*
G01X442205Y456239D02*
Y460739D01*
G01Y462739D02*
Y465541D01*
G01X443355Y455762D02*
Y466018D01*
G01X474140Y451748D02*
X492362Y469970D01*
G01X474953Y450934D02*
X492839Y468820D01*
G01X476992Y446500D02*
X494692Y464200D01*
G01X476265Y447400D02*
X476759Y447895D01*
G01X476992Y446500D02*
X494692Y464200D01*
G01X477962Y449098D02*
X478456Y449592D01*
G01X476992Y446500D02*
X494692Y464200D01*
G01X476992Y446500D02*
X494692Y464200D01*
G01X476992Y446500D02*
X494692Y464200D01*
G01X476992Y446500D02*
X494692Y464200D01*
G01X476992Y446500D02*
X494692Y464200D01*
G01X476992Y446500D02*
X494692Y464200D01*
G01X476992Y446500D02*
X494692Y464200D01*
G01X476992Y446500D02*
X494692Y464200D01*
G01X476992Y446500D02*
X494692Y464200D01*
G01X474953Y450934D02*
X492839Y468820D01*
G01X474140Y451748D02*
X492362Y469970D01*
G01X476265Y447400D02*
X476759Y447895D01*
G01X477962Y449098D02*
X478456Y449592D01*
G01X476992Y446500D02*
X494692Y464200D01*
G01X437612Y468850D02*
Y470391D01*
G01D02*
X449743Y482522D01*
G01X450663Y484149D02*
X451370D01*
G01D02*
X467642Y500421D01*
G01X438762Y469914D02*
X468792Y499944D01*
G01X467642Y500421D02*
Y501523D01*
G01X468792Y499944D02*
Y502000D01*
G01X467642Y501523D02*
X466892Y502273D01*
G01X468792Y502000D02*
X468042Y502750D01*
G01X466892Y502273D02*
Y505527D01*
G01X468042Y502750D02*
Y505050D01*
G01X466892Y505527D02*
X467642Y506277D01*
G01X468042Y505050D02*
X468792Y505800D01*
G01X467642Y506277D02*
Y510851D01*
G01X468792Y505800D02*
Y511328D01*
G01X467642Y510851D02*
X465793Y512700D01*
G01X468792Y511328D02*
X464820Y515300D01*
G01X437612Y468850D02*
Y470391D01*
G01X438762Y469914D02*
X468792Y499944D01*
G01X437612Y470391D02*
X449743Y482522D01*
G01X438762Y469914D02*
X468792Y499944D01*
G01X450663Y484149D02*
X451370D01*
G01X438762Y469914D02*
X468792Y499944D01*
G01X451370Y484149D02*
X467642Y500421D01*
G01X468792Y499944D02*
Y502000D01*
G01X467642Y500421D02*
Y501523D01*
G01X468792Y502000D02*
X468042Y502750D01*
G01X467642Y501523D02*
X466892Y502273D01*
G01X468042Y502750D02*
Y505050D01*
G01X466892Y502273D02*
Y505527D01*
G01X468042Y505050D02*
X468792Y505800D01*
G01X466892Y505527D02*
X467642Y506277D01*
G01X468792Y505800D02*
Y511328D01*
G01X467642Y506277D02*
Y510851D01*
G01X468792Y511328D02*
X464820Y515300D01*
G01X467642Y510851D02*
X465793Y512700D01*
G01X442205Y465541D02*
X441364Y466382D01*
G01X443355Y466018D02*
X442514Y466859D01*
G01X441364Y466382D02*
Y468356D01*
G01X442514Y466859D02*
Y467879D01*
G01X441364Y468356D02*
X442995Y469987D01*
G01X442514Y467879D02*
X443472Y468837D01*
G01X442995Y469987D02*
X444765D01*
G01D02*
X445556Y469196D01*
G01X443472Y468837D02*
X444288D01*
G01X444765Y469987D02*
X445556Y469196D01*
G01X444288Y468837D02*
X445079Y468046D01*
G01X445556Y469196D02*
X446628D01*
G01X445079Y468046D02*
X447105D01*
G01X446628Y469196D02*
X447975Y470543D01*
G01X447105Y468046D02*
X449125Y470066D01*
G01X447975Y470543D02*
Y471782D01*
G01X449125Y470066D02*
Y472259D01*
G01X447975Y471782D02*
X447237Y472520D01*
G01X449125Y472259D02*
X448387Y472997D01*
G01X447237Y472520D02*
Y474466D01*
G01X448387Y472997D02*
Y473989D01*
G01X447237Y474466D02*
X449134Y476363D01*
G01X448387Y473989D02*
X449611Y475213D01*
G01X449134Y476363D02*
X451231D01*
G01X449611Y475213D02*
X450754D01*
G01X451231Y476363D02*
X452119Y475475D01*
G01X450754Y475213D02*
X451642Y474325D01*
G01X452119Y475475D02*
X452910D01*
G01X451642Y474325D02*
X453387D01*
G01X452119Y475475D02*
X452910D01*
G01D02*
X454035Y476600D01*
G01X453387Y474325D02*
X455185Y476123D01*
G01X454035Y476600D02*
Y477592D01*
G01X455185Y476123D02*
Y478069D01*
G01X454035Y477592D02*
X453457Y478170D01*
G01X455185Y478069D02*
X454607Y478647D01*
G01X453457Y478170D02*
Y480136D01*
G01X454607Y478647D02*
Y479659D01*
G01X453457Y480136D02*
X455621Y482300D01*
G01X456329Y483885D02*
X457206D01*
G01D02*
X457913Y484592D01*
G01X458620Y486176D02*
X459497D01*
G01D02*
X460292Y486971D01*
G01X461000Y488556D02*
X461877D01*
G01D02*
X462584Y489263D01*
G01X463292Y490848D02*
X464169D01*
G01D02*
X464876Y491555D01*
G01X465584Y493140D02*
X466461D01*
G01D02*
X467168Y493847D01*
G01X467876Y495432D02*
X468753D01*
G01D02*
X469460Y496139D01*
G01X470168Y497724D02*
X471045D01*
G01D02*
X471752Y498431D01*
G01X454607Y479659D02*
X472902Y497954D01*
G01X471752Y498431D02*
Y499577D01*
G01Y501577D02*
Y502577D01*
G01Y504577D02*
Y505577D01*
G01Y507577D02*
Y508577D01*
G01Y510577D02*
Y511968D01*
G01X472902Y497954D02*
Y512445D01*
G01X471752Y511968D02*
X470806Y512914D01*
G01X472902Y512445D02*
X469833Y515514D01*
G01X443355Y466018D02*
X442514Y466859D01*
G01X442205Y465541D02*
X441364Y466382D01*
G01X442514Y466859D02*
Y467879D01*
G01X441364Y466382D02*
Y468356D01*
G01X442514Y467879D02*
X443472Y468837D01*
G01X441364Y468356D02*
X442995Y469987D01*
G01X443472Y468837D02*
X444288D01*
G01X442995Y469987D02*
X444765D01*
G01X443472Y468837D02*
X444288D01*
G01D02*
X445079Y468046D01*
G01X444765Y469987D02*
X445556Y469196D01*
G01X445079Y468046D02*
X447105D01*
G01X445556Y469196D02*
X446628D01*
G01X447105Y468046D02*
X449125Y470066D01*
G01X446628Y469196D02*
X447975Y470543D01*
G01X449125Y470066D02*
Y472259D01*
G01X447975Y470543D02*
Y471782D01*
G01X449125Y472259D02*
X448387Y472997D01*
G01X447975Y471782D02*
X447237Y472520D01*
G01X448387Y472997D02*
Y473989D01*
G01X447237Y472520D02*
Y474466D01*
G01X448387Y473989D02*
X449611Y475213D01*
G01X447237Y474466D02*
X449134Y476363D01*
G01X449611Y475213D02*
X450754D01*
G01X449134Y476363D02*
X451231D01*
G01X450754Y475213D02*
X451642Y474325D01*
G01X451231Y476363D02*
X452119Y475475D01*
G01X451642Y474325D02*
X453387D01*
G01D02*
X455185Y476123D01*
G01X452119Y475475D02*
X452910D01*
G01X453387Y474325D02*
X455185Y476123D01*
G01X452910Y475475D02*
X454035Y476600D01*
G01X455185Y476123D02*
Y478069D01*
G01X454035Y476600D02*
Y477592D01*
G01X455185Y478069D02*
X454607Y478647D01*
G01X454035Y477592D02*
X453457Y478170D01*
G01X454607Y478647D02*
Y479659D01*
G01X453457Y478170D02*
Y480136D01*
G01X454607Y479659D02*
X472902Y497954D01*
G01X453457Y480136D02*
X455621Y482300D01*
G01X454607Y479659D02*
X472902Y497954D01*
G01X456329Y483885D02*
X457206D01*
G01X454607Y479659D02*
X472902Y497954D01*
G01X457206Y483885D02*
X457913Y484592D01*
G01X454607Y479659D02*
X472902Y497954D01*
G01X458620Y486176D02*
X459497D01*
G01X454607Y479659D02*
X472902Y497954D01*
G01X459497Y486176D02*
X460292Y486971D01*
G01X454607Y479659D02*
X472902Y497954D01*
G01X461000Y488556D02*
X461877D01*
G01X454607Y479659D02*
X472902Y497954D01*
G01X461877Y488556D02*
X462584Y489263D01*
G01X454607Y479659D02*
X472902Y497954D01*
G01X463292Y490848D02*
X464169D01*
G01X454607Y479659D02*
X472902Y497954D01*
G01X464169Y490848D02*
X464876Y491555D01*
G01X454607Y479659D02*
X472902Y497954D01*
G01X465584Y493140D02*
X466461D01*
G01X454607Y479659D02*
X472902Y497954D01*
G01X466461Y493140D02*
X467168Y493847D01*
G01X454607Y479659D02*
X472902Y497954D01*
G01X467876Y495432D02*
X468753D01*
G01X454607Y479659D02*
X472902Y497954D01*
G01X468753Y495432D02*
X469460Y496139D01*
G01X454607Y479659D02*
X472902Y497954D01*
G01X470168Y497724D02*
X471045D01*
G01X454607Y479659D02*
X472902Y497954D01*
G01X471045Y497724D02*
X471752Y498431D01*
G01X472902Y497954D02*
Y512445D01*
G01X471752Y498431D02*
Y499577D01*
G01X472902Y497954D02*
Y512445D01*
G01X471752Y501577D02*
Y502577D01*
G01X472902Y497954D02*
Y512445D01*
G01X471752Y504577D02*
Y505577D01*
G01X472902Y497954D02*
Y512445D01*
G01X471752Y507577D02*
Y508577D01*
G01X472902Y497954D02*
Y512445D01*
G01X471752Y510577D02*
Y511968D01*
G01X472902Y512445D02*
X469833Y515514D01*
G01X471752Y511968D02*
X470806Y512914D01*
G01X437612Y468850D02*
Y470391D01*
G01D02*
X449743Y482522D01*
G01X450663Y484149D02*
X451370D01*
G01D02*
X467642Y500421D01*
G01X438762Y469914D02*
X468792Y499944D01*
G01X467642Y500421D02*
Y501523D01*
G01X468792Y499944D02*
Y502000D01*
G01X467642Y501523D02*
X466892Y502273D01*
G01X468792Y502000D02*
X468042Y502750D01*
G01X466892Y502273D02*
Y505527D01*
G01X468042Y502750D02*
Y505050D01*
G01X466892Y505527D02*
X467642Y506277D01*
G01X468042Y505050D02*
X468792Y505800D01*
G01X467642Y506277D02*
Y510851D01*
G01X468792Y505800D02*
Y511328D01*
G01X467642Y510851D02*
X465793Y512700D01*
G01X468792Y511328D02*
X464820Y515300D01*
G01X437612Y468850D02*
Y470391D01*
G01X438762Y469914D02*
X468792Y499944D01*
G01X437612Y470391D02*
X449743Y482522D01*
G01X438762Y469914D02*
X468792Y499944D01*
G01X450663Y484149D02*
X451370D01*
G01X438762Y469914D02*
X468792Y499944D01*
G01X451370Y484149D02*
X467642Y500421D01*
G01X468792Y499944D02*
Y502000D01*
G01X467642Y500421D02*
Y501523D01*
G01X468792Y502000D02*
X468042Y502750D01*
G01X467642Y501523D02*
X466892Y502273D01*
G01X468042Y502750D02*
Y505050D01*
G01X466892Y502273D02*
Y505527D01*
G01X468042Y505050D02*
X468792Y505800D01*
G01X466892Y505527D02*
X467642Y506277D01*
G01X468792Y505800D02*
Y511328D01*
G01X467642Y506277D02*
Y510851D01*
G01X468792Y511328D02*
X464820Y515300D01*
G01X467642Y510851D02*
X465793Y512700D01*
G01X443355Y466018D02*
X442514Y466859D01*
G01X442205Y465541D02*
X441364Y466382D01*
G01X442514Y466859D02*
Y467879D01*
G01X441364Y466382D02*
Y468356D01*
G01X442514Y467879D02*
X443472Y468837D01*
G01X441364Y468356D02*
X442995Y469987D01*
G01X443472Y468837D02*
X444288D01*
G01X442995Y469987D02*
X444765D01*
G01X443472Y468837D02*
X444288D01*
G01D02*
X445079Y468046D01*
G01X444765Y469987D02*
X445556Y469196D01*
G01X445079Y468046D02*
X447105D01*
G01X445556Y469196D02*
X446628D01*
G01X447105Y468046D02*
X449125Y470066D01*
G01X446628Y469196D02*
X447975Y470543D01*
G01X449125Y470066D02*
Y472259D01*
G01X447975Y470543D02*
Y471782D01*
G01X449125Y472259D02*
X448387Y472997D01*
G01X447975Y471782D02*
X447237Y472520D01*
G01X448387Y472997D02*
Y473989D01*
G01X447237Y472520D02*
Y474466D01*
G01X448387Y473989D02*
X449611Y475213D01*
G01X447237Y474466D02*
X449134Y476363D01*
G01X449611Y475213D02*
X450754D01*
G01X449134Y476363D02*
X451231D01*
G01X450754Y475213D02*
X451642Y474325D01*
G01X451231Y476363D02*
X452119Y475475D01*
G01X451642Y474325D02*
X453387D01*
G01D02*
X455185Y476123D01*
G01X452119Y475475D02*
X452910D01*
G01X453387Y474325D02*
X455185Y476123D01*
G01X452910Y475475D02*
X454035Y476600D01*
G01X455185Y476123D02*
Y478069D01*
G01X454035Y476600D02*
Y477592D01*
G01X455185Y478069D02*
X454607Y478647D01*
G01X454035Y477592D02*
X453457Y478170D01*
G01X454607Y478647D02*
Y479659D01*
G01X453457Y478170D02*
Y480136D01*
G01X454607Y479659D02*
X472902Y497954D01*
G01X453457Y480136D02*
X455621Y482300D01*
G01X454607Y479659D02*
X472902Y497954D01*
G01X456329Y483885D02*
X457206D01*
G01X454607Y479659D02*
X472902Y497954D01*
G01X457206Y483885D02*
X457913Y484592D01*
G01X454607Y479659D02*
X472902Y497954D01*
G01X458620Y486176D02*
X459497D01*
G01X454607Y479659D02*
X472902Y497954D01*
G01X459497Y486176D02*
X460292Y486971D01*
G01X454607Y479659D02*
X472902Y497954D01*
G01X461000Y488556D02*
X461877D01*
G01X454607Y479659D02*
X472902Y497954D01*
G01X461877Y488556D02*
X462584Y489263D01*
G01X454607Y479659D02*
X472902Y497954D01*
G01X463292Y490848D02*
X464169D01*
G01X454607Y479659D02*
X472902Y497954D01*
G01X464169Y490848D02*
X464876Y491555D01*
G01X454607Y479659D02*
X472902Y497954D01*
G01X465584Y493140D02*
X466461D01*
G01X454607Y479659D02*
X472902Y497954D01*
G01X466461Y493140D02*
X467168Y493847D01*
G01X454607Y479659D02*
X472902Y497954D01*
G01X467876Y495432D02*
X468753D01*
G01X454607Y479659D02*
X472902Y497954D01*
G01X468753Y495432D02*
X469460Y496139D01*
G01X454607Y479659D02*
X472902Y497954D01*
G01X470168Y497724D02*
X471045D01*
G01X454607Y479659D02*
X472902Y497954D01*
G01X471045Y497724D02*
X471752Y498431D01*
G01X472902Y497954D02*
Y512445D01*
G01X471752Y498431D02*
Y499577D01*
G01X472902Y497954D02*
Y512445D01*
G01X471752Y501577D02*
Y502577D01*
G01X472902Y497954D02*
Y512445D01*
G01X471752Y504577D02*
Y505577D01*
G01X472902Y497954D02*
Y512445D01*
G01X471752Y507577D02*
Y508577D01*
G01X472902Y497954D02*
Y512445D01*
G01X471752Y510577D02*
Y511968D01*
G01X472902Y512445D02*
X469833Y515514D01*
G01X471752Y511968D02*
X470806Y512914D01*
G01X442205Y465541D02*
X441364Y466382D01*
G01X443355Y466018D02*
X442514Y466859D01*
G01X441364Y466382D02*
Y468356D01*
G01X442514Y466859D02*
Y467879D01*
G01X441364Y468356D02*
X442995Y469987D01*
G01X442514Y467879D02*
X443472Y468837D01*
G01X442995Y469987D02*
X444765D01*
G01D02*
X445556Y469196D01*
G01X443472Y468837D02*
X444288D01*
G01X444765Y469987D02*
X445556Y469196D01*
G01X444288Y468837D02*
X445079Y468046D01*
G01X445556Y469196D02*
X446628D01*
G01X445079Y468046D02*
X447105D01*
G01X446628Y469196D02*
X447975Y470543D01*
G01X447105Y468046D02*
X449125Y470066D01*
G01X447975Y470543D02*
Y471782D01*
G01X449125Y470066D02*
Y472259D01*
G01X447975Y471782D02*
X447237Y472520D01*
G01X449125Y472259D02*
X448387Y472997D01*
G01X447237Y472520D02*
Y474466D01*
G01X448387Y472997D02*
Y473989D01*
G01X447237Y474466D02*
X449134Y476363D01*
G01X448387Y473989D02*
X449611Y475213D01*
G01X449134Y476363D02*
X451231D01*
G01X449611Y475213D02*
X450754D01*
G01X451231Y476363D02*
X452119Y475475D01*
G01X450754Y475213D02*
X451642Y474325D01*
G01X452119Y475475D02*
X452910D01*
G01X451642Y474325D02*
X453387D01*
G01X452119Y475475D02*
X452910D01*
G01D02*
X454035Y476600D01*
G01X453387Y474325D02*
X455185Y476123D01*
G01X454035Y476600D02*
Y477592D01*
G01X455185Y476123D02*
Y478069D01*
G01X454035Y477592D02*
X453457Y478170D01*
G01X455185Y478069D02*
X454607Y478647D01*
G01X453457Y478170D02*
Y480136D01*
G01X454607Y478647D02*
Y479659D01*
G01X453457Y480136D02*
X455621Y482300D01*
G01X456329Y483885D02*
X457206D01*
G01D02*
X457913Y484592D01*
G01X458620Y486176D02*
X459497D01*
G01D02*
X460292Y486971D01*
G01X461000Y488556D02*
X461877D01*
G01D02*
X462584Y489263D01*
G01X463292Y490848D02*
X464169D01*
G01D02*
X464876Y491555D01*
G01X465584Y493140D02*
X466461D01*
G01D02*
X467168Y493847D01*
G01X467876Y495432D02*
X468753D01*
G01D02*
X469460Y496139D01*
G01X470168Y497724D02*
X471045D01*
G01D02*
X471752Y498431D01*
G01X454607Y479659D02*
X472902Y497954D01*
G01X471752Y498431D02*
Y499577D01*
G01Y501577D02*
Y502577D01*
G01Y504577D02*
Y505577D01*
G01Y507577D02*
Y508577D01*
G01Y510577D02*
Y511968D01*
G01X472902Y497954D02*
Y512445D01*
G01X471752Y511968D02*
X470806Y512914D01*
G01X472902Y512445D02*
X469833Y515514D01*
G01X480692Y145500D02*
X488494Y137698D01*
G01X481169Y146650D02*
X489644Y138175D01*
G01X488494Y137698D02*
Y136778D01*
G01X489644Y138175D02*
Y136301D01*
G01X488494Y136778D02*
X487384Y135668D01*
G01X489644Y136301D02*
X488534Y135191D01*
G01X487384Y135668D02*
Y134008D01*
G01X488534Y135191D02*
Y134485D01*
G01X487384Y134008D02*
X489227Y132165D01*
G01X488534Y134485D02*
X489704Y133315D01*
G01X487384Y134008D02*
X489227Y132165D01*
G01D02*
X490887D01*
G01D02*
X491997Y133275D01*
G01X489704Y133315D02*
X490410D01*
G01X490887Y132165D02*
X491997Y133275D01*
G01X490410Y133315D02*
X491520Y134425D01*
G01X491997Y133275D02*
X492917D01*
G01X491520Y134425D02*
X493394D01*
G01X492917Y133275D02*
X495165Y131027D01*
G01X493394Y134425D02*
X496315Y131504D01*
G01X495165Y131027D02*
Y130107D01*
G01X496315Y131504D02*
Y129630D01*
G01X495165Y130107D02*
X494592Y129534D01*
G01X496315Y129630D02*
X495742Y129057D01*
G01X494592Y129534D02*
Y127272D01*
G01X495742Y129057D02*
Y127749D01*
G01X494592Y127272D02*
X496814Y125050D01*
G01X495742Y127749D02*
X497291Y126200D01*
G01X496814Y125050D02*
X500592D01*
G01X497291Y126200D02*
X501069D01*
G01X500592Y125050D02*
X501092Y124550D01*
G01X501069Y126200D02*
X502242Y125027D01*
G01X501092Y124550D02*
Y118799D01*
G01X502242Y125027D02*
Y118322D01*
G01X501092Y118799D02*
X499769Y117476D01*
G01X502242Y118322D02*
X500919Y116999D01*
G01X499769Y117476D02*
Y109666D01*
G01X500919Y116999D02*
Y115573D01*
G01X478342Y152377D02*
X480069Y150650D01*
G01D02*
X482441D01*
G01X479592Y149500D02*
X481964D01*
G01X482441Y150650D02*
X506004Y127087D01*
G01X481964Y149500D02*
X504854Y126610D01*
G01X506004Y127087D02*
Y116287D01*
G01X504854Y126610D02*
Y115180D01*
G01X481169Y146650D02*
X489644Y138175D01*
G01X480692Y145500D02*
X488494Y137698D01*
G01X489644Y138175D02*
Y136301D01*
G01X488494Y137698D02*
Y136778D01*
G01X489644Y136301D02*
X488534Y135191D01*
G01X488494Y136778D02*
X487384Y135668D01*
G01X488534Y135191D02*
Y134485D01*
G01X487384Y135668D02*
Y134008D01*
G01X488534Y134485D02*
X489704Y133315D01*
G01D02*
X490410D01*
G01X487384Y134008D02*
X489227Y132165D01*
G01X489704Y133315D02*
X490410D01*
G01X489227Y132165D02*
X490887D01*
G01X489704Y133315D02*
X490410D01*
G01D02*
X491520Y134425D01*
G01X490887Y132165D02*
X491997Y133275D01*
G01X491520Y134425D02*
X493394D01*
G01X491997Y133275D02*
X492917D01*
G01X493394Y134425D02*
X496315Y131504D01*
G01X492917Y133275D02*
X495165Y131027D01*
G01X496315Y131504D02*
Y129630D01*
G01X495165Y131027D02*
Y130107D01*
G01X496315Y129630D02*
X495742Y129057D01*
G01X495165Y130107D02*
X494592Y129534D01*
G01X495742Y129057D02*
Y127749D01*
G01X494592Y129534D02*
Y127272D01*
G01X495742Y127749D02*
X497291Y126200D01*
G01X494592Y127272D02*
X496814Y125050D01*
G01X497291Y126200D02*
X501069D01*
G01X496814Y125050D02*
X500592D01*
G01X501069Y126200D02*
X502242Y125027D01*
G01X500592Y125050D02*
X501092Y124550D01*
G01X502242Y125027D02*
Y118322D01*
G01X501092Y124550D02*
Y118799D01*
G01X502242Y118322D02*
X500919Y116999D01*
G01X501092Y118799D02*
X499769Y117476D01*
G01X500919Y116999D02*
Y115573D01*
G01X499769Y117476D02*
Y109666D01*
G01X478342Y152377D02*
X480069Y150650D01*
G01X479592Y149500D02*
X481964D01*
G01X480069Y150650D02*
X482441D01*
G01X481964Y149500D02*
X504854Y126610D01*
G01X482441Y150650D02*
X506004Y127087D01*
G01X504854Y126610D02*
Y115180D01*
G01X506004Y127087D02*
Y116287D01*
G01X539842Y142850D02*
Y139500D01*
G01D02*
X537511Y137169D01*
G01X540992Y139023D02*
X538661Y136692D01*
G01X537511Y135500D02*
Y132981D01*
G01Y137169D02*
Y135500D01*
G01X538661Y136692D02*
Y133458D01*
G01X537511Y132981D02*
X539842Y130650D01*
G01X538661Y133458D02*
X540992Y131127D01*
G01X539842Y130650D02*
Y129752D01*
G01D02*
X539140Y129050D01*
G01X540992Y129275D02*
X539617Y127900D01*
G01X539140Y129050D02*
X537097D01*
G01X539617Y127900D02*
X537574D01*
G01X537097Y129050D02*
X535722Y127675D01*
G01X537574Y127900D02*
X536872Y127198D01*
G01X535722Y127675D02*
Y124975D01*
G01X536872Y127198D02*
Y125452D01*
G01X535722Y124975D02*
X537097Y123600D01*
G01X536872Y125452D02*
X537574Y124750D01*
G01X537097Y123600D02*
X539240D01*
G01X537574Y124750D02*
X539717D01*
G01X539240Y123600D02*
X539942Y122898D01*
G01X539717Y124750D02*
X541092Y123375D01*
G01X539942Y121395D02*
X539240Y120693D01*
G01X541092Y120918D02*
X539717Y119543D01*
G01X539240Y120693D02*
X536895D01*
G01X539717Y119543D02*
X537372D01*
G01X536895Y120693D02*
X535722Y119520D01*
G01X537372Y119543D02*
X536872Y119043D01*
G01X535722Y119520D02*
Y115343D01*
G01X536872Y119043D02*
Y115820D01*
G01X535722Y115343D02*
X536392Y114673D01*
G01X536872Y115820D02*
X537692Y115000D01*
G01X521242Y161450D02*
X539842Y142850D01*
G01X521242Y161450D02*
X539842Y142850D01*
G01X521242Y161450D02*
X539842Y142850D01*
G01X526913Y157406D02*
X540992Y143327D01*
G01X539842Y142850D02*
Y139500D01*
G01X533613Y157006D02*
X534320Y156299D01*
G01X535735Y154884D02*
X536442Y154177D01*
G01X537857Y152762D02*
X544809Y145810D01*
G01X525942Y163050D02*
X543659Y145333D01*
G01X538661Y136692D02*
Y133458D01*
G01X537511Y135500D02*
Y132981D01*
G01X538661Y133458D02*
X540992Y131127D01*
G01X537511Y132981D02*
X539842Y130650D01*
G01D02*
Y129752D01*
G01X540992Y129275D02*
X539617Y127900D01*
G01X539842Y129752D02*
X539140Y129050D01*
G01X539617Y127900D02*
X537574D01*
G01X539140Y129050D02*
X537097D01*
G01X537574Y127900D02*
X536872Y127198D01*
G01X537097Y129050D02*
X535722Y127675D01*
G01X536872Y127198D02*
Y125452D01*
G01X535722Y127675D02*
Y124975D01*
G01X536872Y125452D02*
X537574Y124750D01*
G01X535722Y124975D02*
X537097Y123600D01*
G01X537574Y124750D02*
X539717D01*
G01X537097Y123600D02*
X539240D01*
G01X539717Y124750D02*
X541092Y123375D01*
G01X539240Y123600D02*
X539942Y122898D01*
G01X541092Y120918D02*
X539717Y119543D01*
G01X539942Y121395D02*
X539240Y120693D01*
G01X539717Y119543D02*
X537372D01*
G01X539240Y120693D02*
X536895D01*
G01X537372Y119543D02*
X536872Y119043D01*
G01X536895Y120693D02*
X535722Y119520D01*
G01X536872Y119043D02*
Y115820D01*
G01X535722Y119520D02*
Y115343D01*
G01X536872Y115820D02*
X537692Y115000D01*
G01X535722Y115343D02*
X536392Y114673D01*
G01X526913Y157406D02*
X540992Y143327D01*
G01X521242Y161450D02*
X539842Y142850D01*
G01D02*
Y139500D01*
G01X540992Y139023D02*
X538661Y136692D01*
G01X539842Y139500D02*
X537511Y137169D01*
G01X538661Y136692D02*
Y133458D01*
G01X537511Y137169D02*
Y135500D01*
G01X525942Y163050D02*
X543659Y145333D01*
G01X525942Y163050D02*
X543659Y145333D01*
G01X525942Y163050D02*
X543659Y145333D01*
G01X525942Y163050D02*
X543659Y145333D01*
G01X533613Y157006D02*
X534320Y156299D01*
G01X525942Y163050D02*
X543659Y145333D01*
G01X535735Y154884D02*
X536442Y154177D01*
G01X525942Y163050D02*
X543659Y145333D01*
G01X537857Y152762D02*
X544809Y145810D01*
G01X480692Y145500D02*
X488494Y137698D01*
G01X481169Y146650D02*
X489644Y138175D01*
G01X488494Y137698D02*
Y136778D01*
G01X489644Y138175D02*
Y136301D01*
G01X488494Y136778D02*
X487384Y135668D01*
G01X489644Y136301D02*
X488534Y135191D01*
G01X487384Y135668D02*
Y134008D01*
G01X488534Y135191D02*
Y134485D01*
G01X487384Y134008D02*
X489227Y132165D01*
G01X488534Y134485D02*
X489704Y133315D01*
G01X487384Y134008D02*
X489227Y132165D01*
G01D02*
X490887D01*
G01D02*
X491997Y133275D01*
G01X489704Y133315D02*
X490410D01*
G01X490887Y132165D02*
X491997Y133275D01*
G01X490410Y133315D02*
X491520Y134425D01*
G01X491997Y133275D02*
X492917D01*
G01X491520Y134425D02*
X493394D01*
G01X492917Y133275D02*
X495165Y131027D01*
G01X493394Y134425D02*
X496315Y131504D01*
G01X495165Y131027D02*
Y130107D01*
G01X496315Y131504D02*
Y129630D01*
G01X495165Y130107D02*
X494592Y129534D01*
G01X496315Y129630D02*
X495742Y129057D01*
G01X494592Y129534D02*
Y127272D01*
G01X495742Y129057D02*
Y127749D01*
G01X494592Y127272D02*
X496814Y125050D01*
G01X495742Y127749D02*
X497291Y126200D01*
G01X496814Y125050D02*
X500592D01*
G01X497291Y126200D02*
X501069D01*
G01X500592Y125050D02*
X501092Y124550D01*
G01X501069Y126200D02*
X502242Y125027D01*
G01X501092Y124550D02*
Y118799D01*
G01X502242Y125027D02*
Y118322D01*
G01X501092Y118799D02*
X499769Y117476D01*
G01X502242Y118322D02*
X500919Y116999D01*
G01X499769Y117476D02*
Y109666D01*
G01X500919Y116999D02*
Y115573D01*
G01X539842Y142850D02*
Y139500D01*
G01D02*
X537511Y137169D01*
G01X540992Y139023D02*
X538661Y136692D01*
G01X537511Y135500D02*
Y132981D01*
G01Y137169D02*
Y135500D01*
G01X538661Y136692D02*
Y133458D01*
G01X537511Y132981D02*
X539842Y130650D01*
G01X538661Y133458D02*
X540992Y131127D01*
G01X539842Y130650D02*
Y129752D01*
G01D02*
X539140Y129050D01*
G01X540992Y129275D02*
X539617Y127900D01*
G01X539140Y129050D02*
X537097D01*
G01X539617Y127900D02*
X537574D01*
G01X537097Y129050D02*
X535722Y127675D01*
G01X537574Y127900D02*
X536872Y127198D01*
G01X535722Y127675D02*
Y124975D01*
G01X536872Y127198D02*
Y125452D01*
G01X535722Y124975D02*
X537097Y123600D01*
G01X536872Y125452D02*
X537574Y124750D01*
G01X537097Y123600D02*
X539240D01*
G01X537574Y124750D02*
X539717D01*
G01X539240Y123600D02*
X539942Y122898D01*
G01X539717Y124750D02*
X541092Y123375D01*
G01X539942Y121395D02*
X539240Y120693D01*
G01X541092Y120918D02*
X539717Y119543D01*
G01X539240Y120693D02*
X536895D01*
G01X539717Y119543D02*
X537372D01*
G01X536895Y120693D02*
X535722Y119520D01*
G01X537372Y119543D02*
X536872Y119043D01*
G01X535722Y119520D02*
Y115343D01*
G01X536872Y119043D02*
Y115820D01*
G01X535722Y115343D02*
X536392Y114673D01*
G01X536872Y115820D02*
X537692Y115000D01*
G01X521242Y161450D02*
X539842Y142850D01*
G01X521242Y161450D02*
X539842Y142850D01*
G01X521242Y161450D02*
X539842Y142850D01*
G01X526913Y157406D02*
X540992Y143327D01*
G01X539842Y142850D02*
Y139500D01*
G01X478342Y152377D02*
X480069Y150650D01*
G01D02*
X482441D01*
G01X479592Y149500D02*
X481964D01*
G01X482441Y150650D02*
X506004Y127087D01*
G01X481964Y149500D02*
X504854Y126610D01*
G01X506004Y127087D02*
Y116287D01*
G01X504854Y126610D02*
Y115180D01*
G01X481169Y146650D02*
X489644Y138175D01*
G01X480692Y145500D02*
X488494Y137698D01*
G01X489644Y138175D02*
Y136301D01*
G01X488494Y137698D02*
Y136778D01*
G01X489644Y136301D02*
X488534Y135191D01*
G01X488494Y136778D02*
X487384Y135668D01*
G01X488534Y135191D02*
Y134485D01*
G01X487384Y135668D02*
Y134008D01*
G01X488534Y134485D02*
X489704Y133315D01*
G01D02*
X490410D01*
G01X487384Y134008D02*
X489227Y132165D01*
G01X489704Y133315D02*
X490410D01*
G01X489227Y132165D02*
X490887D01*
G01X489704Y133315D02*
X490410D01*
G01D02*
X491520Y134425D01*
G01X490887Y132165D02*
X491997Y133275D01*
G01X491520Y134425D02*
X493394D01*
G01X491997Y133275D02*
X492917D01*
G01X493394Y134425D02*
X496315Y131504D01*
G01X492917Y133275D02*
X495165Y131027D01*
G01X496315Y131504D02*
Y129630D01*
G01X495165Y131027D02*
Y130107D01*
G01X496315Y129630D02*
X495742Y129057D01*
G01X495165Y130107D02*
X494592Y129534D01*
G01X495742Y129057D02*
Y127749D01*
G01X494592Y129534D02*
Y127272D01*
G01X495742Y127749D02*
X497291Y126200D01*
G01X494592Y127272D02*
X496814Y125050D01*
G01X497291Y126200D02*
X501069D01*
G01X496814Y125050D02*
X500592D01*
G01X501069Y126200D02*
X502242Y125027D01*
G01X500592Y125050D02*
X501092Y124550D01*
G01X502242Y125027D02*
Y118322D01*
G01X501092Y124550D02*
Y118799D01*
G01X502242Y118322D02*
X500919Y116999D01*
G01X501092Y118799D02*
X499769Y117476D01*
G01X500919Y116999D02*
Y115573D01*
G01X499769Y117476D02*
Y109666D01*
G01X538661Y136692D02*
Y133458D01*
G01X537511Y135500D02*
Y132981D01*
G01X538661Y133458D02*
X540992Y131127D01*
G01X537511Y132981D02*
X539842Y130650D01*
G01D02*
Y129752D01*
G01X540992Y129275D02*
X539617Y127900D01*
G01X539842Y129752D02*
X539140Y129050D01*
G01X539617Y127900D02*
X537574D01*
G01X539140Y129050D02*
X537097D01*
G01X537574Y127900D02*
X536872Y127198D01*
G01X537097Y129050D02*
X535722Y127675D01*
G01X536872Y127198D02*
Y125452D01*
G01X535722Y127675D02*
Y124975D01*
G01X536872Y125452D02*
X537574Y124750D01*
G01X535722Y124975D02*
X537097Y123600D01*
G01X537574Y124750D02*
X539717D01*
G01X537097Y123600D02*
X539240D01*
G01X539717Y124750D02*
X541092Y123375D01*
G01X539240Y123600D02*
X539942Y122898D01*
G01X541092Y120918D02*
X539717Y119543D01*
G01X539942Y121395D02*
X539240Y120693D01*
G01X539717Y119543D02*
X537372D01*
G01X539240Y120693D02*
X536895D01*
G01X537372Y119543D02*
X536872Y119043D01*
G01X536895Y120693D02*
X535722Y119520D01*
G01X536872Y119043D02*
Y115820D01*
G01X535722Y119520D02*
Y115343D01*
G01X536872Y115820D02*
X537692Y115000D01*
G01X535722Y115343D02*
X536392Y114673D01*
G01X526913Y157406D02*
X540992Y143327D01*
G01X521242Y161450D02*
X539842Y142850D01*
G01D02*
Y139500D01*
G01X540992Y139023D02*
X538661Y136692D01*
G01X539842Y139500D02*
X537511Y137169D01*
G01X538661Y136692D02*
Y133458D01*
G01X537511Y137169D02*
Y135500D01*
G01X478342Y152377D02*
X480069Y150650D01*
G01X479592Y149500D02*
X481964D01*
G01X480069Y150650D02*
X482441D01*
G01X481964Y149500D02*
X504854Y126610D01*
G01X482441Y150650D02*
X506004Y127087D01*
G01X504854Y126610D02*
Y115180D01*
G01X506004Y127087D02*
Y116287D01*
G01X539842Y142850D02*
Y139500D01*
G01D02*
X537511Y137169D01*
G01X540992Y139023D02*
X538661Y136692D01*
G01X537511Y135500D02*
Y132981D01*
G01Y137169D02*
Y135500D01*
G01X538661Y136692D02*
Y133458D01*
G01X537511Y132981D02*
X539842Y130650D01*
G01X538661Y133458D02*
X540992Y131127D01*
G01X539842Y130650D02*
Y129752D01*
G01D02*
X539140Y129050D01*
G01X540992Y129275D02*
X539617Y127900D01*
G01X539140Y129050D02*
X537097D01*
G01X539617Y127900D02*
X537574D01*
G01X537097Y129050D02*
X535722Y127675D01*
G01X537574Y127900D02*
X536872Y127198D01*
G01X535722Y127675D02*
Y124975D01*
G01X536872Y127198D02*
Y125452D01*
G01X535722Y124975D02*
X537097Y123600D01*
G01X536872Y125452D02*
X537574Y124750D01*
G01X537097Y123600D02*
X539240D01*
G01X537574Y124750D02*
X539717D01*
G01X539240Y123600D02*
X539942Y122898D01*
G01X539717Y124750D02*
X541092Y123375D01*
G01X539942Y121395D02*
X539240Y120693D01*
G01X541092Y120918D02*
X539717Y119543D01*
G01X539240Y120693D02*
X536895D01*
G01X539717Y119543D02*
X537372D01*
G01X536895Y120693D02*
X535722Y119520D01*
G01X537372Y119543D02*
X536872Y119043D01*
G01X535722Y119520D02*
Y115343D01*
G01X536872Y119043D02*
Y115820D01*
G01X535722Y115343D02*
X536392Y114673D01*
G01X536872Y115820D02*
X537692Y115000D01*
G01X521242Y161450D02*
X539842Y142850D01*
G01X521242Y161450D02*
X539842Y142850D01*
G01X521242Y161450D02*
X539842Y142850D01*
G01X526913Y157406D02*
X540992Y143327D01*
G01X539842Y142850D02*
Y139500D01*
G01X538661Y136692D02*
Y133458D01*
G01X537511Y135500D02*
Y132981D01*
G01X538661Y133458D02*
X540992Y131127D01*
G01X537511Y132981D02*
X539842Y130650D01*
G01D02*
Y129752D01*
G01X540992Y129275D02*
X539617Y127900D01*
G01X539842Y129752D02*
X539140Y129050D01*
G01X539617Y127900D02*
X537574D01*
G01X539140Y129050D02*
X537097D01*
G01X537574Y127900D02*
X536872Y127198D01*
G01X537097Y129050D02*
X535722Y127675D01*
G01X536872Y127198D02*
Y125452D01*
G01X535722Y127675D02*
Y124975D01*
G01X536872Y125452D02*
X537574Y124750D01*
G01X535722Y124975D02*
X537097Y123600D01*
G01X537574Y124750D02*
X539717D01*
G01X537097Y123600D02*
X539240D01*
G01X539717Y124750D02*
X541092Y123375D01*
G01X539240Y123600D02*
X539942Y122898D01*
G01X541092Y120918D02*
X539717Y119543D01*
G01X539942Y121395D02*
X539240Y120693D01*
G01X539717Y119543D02*
X537372D01*
G01X539240Y120693D02*
X536895D01*
G01X537372Y119543D02*
X536872Y119043D01*
G01X536895Y120693D02*
X535722Y119520D01*
G01X536872Y119043D02*
Y115820D01*
G01X535722Y119520D02*
Y115343D01*
G01X536872Y115820D02*
X537692Y115000D01*
G01X535722Y115343D02*
X536392Y114673D01*
G01X526913Y157406D02*
X540992Y143327D01*
G01X521242Y161450D02*
X539842Y142850D01*
G01D02*
Y139500D01*
G01X540992Y139023D02*
X538661Y136692D01*
G01X539842Y139500D02*
X537511Y137169D01*
G01X538661Y136692D02*
Y133458D01*
G01X537511Y137169D02*
Y135500D01*
G01X533613Y157006D02*
X534320Y156299D01*
G01X535735Y154884D02*
X536442Y154177D01*
G01X537857Y152762D02*
X544809Y145810D01*
G01X525942Y163050D02*
X543659Y145333D01*
G01X525942Y163050D02*
X543659Y145333D01*
G01X525942Y163050D02*
X543659Y145333D01*
G01X525942Y163050D02*
X543659Y145333D01*
G01X525942Y163050D02*
X543659Y145333D01*
G01X533613Y157006D02*
X534320Y156299D01*
G01X525942Y163050D02*
X543659Y145333D01*
G01X535735Y154884D02*
X536442Y154177D01*
G01X525942Y163050D02*
X543659Y145333D01*
G01X537857Y152762D02*
X544809Y145810D01*
G01X533613Y157006D02*
X534320Y156299D01*
G01X535735Y154884D02*
X536442Y154177D01*
G01X537857Y152762D02*
X544809Y145810D01*
G01X525942Y163050D02*
X543659Y145333D01*
G01X525942Y163050D02*
X543659Y145333D01*
G01X525942Y163050D02*
X543659Y145333D01*
G01X525942Y163050D02*
X543659Y145333D01*
G01X525942Y163050D02*
X543659Y145333D01*
G01X533613Y157006D02*
X534320Y156299D01*
G01X525942Y163050D02*
X543659Y145333D01*
G01X535735Y154884D02*
X536442Y154177D01*
G01X525942Y163050D02*
X543659Y145333D01*
G01X537857Y152762D02*
X544809Y145810D01*
G01X521242Y164900D02*
Y161450D01*
G01X522392Y164900D02*
Y161927D01*
G01D02*
X523099Y161220D01*
G01X524514Y159805D02*
X525498Y158821D01*
G01X527092Y164800D02*
Y163527D01*
G01X525942Y164800D02*
Y163050D01*
G01X527092Y163527D02*
X527799Y162820D01*
G01X529214Y161405D02*
X529998Y160621D01*
G01X531413Y159206D02*
X532198Y158421D01*
G01X522392Y164900D02*
Y161927D01*
G01X521242Y164900D02*
Y161450D01*
G01X522392Y161927D02*
X523099Y161220D01*
G01X524514Y159805D02*
X525498Y158821D01*
G01X525942Y164800D02*
Y163050D01*
G01X527092Y164800D02*
Y163527D01*
G01D02*
X527799Y162820D01*
G01X529214Y161405D02*
X529998Y160621D01*
G01X531413Y159206D02*
X532198Y158421D01*
G01X521242Y164900D02*
Y161450D01*
G01X522392Y164900D02*
Y161927D01*
G01D02*
X523099Y161220D01*
G01X524514Y159805D02*
X525498Y158821D01*
G01X522392Y164900D02*
Y161927D01*
G01X521242Y164900D02*
Y161450D01*
G01X522392Y161927D02*
X523099Y161220D01*
G01X524514Y159805D02*
X525498Y158821D01*
G01X521242Y164900D02*
Y161450D01*
G01X522392Y164900D02*
Y161927D01*
G01D02*
X523099Y161220D01*
G01X524514Y159805D02*
X525498Y158821D01*
G01X522392Y164900D02*
Y161927D01*
G01X521242Y164900D02*
Y161450D01*
G01X522392Y161927D02*
X523099Y161220D01*
G01X524514Y159805D02*
X525498Y158821D01*
G01X527092Y164800D02*
Y163527D01*
G01X525942Y164800D02*
Y163050D01*
G01X527092Y163527D02*
X527799Y162820D01*
G01X529214Y161405D02*
X529998Y160621D01*
G01X531413Y159206D02*
X532198Y158421D01*
G01X525942Y164800D02*
Y163050D01*
G01X527092Y164800D02*
Y163527D01*
G01D02*
X527799Y162820D01*
G01X529214Y161405D02*
X529998Y160621D01*
G01X531413Y159206D02*
X532198Y158421D01*
G01X527092Y164800D02*
Y163527D01*
G01X525942Y164800D02*
Y163050D01*
G01X527092Y163527D02*
X527799Y162820D01*
G01X529214Y161405D02*
X529998Y160621D01*
G01X531413Y159206D02*
X532198Y158421D01*
G01X525942Y164800D02*
Y163050D01*
G01X527092Y164800D02*
Y163527D01*
G01D02*
X527799Y162820D01*
G01X529214Y161405D02*
X529998Y160621D01*
G01X531413Y159206D02*
X532198Y158421D01*
G01X526578Y435813D02*
X527285Y436520D01*
G01X528700Y437935D02*
X529407Y438642D01*
G01X530822Y440057D02*
X531529Y440764D01*
G01X532944Y442179D02*
X533651Y442886D01*
G01X535066Y444301D02*
X535773Y445008D01*
G01X537188Y446423D02*
X539892Y449127D01*
G01X527392Y435000D02*
X541042Y448650D01*
G01X539892Y449127D02*
Y480828D01*
G01X527392Y435000D02*
X541042Y448650D01*
G01X526578Y435813D02*
X527285Y436520D01*
G01X527392Y435000D02*
X541042Y448650D01*
G01X528700Y437935D02*
X529407Y438642D01*
G01X527392Y435000D02*
X541042Y448650D01*
G01X530822Y440057D02*
X531529Y440764D01*
G01X527392Y435000D02*
X541042Y448650D01*
G01X532944Y442179D02*
X533651Y442886D01*
G01X527392Y435000D02*
X541042Y448650D01*
G01X535066Y444301D02*
X535773Y445008D01*
G01X527392Y435000D02*
X541042Y448650D01*
G01X537188Y446423D02*
X539892Y449127D01*
G01D02*
Y480828D01*
G01X479660Y450796D02*
X480154Y451290D01*
G01X481357Y452494D02*
X481851Y452988D01*
G01X483055Y454192D02*
X483549Y454686D01*
G01X484753Y455890D02*
X485247Y456384D01*
G01X486451Y457588D02*
X486945Y458082D01*
G01X488149Y459286D02*
X488643Y459780D01*
G01X489847Y460984D02*
X490341Y461478D01*
G01X491547Y462682D02*
X492041Y463176D01*
G01X493245Y464380D02*
X494215Y465350D01*
G01X494692Y464200D02*
X498092D01*
G01D02*
X508285Y474393D01*
G01X529628Y432900D02*
X530334Y433607D01*
G01X531749Y435022D02*
X532455Y435729D01*
G01X533870Y437144D02*
X534576Y437851D01*
G01X535991Y439266D02*
X536697Y439973D01*
G01X538112Y441388D02*
X538818Y442095D01*
G01X545362Y447011D02*
X530392Y432041D01*
G01X479660Y450796D02*
X480154Y451290D01*
G01X481357Y452494D02*
X481851Y452988D01*
G01X483055Y454192D02*
X483549Y454686D01*
G01X484753Y455890D02*
X485247Y456384D01*
G01X486451Y457588D02*
X486945Y458082D01*
G01X488149Y459286D02*
X488643Y459780D01*
G01X489847Y460984D02*
X490341Y461478D01*
G01X491547Y462682D02*
X492041Y463176D01*
G01X493245Y464380D02*
X494215Y465350D01*
G01X494692Y464200D02*
X498092D01*
G01D02*
X508285Y474393D01*
G01X498092Y464200D02*
X508285Y474393D01*
G01X498092Y464200D02*
X508285Y474393D01*
G01X498092Y464200D02*
X508285Y474393D01*
G01X545362Y447011D02*
X530392Y432041D01*
G01X529628Y432900D02*
X530334Y433607D01*
G01X545362Y447011D02*
X530392Y432041D01*
G01X531749Y435022D02*
X532455Y435729D01*
G01X545362Y447011D02*
X530392Y432041D01*
G01X533870Y437144D02*
X534576Y437851D01*
G01X545362Y447011D02*
X530392Y432041D01*
G01X535991Y439266D02*
X536697Y439973D01*
G01X545362Y447011D02*
X530392Y432041D01*
G01X538112Y441388D02*
X538818Y442095D01*
G01X545362Y447011D02*
X530392Y432041D01*
G01X545362Y447011D02*
X530392Y432041D01*
G01X526578Y435813D02*
X527285Y436520D01*
G01X528700Y437935D02*
X529407Y438642D01*
G01X530822Y440057D02*
X531529Y440764D01*
G01X532944Y442179D02*
X533651Y442886D01*
G01X535066Y444301D02*
X535773Y445008D01*
G01X537188Y446423D02*
X539892Y449127D01*
G01X527392Y435000D02*
X541042Y448650D01*
G01X539892Y449127D02*
Y480828D01*
G01X479660Y450796D02*
X480154Y451290D01*
G01X481357Y452494D02*
X481851Y452988D01*
G01X483055Y454192D02*
X483549Y454686D01*
G01X484753Y455890D02*
X485247Y456384D01*
G01X486451Y457588D02*
X486945Y458082D01*
G01X488149Y459286D02*
X488643Y459780D01*
G01X489847Y460984D02*
X490341Y461478D01*
G01X491547Y462682D02*
X492041Y463176D01*
G01X493245Y464380D02*
X494215Y465350D01*
G01X494692Y464200D02*
X498092D01*
G01D02*
X508285Y474393D01*
G01X498092Y464200D02*
X508285Y474393D01*
G01X498092Y464200D02*
X508285Y474393D01*
G01X498092Y464200D02*
X508285Y474393D01*
G01X527392Y435000D02*
X541042Y448650D01*
G01X526578Y435813D02*
X527285Y436520D01*
G01X527392Y435000D02*
X541042Y448650D01*
G01X528700Y437935D02*
X529407Y438642D01*
G01X527392Y435000D02*
X541042Y448650D01*
G01X530822Y440057D02*
X531529Y440764D01*
G01X527392Y435000D02*
X541042Y448650D01*
G01X532944Y442179D02*
X533651Y442886D01*
G01X527392Y435000D02*
X541042Y448650D01*
G01X535066Y444301D02*
X535773Y445008D01*
G01X527392Y435000D02*
X541042Y448650D01*
G01X537188Y446423D02*
X539892Y449127D01*
G01D02*
Y480828D01*
G01X479660Y450796D02*
X480154Y451290D01*
G01X481357Y452494D02*
X481851Y452988D01*
G01X483055Y454192D02*
X483549Y454686D01*
G01X484753Y455890D02*
X485247Y456384D01*
G01X486451Y457588D02*
X486945Y458082D01*
G01X488149Y459286D02*
X488643Y459780D01*
G01X489847Y460984D02*
X490341Y461478D01*
G01X491547Y462682D02*
X492041Y463176D01*
G01X493245Y464380D02*
X494215Y465350D01*
G01X494692Y464200D02*
X498092D01*
G01D02*
X508285Y474393D01*
G01X545362Y447011D02*
X530392Y432041D01*
G01X529628Y432900D02*
X530334Y433607D01*
G01X545362Y447011D02*
X530392Y432041D01*
G01X531749Y435022D02*
X532455Y435729D01*
G01X545362Y447011D02*
X530392Y432041D01*
G01X533870Y437144D02*
X534576Y437851D01*
G01X545362Y447011D02*
X530392Y432041D01*
G01X535991Y439266D02*
X536697Y439973D01*
G01X545362Y447011D02*
X530392Y432041D01*
G01X538112Y441388D02*
X538818Y442095D01*
G01X545362Y447011D02*
X530392Y432041D01*
G01X545362Y447011D02*
X530392Y432041D01*
G01X529628Y432900D02*
X530334Y433607D01*
G01X531749Y435022D02*
X532455Y435729D01*
G01X533870Y437144D02*
X534576Y437851D01*
G01X535991Y439266D02*
X536697Y439973D01*
G01X538112Y441388D02*
X538818Y442095D01*
G01X545362Y447011D02*
X530392Y432041D01*
G01X492362Y469970D02*
X494235D01*
G01X492839Y468820D02*
X494712D01*
G01X494235Y469970D02*
X495392Y471127D01*
G01X497165Y472900D02*
X498092Y473827D01*
G01X499765Y475500D02*
X500992Y476727D01*
G01X502631Y478366D02*
X503422Y479157D01*
G01X494712Y468820D02*
X504572Y478680D01*
G01X503422Y479157D02*
Y492823D01*
G01X504572Y478680D02*
Y493300D01*
G01X503422Y492823D02*
X502778Y493467D01*
G01X504572Y493300D02*
X503255Y494617D01*
G01X539892Y480828D02*
X540266Y481202D01*
G01Y491313D02*
X538370Y493209D01*
G01X492839Y468820D02*
X494712D01*
G01X492362Y469970D02*
X494235D01*
G01X494712Y468820D02*
X504572Y478680D01*
G01X494235Y469970D02*
X495392Y471127D01*
G01X494712Y468820D02*
X504572Y478680D01*
G01X497165Y472900D02*
X498092Y473827D01*
G01X494712Y468820D02*
X504572Y478680D01*
G01X499765Y475500D02*
X500992Y476727D01*
G01X494712Y468820D02*
X504572Y478680D01*
G01X502631Y478366D02*
X503422Y479157D01*
G01X504572Y478680D02*
Y493300D01*
G01X503422Y479157D02*
Y492823D01*
G01X504572Y493300D02*
X503255Y494617D01*
G01X503422Y492823D02*
X502778Y493467D01*
G01X539892Y480828D02*
X540266Y481202D01*
G01Y491313D02*
X538370Y493209D01*
G01X494215Y465350D02*
X497615D01*
G01D02*
X498392Y466127D01*
G01X499965Y467700D02*
X500792Y468527D01*
G01X502365Y470100D02*
X503192Y470927D01*
G01X504765Y472500D02*
X507135Y474870D01*
G01D02*
Y475856D01*
G01Y477644D02*
Y480457D01*
G01X508285Y474393D02*
Y479980D01*
G01X507135Y480457D02*
X508587Y481909D01*
G01X508285Y479980D02*
X509064Y480759D01*
G01X508587Y481909D02*
X510292D01*
G01X509064Y480759D02*
X510769D01*
G01X508587Y481909D02*
X510292D01*
G01D02*
X510792Y482409D01*
G01X510769Y480759D02*
X511942Y481932D01*
G01X510792Y482409D02*
Y484659D01*
G01X511942Y481932D02*
Y485136D01*
G01X510792Y484659D02*
X510292Y485159D01*
G01X511942Y485136D02*
X510769Y486309D01*
G01X510292Y485159D02*
X508591D01*
G01X510769Y486309D02*
X509068D01*
G01X508591Y485159D02*
X507342Y486408D01*
G01X509068Y486309D02*
X508492Y486885D01*
G01X507342Y486408D02*
Y488577D01*
G01X508492Y486885D02*
Y488100D01*
G01X507342Y488577D02*
X508616Y489851D01*
G01X508492Y488100D02*
X509766Y489374D01*
G01X508616Y489851D02*
Y492568D01*
G01X509766Y489374D02*
Y493045D01*
G01X508616Y492568D02*
X507617Y493567D01*
G01X509766Y493045D02*
X506644Y496167D01*
G01X494215Y465350D02*
X497615D01*
G01D02*
X498392Y466127D01*
G01X499965Y467700D02*
X500792Y468527D01*
G01X502365Y470100D02*
X503192Y470927D01*
G01X504765Y472500D02*
X507135Y474870D01*
G01X508285Y474393D02*
Y479980D01*
G01X507135Y474870D02*
Y475856D01*
G01X508285Y474393D02*
Y479980D01*
G01X507135Y477644D02*
Y480457D01*
G01X508285Y479980D02*
X509064Y480759D01*
G01X507135Y480457D02*
X508587Y481909D01*
G01X509064Y480759D02*
X510769D01*
G01D02*
X511942Y481932D01*
G01X508587Y481909D02*
X510292D01*
G01X510769Y480759D02*
X511942Y481932D01*
G01X510292Y481909D02*
X510792Y482409D01*
G01X511942Y481932D02*
Y485136D01*
G01X510792Y482409D02*
Y484659D01*
G01X511942Y485136D02*
X510769Y486309D01*
G01X510792Y484659D02*
X510292Y485159D01*
G01X510769Y486309D02*
X509068D01*
G01X510292Y485159D02*
X508591D01*
G01X509068Y486309D02*
X508492Y486885D01*
G01X508591Y485159D02*
X507342Y486408D01*
G01X508492Y486885D02*
Y488100D01*
G01X507342Y486408D02*
Y488577D01*
G01X508492Y488100D02*
X509766Y489374D01*
G01X507342Y488577D02*
X508616Y489851D01*
G01X509766Y489374D02*
Y493045D01*
G01X508616Y489851D02*
Y492568D01*
G01X509766Y493045D02*
X506644Y496167D01*
G01X508616Y492568D02*
X507617Y493567D01*
G01X492362Y469970D02*
X494235D01*
G01X492839Y468820D02*
X494712D01*
G01X494235Y469970D02*
X495392Y471127D01*
G01X497165Y472900D02*
X498092Y473827D01*
G01X499765Y475500D02*
X500992Y476727D01*
G01X502631Y478366D02*
X503422Y479157D01*
G01X494712Y468820D02*
X504572Y478680D01*
G01X503422Y479157D02*
Y492823D01*
G01X504572Y478680D02*
Y493300D01*
G01X503422Y492823D02*
X502778Y493467D01*
G01X504572Y493300D02*
X503255Y494617D01*
G01X539892Y480828D02*
X540266Y481202D01*
G01Y491313D02*
X538370Y493209D01*
G01X494215Y465350D02*
X497615D01*
G01D02*
X498392Y466127D01*
G01X499965Y467700D02*
X500792Y468527D01*
G01X502365Y470100D02*
X503192Y470927D01*
G01X504765Y472500D02*
X507135Y474870D01*
G01X508285Y474393D02*
Y479980D01*
G01X507135Y474870D02*
Y475856D01*
G01X508285Y474393D02*
Y479980D01*
G01X507135Y477644D02*
Y480457D01*
G01X508285Y479980D02*
X509064Y480759D01*
G01X507135Y480457D02*
X508587Y481909D01*
G01X509064Y480759D02*
X510769D01*
G01D02*
X511942Y481932D01*
G01X508587Y481909D02*
X510292D01*
G01X510769Y480759D02*
X511942Y481932D01*
G01X510292Y481909D02*
X510792Y482409D01*
G01X511942Y481932D02*
Y485136D01*
G01X510792Y482409D02*
Y484659D01*
G01X511942Y485136D02*
X510769Y486309D01*
G01X510792Y484659D02*
X510292Y485159D01*
G01X510769Y486309D02*
X509068D01*
G01X510292Y485159D02*
X508591D01*
G01X509068Y486309D02*
X508492Y486885D01*
G01X508591Y485159D02*
X507342Y486408D01*
G01X508492Y486885D02*
Y488100D01*
G01X507342Y486408D02*
Y488577D01*
G01X508492Y488100D02*
X509766Y489374D01*
G01X507342Y488577D02*
X508616Y489851D01*
G01X509766Y489374D02*
Y493045D01*
G01X508616Y489851D02*
Y492568D01*
G01X509766Y493045D02*
X506644Y496167D01*
G01X508616Y492568D02*
X507617Y493567D01*
G01X492839Y468820D02*
X494712D01*
G01X492362Y469970D02*
X494235D01*
G01X494712Y468820D02*
X504572Y478680D01*
G01X494235Y469970D02*
X495392Y471127D01*
G01X494712Y468820D02*
X504572Y478680D01*
G01X497165Y472900D02*
X498092Y473827D01*
G01X494712Y468820D02*
X504572Y478680D01*
G01X499765Y475500D02*
X500992Y476727D01*
G01X494712Y468820D02*
X504572Y478680D01*
G01X502631Y478366D02*
X503422Y479157D01*
G01X504572Y478680D02*
Y493300D01*
G01X503422Y479157D02*
Y492823D01*
G01X504572Y493300D02*
X503255Y494617D01*
G01X503422Y492823D02*
X502778Y493467D01*
G01X539892Y480828D02*
X540266Y481202D01*
G01Y491313D02*
X538370Y493209D01*
G01X494215Y465350D02*
X497615D01*
G01D02*
X498392Y466127D01*
G01X499965Y467700D02*
X500792Y468527D01*
G01X502365Y470100D02*
X503192Y470927D01*
G01X504765Y472500D02*
X507135Y474870D01*
G01D02*
Y475856D01*
G01Y477644D02*
Y480457D01*
G01X508285Y474393D02*
Y479980D01*
G01X507135Y480457D02*
X508587Y481909D01*
G01X508285Y479980D02*
X509064Y480759D01*
G01X508587Y481909D02*
X510292D01*
G01X509064Y480759D02*
X510769D01*
G01X508587Y481909D02*
X510292D01*
G01D02*
X510792Y482409D01*
G01X510769Y480759D02*
X511942Y481932D01*
G01X510792Y482409D02*
Y484659D01*
G01X511942Y481932D02*
Y485136D01*
G01X510792Y484659D02*
X510292Y485159D01*
G01X511942Y485136D02*
X510769Y486309D01*
G01X510292Y485159D02*
X508591D01*
G01X510769Y486309D02*
X509068D01*
G01X508591Y485159D02*
X507342Y486408D01*
G01X509068Y486309D02*
X508492Y486885D01*
G01X507342Y486408D02*
Y488577D01*
G01X508492Y486885D02*
Y488100D01*
G01X507342Y488577D02*
X508616Y489851D01*
G01X508492Y488100D02*
X509766Y489374D01*
G01X508616Y489851D02*
Y492568D01*
G01X509766Y489374D02*
Y493045D01*
G01X508616Y492568D02*
X507617Y493567D01*
G01X509766Y493045D02*
X506644Y496167D01*
G01X774974Y-40725D02*
X583682D01*
G01X774974Y-41875D02*
X583682D01*
G01Y-40725D02*
G03Y-46975I0J-3125D01*
G01Y-41875D02*
G03Y-45825I0J-1975D01*
G01Y-46975D02*
X776815D01*
G01X583682Y-45825D02*
X776815D01*
G01Y-50925D02*
X577262D01*
G01X776815Y-52075D02*
X576785D01*
G01X577262Y-50925D02*
X573063Y-46726D01*
G01X576785Y-52075D02*
X572586Y-47876D01*
G01X774974Y-41875D02*
X583682D01*
G01X774974Y-40725D02*
X583682D01*
G01Y-41875D02*
G03Y-45825I0J-1975D01*
G01Y-40725D02*
G03Y-46975I0J-3125D01*
G01Y-45825D02*
X776815D01*
G01X583682Y-46975D02*
X776815D01*
G01Y-52075D02*
X576785D01*
G01X776815Y-50925D02*
X577262D01*
G01X576785Y-52075D02*
X572586Y-47876D01*
G01X577262Y-50925D02*
X573063Y-46726D01*
G01X540992Y141000D02*
Y139023D01*
G01Y131127D02*
Y129275D01*
G01X539942Y122898D02*
Y121395D01*
G01X541092Y123375D02*
Y120918D01*
G01X540992Y143327D02*
Y141000D01*
G01X544809Y135000D02*
Y119445D01*
G01X543659Y126500D02*
Y119922D01*
G01X544809Y119445D02*
X542856Y117492D01*
G01X543659Y119922D02*
X541706Y117969D01*
G01X542856Y117492D02*
Y116036D01*
G01X541706Y117969D02*
Y109404D01*
G01X544809Y145810D02*
Y135000D01*
G01X543659Y145333D02*
Y126500D01*
G01X540992Y131127D02*
Y129275D01*
G01X541092Y123375D02*
Y120918D01*
G01X539942Y122898D02*
Y121395D01*
G01X540992Y141000D02*
Y139023D01*
G01Y143327D02*
Y141000D01*
G01X543659Y126500D02*
Y119922D01*
G01X544809Y135000D02*
Y119445D01*
G01X543659Y119922D02*
X541706Y117969D01*
G01X544809Y119445D02*
X542856Y117492D01*
G01X541706Y117969D02*
Y109404D01*
G01X542856Y117492D02*
Y116036D01*
G01X543659Y145333D02*
Y126500D01*
G01X544809Y145810D02*
Y135000D01*
G01X540992Y141000D02*
Y139023D01*
G01Y131127D02*
Y129275D01*
G01X539942Y122898D02*
Y121395D01*
G01X541092Y123375D02*
Y120918D01*
G01X540992Y143327D02*
Y141000D01*
G01Y131127D02*
Y129275D01*
G01X541092Y123375D02*
Y120918D01*
G01X539942Y122898D02*
Y121395D01*
G01X540992Y141000D02*
Y139023D01*
G01Y143327D02*
Y141000D01*
G01D02*
Y139023D01*
G01Y131127D02*
Y129275D01*
G01X539942Y122898D02*
Y121395D01*
G01X541092Y123375D02*
Y120918D01*
G01X540992Y143327D02*
Y141000D01*
G01Y131127D02*
Y129275D01*
G01X541092Y123375D02*
Y120918D01*
G01X539942Y122898D02*
Y121395D01*
G01X540992Y141000D02*
Y139023D01*
G01Y143327D02*
Y141000D01*
G01X544809Y135000D02*
Y119445D01*
G01X543659Y126500D02*
Y119922D01*
G01X544809Y119445D02*
X542856Y117492D01*
G01X543659Y119922D02*
X541706Y117969D01*
G01X542856Y117492D02*
Y116036D01*
G01X541706Y117969D02*
Y109404D01*
G01X544809Y145810D02*
Y135000D01*
G01X543659Y145333D02*
Y126500D01*
G01D02*
Y119922D01*
G01X544809Y135000D02*
Y119445D01*
G01X543659Y119922D02*
X541706Y117969D01*
G01X544809Y119445D02*
X542856Y117492D01*
G01X541706Y117969D02*
Y109404D01*
G01X542856Y117492D02*
Y116036D01*
G01X543659Y145333D02*
Y126500D01*
G01X544809Y145810D02*
Y135000D01*
G01D02*
Y119445D01*
G01X543659Y126500D02*
Y119922D01*
G01X544809Y119445D02*
X542856Y117492D01*
G01X543659Y119922D02*
X541706Y117969D01*
G01X542856Y117492D02*
Y116036D01*
G01X541706Y117969D02*
Y109404D01*
G01X544809Y145810D02*
Y135000D01*
G01X543659Y145333D02*
Y126500D01*
G01D02*
Y119922D01*
G01X544809Y135000D02*
Y119445D01*
G01X543659Y119922D02*
X541706Y117969D01*
G01X544809Y119445D02*
X542856Y117492D01*
G01X541706Y117969D02*
Y109404D01*
G01X542856Y117492D02*
Y116036D01*
G01X543659Y145333D02*
Y126500D01*
G01X544809Y145810D02*
Y135000D01*
G01X541042Y448650D02*
Y480351D01*
G01Y448650D02*
Y480351D01*
G01X544212Y447490D02*
Y450408D01*
G01Y452408D02*
Y453408D01*
G01Y455408D02*
Y456408D01*
G01Y458408D02*
Y459500D01*
G01Y461500D02*
Y462500D01*
G01Y464500D02*
Y465500D01*
G01X545362Y477546D02*
Y447011D01*
G01X540233Y443510D02*
X540940Y444217D01*
G01X542355Y445632D02*
X544212Y447490D01*
G01X540233Y443510D02*
X540940Y444217D01*
G01X542355Y445632D02*
X544212Y447490D01*
G01X545362Y477546D02*
Y447011D01*
G01X544212Y447490D02*
Y450408D01*
G01X545362Y477546D02*
Y447011D01*
G01X544212Y452408D02*
Y453408D01*
G01X545362Y477546D02*
Y447011D01*
G01X544212Y455408D02*
Y456408D01*
G01X545362Y477546D02*
Y447011D01*
G01X544212Y458408D02*
Y459500D01*
G01X545362Y477546D02*
Y447011D01*
G01X544212Y461500D02*
Y462500D01*
G01X545362Y477546D02*
Y447011D01*
G01X544212Y464500D02*
Y465500D01*
G01X545362Y477546D02*
Y447011D01*
G01Y477546D02*
Y447011D01*
G01Y477546D02*
Y447011D01*
G01Y477546D02*
Y447011D01*
G01X541042Y448650D02*
Y480351D01*
G01Y448650D02*
Y480351D01*
G01X540233Y443510D02*
X540940Y444217D01*
G01X542355Y445632D02*
X544212Y447490D01*
G01X545362Y477546D02*
Y447011D01*
G01X544212Y447490D02*
Y450408D01*
G01X545362Y477546D02*
Y447011D01*
G01X544212Y452408D02*
Y453408D01*
G01X545362Y477546D02*
Y447011D01*
G01X544212Y455408D02*
Y456408D01*
G01X545362Y477546D02*
Y447011D01*
G01X544212Y458408D02*
Y459500D01*
G01X545362Y477546D02*
Y447011D01*
G01X544212Y461500D02*
Y462500D01*
G01X545362Y477546D02*
Y447011D01*
G01X544212Y464500D02*
Y465500D01*
G01X545362Y477546D02*
Y447011D01*
G01Y477546D02*
Y447011D01*
G01Y477546D02*
Y447011D01*
G01Y477546D02*
Y447011D01*
G01X544212Y447490D02*
Y450408D01*
G01Y452408D02*
Y453408D01*
G01Y455408D02*
Y456408D01*
G01Y458408D02*
Y459500D01*
G01Y461500D02*
Y462500D01*
G01Y464500D02*
Y465500D01*
G01X545362Y477546D02*
Y447011D01*
G01X540233Y443510D02*
X540940Y444217D01*
G01X542355Y445632D02*
X544212Y447490D01*
G01X541042Y480351D02*
X541416Y480725D01*
G01X540266Y481202D02*
Y491313D01*
G01X541416Y480725D02*
Y491790D01*
G01D02*
X540266Y492940D01*
G01X541042Y480351D02*
X541416Y480725D01*
G01D02*
Y491790D01*
G01X540266Y481202D02*
Y491313D01*
G01X541416Y491790D02*
X540266Y492940D01*
G01X545566Y486801D02*
Y487600D01*
G01Y489600D02*
Y492426D01*
G01X546716Y492920D02*
Y486324D01*
G01X544166Y485401D02*
X545566Y486801D01*
G01X546716Y486324D02*
X545316Y484924D01*
G01X544166Y483073D02*
Y485401D01*
G01X545316Y484924D02*
Y483550D01*
G01X545489Y481750D02*
X544166Y483073D01*
G01X545316Y483550D02*
X545966Y482900D01*
G01X546660Y481750D02*
X545489D01*
G01D02*
X544166Y483073D01*
G01X545966Y482900D02*
X547137D01*
G01X547160Y481250D02*
X546660Y481750D01*
G01D02*
X545489D01*
G01X547137Y482900D02*
X548310Y481727D01*
G01X547160Y479600D02*
Y481250D01*
G01X548310Y481727D02*
Y479123D01*
G01X545289Y479100D02*
X546660D01*
G01D02*
X547160Y479600D01*
G01X548310Y479123D02*
X547137Y477950D01*
G01X545289Y479100D02*
X546660D01*
G01X547137Y477950D02*
X545766D01*
G01X544212Y478023D02*
X545289Y479100D01*
G01X545766Y477950D02*
X545362Y477546D01*
G01X544212Y467500D02*
Y468500D01*
G01Y470500D02*
Y471500D01*
G01Y473500D02*
Y474500D01*
G01Y476500D02*
Y478023D01*
G01Y467500D02*
Y468500D01*
G01Y470500D02*
Y471500D01*
G01Y473500D02*
Y474500D01*
G01Y476500D02*
Y478023D01*
G01X545766Y477950D02*
X545362Y477546D01*
G01X544212Y478023D02*
X545289Y479100D01*
G01X548310Y479123D02*
X547137Y477950D01*
G01D02*
X545766D01*
G01X545289Y479100D02*
X546660D01*
G01X548310Y479123D02*
X547137Y477950D01*
G01X546660Y479100D02*
X547160Y479600D01*
G01X548310Y481727D02*
Y479123D01*
G01X547160Y479600D02*
Y481250D01*
G01X547137Y482900D02*
X548310Y481727D01*
G01X547160Y481250D02*
X546660Y481750D01*
G01X545966Y482900D02*
X547137D01*
G01D02*
X548310Y481727D01*
G01X546660Y481750D02*
X545489D01*
G01X545316Y483550D02*
X545966Y482900D01*
G01D02*
X547137D01*
G01X545489Y481750D02*
X544166Y483073D01*
G01X545316Y484924D02*
Y483550D01*
G01X544166Y483073D02*
Y485401D01*
G01X546716Y486324D02*
X545316Y484924D01*
G01X544166Y485401D02*
X545566Y486801D01*
G01X546716Y492920D02*
Y486324D01*
G01X545566Y486801D02*
Y487600D01*
G01X546716Y492920D02*
Y486324D01*
G01X545566Y489600D02*
Y492426D01*
G01X541042Y480351D02*
X541416Y480725D01*
G01X540266Y481202D02*
Y491313D01*
G01X541416Y480725D02*
Y491790D01*
G01D02*
X540266Y492940D01*
G01X541042Y480351D02*
X541416Y480725D01*
G01D02*
Y491790D01*
G01X540266Y481202D02*
Y491313D01*
G01X541416Y491790D02*
X540266Y492940D01*
G01X544212Y467500D02*
Y468500D01*
G01Y470500D02*
Y471500D01*
G01Y473500D02*
Y474500D01*
G01Y476500D02*
Y478023D01*
G01X545766Y477950D02*
X545362Y477546D01*
G01X544212Y478023D02*
X545289Y479100D01*
G01X548310Y479123D02*
X547137Y477950D01*
G01D02*
X545766D01*
G01X545289Y479100D02*
X546660D01*
G01X548310Y479123D02*
X547137Y477950D01*
G01X546660Y479100D02*
X547160Y479600D01*
G01X548310Y481727D02*
Y479123D01*
G01X547160Y479600D02*
Y481250D01*
G01X547137Y482900D02*
X548310Y481727D01*
G01X547160Y481250D02*
X546660Y481750D01*
G01X545966Y482900D02*
X547137D01*
G01D02*
X548310Y481727D01*
G01X546660Y481750D02*
X545489D01*
G01X545316Y483550D02*
X545966Y482900D01*
G01D02*
X547137D01*
G01X545489Y481750D02*
X544166Y483073D01*
G01X545316Y484924D02*
Y483550D01*
G01X544166Y483073D02*
Y485401D01*
G01X546716Y486324D02*
X545316Y484924D01*
G01X544166Y485401D02*
X545566Y486801D01*
G01X546716Y492920D02*
Y486324D01*
G01X545566Y486801D02*
Y487600D01*
G01X546716Y492920D02*
Y486324D01*
G01X545566Y489600D02*
Y492426D01*
G01Y486801D02*
Y487600D01*
G01Y489600D02*
Y492426D01*
G01X546716Y492920D02*
Y486324D01*
G01X544166Y485401D02*
X545566Y486801D01*
G01X546716Y486324D02*
X545316Y484924D01*
G01X544166Y483073D02*
Y485401D01*
G01X545316Y484924D02*
Y483550D01*
G01X545489Y481750D02*
X544166Y483073D01*
G01X545316Y483550D02*
X545966Y482900D01*
G01X546660Y481750D02*
X545489D01*
G01D02*
X544166Y483073D01*
G01X545966Y482900D02*
X547137D01*
G01X547160Y481250D02*
X546660Y481750D01*
G01D02*
X545489D01*
G01X547137Y482900D02*
X548310Y481727D01*
G01X547160Y479600D02*
Y481250D01*
G01X548310Y481727D02*
Y479123D01*
G01X545289Y479100D02*
X546660D01*
G01D02*
X547160Y479600D01*
G01X548310Y479123D02*
X547137Y477950D01*
G01X545289Y479100D02*
X546660D01*
G01X547137Y477950D02*
X545766D01*
G01X544212Y478023D02*
X545289Y479100D01*
G01X545766Y477950D02*
X545362Y477546D01*
G01X544212Y467500D02*
Y468500D01*
G01Y470500D02*
Y471500D01*
G01Y473500D02*
Y474500D01*
G01Y476500D02*
Y478023D01*
G01X776815Y-46975D02*
G02Y-50925I0J-1975D01*
G01Y-45825D02*
G02Y-52075I0J-3125D01*
G01Y-45825D02*
G02Y-52075I0J-3125D01*
G01Y-46975D02*
G02Y-50925I0J-1975D01*
G01X821350Y93923D02*
X820592Y94681D01*
G01X821742Y95158D02*
X822500Y94400D01*
G01X821350Y93923D02*
X820592Y94681D01*
G01X821742Y95158D02*
X822500Y94400D01*
G01X821742Y95158D02*
X822500Y94400D01*
G01X821350Y93923D02*
X820592Y94681D01*
G01X821742Y95158D02*
X822500Y94400D01*
G01X821350Y93923D02*
X820592Y94681D01*
G01X821742Y95158D02*
X822500Y94400D01*
G01X821350Y93923D02*
X820592Y94681D01*
G01X834474Y154689D02*
X905076Y225291D01*
G01X905553Y224141D02*
X835624Y154212D01*
G01X834474Y133225D02*
Y154689D01*
G01X835624Y154212D02*
Y132748D01*
G01X833824Y132575D02*
X834474Y133225D01*
G01X835624Y132748D02*
X834301Y131425D01*
G01X831500Y132575D02*
X833824D01*
G01X834301Y131425D02*
X831977D01*
G01X830177Y131252D02*
X831500Y132575D01*
G01X831977Y131425D02*
X831327Y130775D01*
G01X830177Y128948D02*
Y131252D01*
G01X831327Y130775D02*
Y129425D01*
G01X831500Y127625D02*
X830177Y128948D01*
G01X831327Y129425D02*
X831977Y128775D01*
G01X833824Y127625D02*
X831500D01*
G01X831977Y128775D02*
X834301D01*
G01X834474Y126975D02*
X833824Y127625D01*
G01X834301Y128775D02*
X835624Y127452D01*
G01X834474Y122801D02*
Y126975D01*
G01X835624Y127452D02*
Y122324D01*
G01X831125Y119452D02*
X834474Y122801D01*
G01X820592Y108919D02*
X831125Y119452D01*
G01X835624Y122324D02*
X824204Y110904D01*
G01X820592Y108919D02*
X831125Y119452D01*
G01X822789Y109489D02*
X821742Y108442D01*
G01X820592Y94681D02*
Y108919D01*
G01X821742Y108442D02*
Y107158D01*
G01X820592Y94681D02*
Y108919D01*
G01X821742Y105158D02*
Y104158D01*
G01X820592Y94681D02*
Y108919D01*
G01X821742Y102158D02*
Y101158D01*
G01X820592Y94681D02*
Y108919D01*
G01X821742Y99158D02*
Y98158D01*
G01X820592Y94681D02*
Y108919D01*
G01X821742Y96158D02*
Y95158D01*
G01X834474Y154689D02*
X905076Y225291D01*
G01X905553Y224141D02*
X835624Y154212D01*
G01X834474Y133225D02*
Y154689D01*
G01X835624Y154212D02*
Y132748D01*
G01X833824Y132575D02*
X834474Y133225D01*
G01X835624Y132748D02*
X834301Y131425D01*
G01X831500Y132575D02*
X833824D01*
G01X834301Y131425D02*
X831977D01*
G01X830177Y131252D02*
X831500Y132575D01*
G01X831977Y131425D02*
X831327Y130775D01*
G01X830177Y128948D02*
Y131252D01*
G01X831327Y130775D02*
Y129425D01*
G01X831500Y127625D02*
X830177Y128948D01*
G01X831327Y129425D02*
X831977Y128775D01*
G01X833824Y127625D02*
X831500D01*
G01X831977Y128775D02*
X834301D01*
G01X834474Y126975D02*
X833824Y127625D01*
G01X834301Y128775D02*
X835624Y127452D01*
G01X834474Y122801D02*
Y126975D01*
G01X835624Y127452D02*
Y122324D01*
G01X831125Y119452D02*
X834474Y122801D01*
G01X820592Y108919D02*
X831125Y119452D01*
G01X835624Y122324D02*
X824204Y110904D01*
G01X820592Y108919D02*
X831125Y119452D01*
G01X822789Y109489D02*
X821742Y108442D01*
G01X820592Y94681D02*
Y108919D01*
G01X821742Y108442D02*
Y107158D01*
G01X820592Y94681D02*
Y108919D01*
G01X821742Y105158D02*
Y104158D01*
G01X820592Y94681D02*
Y108919D01*
G01X821742Y102158D02*
Y101158D01*
G01X820592Y94681D02*
Y108919D01*
G01X821742Y99158D02*
Y98158D01*
G01X820592Y94681D02*
Y108919D01*
G01X821742Y96158D02*
Y95158D01*
G01X839900Y152953D02*
X906863Y219916D01*
G01X906386Y221066D02*
X838750Y153430D01*
G01X839900Y150029D02*
Y152953D01*
G01X838750Y153430D02*
Y149552D01*
G01X840550Y149379D02*
X839900Y150029D01*
G01X838750Y149552D02*
X840073Y148229D01*
G01X843449Y149379D02*
X840550D01*
G01X840073Y148229D02*
X842972D01*
G01X844622Y148206D02*
X843449Y149379D01*
G01X842972Y148229D02*
X843472Y147729D01*
G01X844622Y145602D02*
Y148206D01*
G01X843472Y147729D02*
Y146079D01*
G01X843449Y144429D02*
X844622Y145602D01*
G01X843472Y146079D02*
X842972Y145579D01*
G01X840550Y144429D02*
X843449D01*
G01X842972Y145579D02*
X840073D01*
G01X839900Y143779D02*
X840550Y144429D01*
G01X840073Y145579D02*
X838750Y144256D01*
G01X839900Y140044D02*
Y143779D01*
G01X838750Y144256D02*
Y139567D01*
G01X840550Y139394D02*
X839900Y140044D01*
G01X838750Y139567D02*
X840073Y138244D01*
G01X842601Y139394D02*
X840550D01*
G01X840073Y138244D02*
X842124D01*
G01X843774Y138221D02*
X842601Y139394D01*
G01X842124Y138244D02*
X842624Y137744D01*
G01X843774Y135617D02*
Y138221D01*
G01X842624Y137744D02*
Y136094D01*
G01X842601Y134444D02*
X843774Y135617D01*
G01X842624Y136094D02*
X842124Y135594D01*
G01X840550Y134444D02*
X842601D01*
G01X842124Y135594D02*
X840073D01*
G01X839900Y133794D02*
X840550Y134444D01*
G01X840073Y135594D02*
X838750Y134271D01*
G01X839900Y119460D02*
Y121794D01*
G01Y123794D02*
Y124794D01*
G01Y126794D02*
Y127794D01*
G01Y129794D02*
Y130794D01*
G01Y132794D02*
Y133794D01*
G01X838750Y134271D02*
Y119937D01*
G01X829466Y109026D02*
X839900Y119460D01*
G01X826324Y105884D02*
X829466Y109026D01*
G01X838750Y119937D02*
X825174Y106361D01*
G01X826324Y97276D02*
Y105884D01*
G01X825174Y106361D02*
Y96799D01*
G01X827800Y95800D02*
X826324Y97276D01*
G01X825174Y96799D02*
X826504Y95469D01*
G01X839900Y152953D02*
X906863Y219916D01*
G01X906386Y221066D02*
X838750Y153430D01*
G01X839900Y150029D02*
Y152953D01*
G01X838750Y153430D02*
Y149552D01*
G01X840550Y149379D02*
X839900Y150029D01*
G01X838750Y149552D02*
X840073Y148229D01*
G01X843449Y149379D02*
X840550D01*
G01X840073Y148229D02*
X842972D01*
G01X844622Y148206D02*
X843449Y149379D01*
G01X842972Y148229D02*
X843472Y147729D01*
G01X844622Y145602D02*
Y148206D01*
G01X843472Y147729D02*
Y146079D01*
G01X843449Y144429D02*
X844622Y145602D01*
G01X843472Y146079D02*
X842972Y145579D01*
G01X840550Y144429D02*
X843449D01*
G01X842972Y145579D02*
X840073D01*
G01X839900Y143779D02*
X840550Y144429D01*
G01X840073Y145579D02*
X838750Y144256D01*
G01X839900Y140044D02*
Y143779D01*
G01X838750Y144256D02*
Y139567D01*
G01X840550Y139394D02*
X839900Y140044D01*
G01X838750Y139567D02*
X840073Y138244D01*
G01X842601Y139394D02*
X840550D01*
G01X840073Y138244D02*
X842124D01*
G01X843774Y138221D02*
X842601Y139394D01*
G01X842124Y138244D02*
X842624Y137744D01*
G01X843774Y135617D02*
Y138221D01*
G01X842624Y137744D02*
Y136094D01*
G01X842601Y134444D02*
X843774Y135617D01*
G01X842624Y136094D02*
X842124Y135594D01*
G01X840550Y134444D02*
X842601D01*
G01X842124Y135594D02*
X840073D01*
G01X839900Y133794D02*
X840550Y134444D01*
G01X840073Y135594D02*
X838750Y134271D01*
G01X839900Y119460D02*
Y121794D01*
G01Y123794D02*
Y124794D01*
G01Y126794D02*
Y127794D01*
G01Y129794D02*
Y130794D01*
G01Y132794D02*
Y133794D01*
G01X838750Y134271D02*
Y119937D01*
G01X829466Y109026D02*
X839900Y119460D01*
G01X826324Y105884D02*
X829466Y109026D01*
G01X838750Y119937D02*
X825174Y106361D01*
G01X826324Y97276D02*
Y105884D01*
G01X825174Y106361D02*
Y96799D01*
G01X827800Y95800D02*
X826324Y97276D01*
G01X825174Y96799D02*
X826504Y95469D01*
G01X835624Y122324D02*
X824204Y110904D01*
G01X831125Y119452D02*
X834474Y122801D01*
G01X835624Y127452D02*
Y122324D01*
G01X834474Y122801D02*
Y126975D01*
G01X834301Y128775D02*
X835624Y127452D01*
G01X834474Y126975D02*
X833824Y127625D01*
G01X831977Y128775D02*
X834301D01*
G01X833824Y127625D02*
X831500D01*
G01X831327Y129425D02*
X831977Y128775D01*
G01X831500Y127625D02*
X830177Y128948D01*
G01X831327Y130775D02*
Y129425D01*
G01X830177Y128948D02*
Y131252D01*
G01X831977Y131425D02*
X831327Y130775D01*
G01X830177Y131252D02*
X831500Y132575D01*
G01X834301Y131425D02*
X831977D01*
G01X831500Y132575D02*
X833824D01*
G01X835624Y132748D02*
X834301Y131425D01*
G01X833824Y132575D02*
X834474Y133225D01*
G01X835624Y154212D02*
Y132748D01*
G01X834474Y133225D02*
Y154689D01*
G01X905553Y224141D02*
X835624Y154212D01*
G01X834474Y154689D02*
X905076Y225291D01*
G01X821742Y108442D02*
Y107158D01*
G01Y105158D02*
Y104158D01*
G01Y102158D02*
Y101158D01*
G01Y99158D02*
Y98158D01*
G01Y96158D02*
Y95158D01*
G01X820592Y94681D02*
Y108919D01*
G01X835624Y122324D02*
X824204Y110904D01*
G01X822789Y109489D02*
X821742Y108442D01*
G01X820592Y108919D02*
X831125Y119452D01*
G01X835624Y122324D02*
X824204Y110904D01*
G01X831125Y119452D02*
X834474Y122801D01*
G01X835624Y127452D02*
Y122324D01*
G01X834474Y122801D02*
Y126975D01*
G01X834301Y128775D02*
X835624Y127452D01*
G01X834474Y126975D02*
X833824Y127625D01*
G01X831977Y128775D02*
X834301D01*
G01X833824Y127625D02*
X831500D01*
G01X831327Y129425D02*
X831977Y128775D01*
G01X831500Y127625D02*
X830177Y128948D01*
G01X831327Y130775D02*
Y129425D01*
G01X830177Y128948D02*
Y131252D01*
G01X831977Y131425D02*
X831327Y130775D01*
G01X830177Y131252D02*
X831500Y132575D01*
G01X834301Y131425D02*
X831977D01*
G01X831500Y132575D02*
X833824D01*
G01X835624Y132748D02*
X834301Y131425D01*
G01X833824Y132575D02*
X834474Y133225D01*
G01X835624Y154212D02*
Y132748D01*
G01X834474Y133225D02*
Y154689D01*
G01X905553Y224141D02*
X835624Y154212D01*
G01X834474Y154689D02*
X905076Y225291D01*
G01X821742Y108442D02*
Y107158D01*
G01Y105158D02*
Y104158D01*
G01Y102158D02*
Y101158D01*
G01Y99158D02*
Y98158D01*
G01Y96158D02*
Y95158D01*
G01X820592Y94681D02*
Y108919D01*
G01X835624Y122324D02*
X824204Y110904D01*
G01X822789Y109489D02*
X821742Y108442D01*
G01X820592Y108919D02*
X831125Y119452D01*
G01X838750Y119937D02*
X825174Y106361D01*
G01X829466Y109026D02*
X839900Y119460D01*
G01X838750Y134271D02*
Y119937D01*
G01X839900Y119460D02*
Y121794D01*
G01X838750Y134271D02*
Y119937D01*
G01X839900Y123794D02*
Y124794D01*
G01X838750Y134271D02*
Y119937D01*
G01X839900Y126794D02*
Y127794D01*
G01X838750Y134271D02*
Y119937D01*
G01X839900Y129794D02*
Y130794D01*
G01X838750Y134271D02*
Y119937D01*
G01X839900Y132794D02*
Y133794D01*
G01X840073Y135594D02*
X838750Y134271D01*
G01X839900Y133794D02*
X840550Y134444D01*
G01X842124Y135594D02*
X840073D01*
G01X840550Y134444D02*
X842601D01*
G01X842624Y136094D02*
X842124Y135594D01*
G01X842601Y134444D02*
X843774Y135617D01*
G01X842624Y137744D02*
Y136094D01*
G01X843774Y135617D02*
Y138221D01*
G01X842124Y138244D02*
X842624Y137744D01*
G01X843774Y138221D02*
X842601Y139394D01*
G01X840073Y138244D02*
X842124D01*
G01X842601Y139394D02*
X840550D01*
G01X838750Y139567D02*
X840073Y138244D01*
G01X840550Y139394D02*
X839900Y140044D01*
G01X838750Y144256D02*
Y139567D01*
G01X839900Y140044D02*
Y143779D01*
G01X840073Y145579D02*
X838750Y144256D01*
G01X839900Y143779D02*
X840550Y144429D01*
G01X842972Y145579D02*
X840073D01*
G01X840550Y144429D02*
X843449D01*
G01X843472Y146079D02*
X842972Y145579D01*
G01X843449Y144429D02*
X844622Y145602D01*
G01X843472Y147729D02*
Y146079D01*
G01X844622Y145602D02*
Y148206D01*
G01X842972Y148229D02*
X843472Y147729D01*
G01X844622Y148206D02*
X843449Y149379D01*
G01X840073Y148229D02*
X842972D01*
G01X843449Y149379D02*
X840550D01*
G01X838750Y149552D02*
X840073Y148229D01*
G01X840550Y149379D02*
X839900Y150029D01*
G01X838750Y153430D02*
Y149552D01*
G01X839900Y150029D02*
Y152953D01*
G01X906386Y221066D02*
X838750Y153430D01*
G01X839900Y152953D02*
X906863Y219916D01*
G01X825174Y96799D02*
X826504Y95469D01*
G01X827800Y95800D02*
X826324Y97276D01*
G01X825174Y106361D02*
Y96799D01*
G01X826324Y97276D02*
Y105884D01*
G01X838750Y119937D02*
X825174Y106361D01*
G01X826324Y105884D02*
X829466Y109026D01*
G01X838750Y119937D02*
X825174Y106361D01*
G01X829466Y109026D02*
X839900Y119460D01*
G01X838750Y134271D02*
Y119937D01*
G01X839900Y119460D02*
Y121794D01*
G01X838750Y134271D02*
Y119937D01*
G01X839900Y123794D02*
Y124794D01*
G01X838750Y134271D02*
Y119937D01*
G01X839900Y126794D02*
Y127794D01*
G01X838750Y134271D02*
Y119937D01*
G01X839900Y129794D02*
Y130794D01*
G01X838750Y134271D02*
Y119937D01*
G01X839900Y132794D02*
Y133794D01*
G01X840073Y135594D02*
X838750Y134271D01*
G01X839900Y133794D02*
X840550Y134444D01*
G01X842124Y135594D02*
X840073D01*
G01X840550Y134444D02*
X842601D01*
G01X842624Y136094D02*
X842124Y135594D01*
G01X842601Y134444D02*
X843774Y135617D01*
G01X842624Y137744D02*
Y136094D01*
G01X843774Y135617D02*
Y138221D01*
G01X842124Y138244D02*
X842624Y137744D01*
G01X843774Y138221D02*
X842601Y139394D01*
G01X840073Y138244D02*
X842124D01*
G01X842601Y139394D02*
X840550D01*
G01X838750Y139567D02*
X840073Y138244D01*
G01X840550Y139394D02*
X839900Y140044D01*
G01X838750Y144256D02*
Y139567D01*
G01X839900Y140044D02*
Y143779D01*
G01X840073Y145579D02*
X838750Y144256D01*
G01X839900Y143779D02*
X840550Y144429D01*
G01X842972Y145579D02*
X840073D01*
G01X840550Y144429D02*
X843449D01*
G01X843472Y146079D02*
X842972Y145579D01*
G01X843449Y144429D02*
X844622Y145602D01*
G01X843472Y147729D02*
Y146079D01*
G01X844622Y145602D02*
Y148206D01*
G01X842972Y148229D02*
X843472Y147729D01*
G01X844622Y148206D02*
X843449Y149379D01*
G01X840073Y148229D02*
X842972D01*
G01X843449Y149379D02*
X840550D01*
G01X838750Y149552D02*
X840073Y148229D01*
G01X840550Y149379D02*
X839900Y150029D01*
G01X838750Y153430D02*
Y149552D01*
G01X839900Y150029D02*
Y152953D01*
G01X906386Y221066D02*
X838750Y153430D01*
G01X839900Y152953D02*
X906863Y219916D01*
G01X825174Y96799D02*
X826504Y95469D01*
G01X827800Y95800D02*
X826324Y97276D01*
G01X825174Y106361D02*
Y96799D01*
G01X826324Y97276D02*
Y105884D01*
G01X838750Y119937D02*
X825174Y106361D01*
G01X826324Y105884D02*
X829466Y109026D01*
G01X835624Y122324D02*
X824204Y110904D01*
G01X831125Y119452D02*
X834474Y122801D01*
G01X835624Y127452D02*
Y122324D01*
G01X834474Y122801D02*
Y126975D01*
G01X834301Y128775D02*
X835624Y127452D01*
G01X834474Y126975D02*
X833824Y127625D01*
G01X831977Y128775D02*
X834301D01*
G01X833824Y127625D02*
X831500D01*
G01X831327Y129425D02*
X831977Y128775D01*
G01X831500Y127625D02*
X830177Y128948D01*
G01X831327Y130775D02*
Y129425D01*
G01X830177Y128948D02*
Y131252D01*
G01X831977Y131425D02*
X831327Y130775D01*
G01X830177Y131252D02*
X831500Y132575D01*
G01X834301Y131425D02*
X831977D01*
G01X831500Y132575D02*
X833824D01*
G01X835624Y132748D02*
X834301Y131425D01*
G01X833824Y132575D02*
X834474Y133225D01*
G01X835624Y154212D02*
Y132748D01*
G01X834474Y133225D02*
Y154689D01*
G01X905553Y224141D02*
X835624Y154212D01*
G01X834474Y154689D02*
X905076Y225291D01*
G01X821742Y108442D02*
Y107158D01*
G01Y105158D02*
Y104158D01*
G01Y102158D02*
Y101158D01*
G01Y99158D02*
Y98158D01*
G01Y96158D02*
Y95158D01*
G01X820592Y94681D02*
Y108919D01*
G01X835624Y122324D02*
X824204Y110904D01*
G01X822789Y109489D02*
X821742Y108442D01*
G01X820592Y108919D02*
X831125Y119452D01*
G01X838750Y119937D02*
X825174Y106361D01*
G01X829466Y109026D02*
X839900Y119460D01*
G01X838750Y134271D02*
Y119937D01*
G01X839900Y119460D02*
Y121794D01*
G01X838750Y134271D02*
Y119937D01*
G01X839900Y123794D02*
Y124794D01*
G01X838750Y134271D02*
Y119937D01*
G01X839900Y126794D02*
Y127794D01*
G01X838750Y134271D02*
Y119937D01*
G01X839900Y129794D02*
Y130794D01*
G01X838750Y134271D02*
Y119937D01*
G01X839900Y132794D02*
Y133794D01*
G01X840073Y135594D02*
X838750Y134271D01*
G01X839900Y133794D02*
X840550Y134444D01*
G01X842124Y135594D02*
X840073D01*
G01X840550Y134444D02*
X842601D01*
G01X842624Y136094D02*
X842124Y135594D01*
G01X842601Y134444D02*
X843774Y135617D01*
G01X842624Y137744D02*
Y136094D01*
G01X843774Y135617D02*
Y138221D01*
G01X842124Y138244D02*
X842624Y137744D01*
G01X843774Y138221D02*
X842601Y139394D01*
G01X840073Y138244D02*
X842124D01*
G01X842601Y139394D02*
X840550D01*
G01X838750Y139567D02*
X840073Y138244D01*
G01X840550Y139394D02*
X839900Y140044D01*
G01X838750Y144256D02*
Y139567D01*
G01X839900Y140044D02*
Y143779D01*
G01X840073Y145579D02*
X838750Y144256D01*
G01X839900Y143779D02*
X840550Y144429D01*
G01X842972Y145579D02*
X840073D01*
G01X840550Y144429D02*
X843449D01*
G01X843472Y146079D02*
X842972Y145579D01*
G01X843449Y144429D02*
X844622Y145602D01*
G01X843472Y147729D02*
Y146079D01*
G01X844622Y145602D02*
Y148206D01*
G01X842972Y148229D02*
X843472Y147729D01*
G01X844622Y148206D02*
X843449Y149379D01*
G01X840073Y148229D02*
X842972D01*
G01X843449Y149379D02*
X840550D01*
G01X838750Y149552D02*
X840073Y148229D01*
G01X840550Y149379D02*
X839900Y150029D01*
G01X838750Y153430D02*
Y149552D01*
G01X839900Y150029D02*
Y152953D01*
G01X906386Y221066D02*
X838750Y153430D01*
G01X839900Y152953D02*
X906863Y219916D01*
G01X825174Y96799D02*
X826504Y95469D01*
G01X827800Y95800D02*
X826324Y97276D01*
G01X825174Y106361D02*
Y96799D01*
G01X826324Y97276D02*
Y105884D01*
G01X838750Y119937D02*
X825174Y106361D01*
G01X826324Y105884D02*
X829466Y109026D01*
G01X908884Y370405D02*
X825587Y453702D01*
G01X909361Y371555D02*
X826737Y454179D01*
G01X825587Y453702D02*
Y456664D01*
G01X826737Y454179D02*
Y456187D01*
G01X825587Y456664D02*
X826949Y458026D01*
G01X826737Y456187D02*
X827426Y456876D01*
G01X826949Y458026D02*
X828228D01*
G01X827426Y456876D02*
X828705D01*
G01X828228Y458026D02*
X828930Y458728D01*
G01X828705Y456876D02*
X830080Y458251D01*
G01X828930Y458728D02*
Y469114D01*
G01X830080Y458251D02*
Y469591D01*
G01X911020Y375431D02*
X833780Y452671D01*
G01X910543Y374281D02*
X832630Y452194D01*
G01X833780Y452671D02*
Y471480D01*
G01X832630Y452194D02*
Y471003D01*
G01X909361Y371555D02*
X826737Y454179D01*
G01X908884Y370405D02*
X825587Y453702D01*
G01X826737Y454179D02*
Y456187D01*
G01X825587Y453702D02*
Y456664D01*
G01X826737Y456187D02*
X827426Y456876D01*
G01X825587Y456664D02*
X826949Y458026D01*
G01X827426Y456876D02*
X828705D01*
G01X826949Y458026D02*
X828228D01*
G01X828705Y456876D02*
X830080Y458251D01*
G01X828228Y458026D02*
X828930Y458728D01*
G01X830080Y458251D02*
Y469591D01*
G01X828930Y458728D02*
Y469114D01*
G01X910543Y374281D02*
X832630Y452194D01*
G01X911020Y375431D02*
X833780Y452671D01*
G01X832630Y452194D02*
Y471003D01*
G01X833780Y452671D02*
Y471480D01*
G01X908884Y370405D02*
X825587Y453702D01*
G01X909361Y371555D02*
X826737Y454179D01*
G01X825587Y453702D02*
Y456664D01*
G01X826737Y454179D02*
Y456187D01*
G01X825587Y456664D02*
X826949Y458026D01*
G01X826737Y456187D02*
X827426Y456876D01*
G01X826949Y458026D02*
X828228D01*
G01X827426Y456876D02*
X828705D01*
G01X828228Y458026D02*
X828930Y458728D01*
G01X828705Y456876D02*
X830080Y458251D01*
G01X828930Y458728D02*
Y469114D01*
G01X830080Y458251D02*
Y469591D01*
G01X909361Y371555D02*
X826737Y454179D01*
G01X908884Y370405D02*
X825587Y453702D01*
G01X826737Y454179D02*
Y456187D01*
G01X825587Y453702D02*
Y456664D01*
G01X826737Y456187D02*
X827426Y456876D01*
G01X825587Y456664D02*
X826949Y458026D01*
G01X827426Y456876D02*
X828705D01*
G01X826949Y458026D02*
X828228D01*
G01X828705Y456876D02*
X830080Y458251D01*
G01X828228Y458026D02*
X828930Y458728D01*
G01X830080Y458251D02*
Y469591D01*
G01X828930Y458728D02*
Y469114D01*
G01X911020Y375431D02*
X833780Y452671D01*
G01X910543Y374281D02*
X832630Y452194D01*
G01X833780Y452671D02*
Y471480D01*
G01X832630Y452194D02*
Y471003D01*
G01X910543Y374281D02*
X832630Y452194D01*
G01X911020Y375431D02*
X833780Y452671D01*
G01X832630Y452194D02*
Y471003D01*
G01X833780Y452671D02*
Y471480D01*
G01X828930Y469114D02*
X828028Y470016D01*
G01X830080Y469591D02*
X828505Y471166D01*
G01X828028Y470016D02*
X826749D01*
G01X828505Y471166D02*
X827226D01*
G01X826749Y470016D02*
X825374Y471391D01*
G01X827226Y471166D02*
X826524Y471868D01*
G01X825374Y471391D02*
Y504413D01*
G01Y506161D02*
Y507451D01*
G01Y509175D02*
Y511498D01*
G01X826524Y471868D02*
Y511975D01*
G01X825374Y511498D02*
X824172Y512700D01*
G01X826524Y511975D02*
X823199Y515300D01*
G01X833780Y471480D02*
X830680Y474580D01*
G01X832630Y471003D02*
X829530Y474103D01*
G01X830680Y474580D02*
Y476320D01*
G01X829530Y474103D02*
Y476797D01*
G01X830680Y476320D02*
X833780Y479420D01*
G01X829530Y476797D02*
X832630Y479897D01*
G01X833780Y479420D02*
Y482460D01*
G01X832630Y479897D02*
Y481983D01*
G01X833780Y482460D02*
X832405Y483835D01*
G01X832630Y481983D02*
X831928Y482685D01*
G01X832405Y483835D02*
X831172D01*
G01X831928Y482685D02*
X830695D01*
G01X831172Y483835D02*
X830470Y484537D01*
G01X830695Y482685D02*
X829320Y484060D01*
G01X830470Y484537D02*
Y486623D01*
G01X829320Y484060D02*
Y487100D01*
G01X830470Y486623D02*
X831172Y487325D01*
G01X829320Y487100D02*
X830695Y488475D01*
G01X831172Y487325D02*
X832405D01*
G01X830695Y488475D02*
X831928D01*
G01X832405Y487325D02*
X833780Y488700D01*
G01X831928Y488475D02*
X832630Y489177D01*
G01X833780Y488700D02*
Y491740D01*
G01X832630Y489177D02*
Y491263D01*
G01X833780Y491740D02*
X832405Y493115D01*
G01X832630Y491263D02*
X831928Y491965D01*
G01X832405Y493115D02*
X831172D01*
G01X831928Y491965D02*
X830695D01*
G01X831172Y493115D02*
X830470Y493817D01*
G01X830695Y491965D02*
X829320Y493340D01*
G01X830470Y493817D02*
Y495903D01*
G01X829320Y493340D02*
Y496380D01*
G01X830470Y495903D02*
X831172Y496605D01*
G01X829320Y496380D02*
X830695Y497755D01*
G01X831172Y496605D02*
X832405D01*
G01X830695Y497755D02*
X831928D01*
G01X832405Y496605D02*
X833780Y497980D01*
G01X831928Y497755D02*
X832630Y498457D01*
G01X833780Y497980D02*
Y500328D01*
G01X832630Y498457D02*
Y499851D01*
G01X833780Y500328D02*
X830403Y503705D01*
G01X832630Y499851D02*
X828963Y503518D01*
G01X830403Y503705D02*
Y513411D01*
G01X829253Y505264D02*
Y506264D01*
G01X830403Y503705D02*
Y513411D01*
G01X829253Y508264D02*
Y509264D01*
G01X830403Y503705D02*
Y513411D01*
G01X829253Y511264D02*
Y511961D01*
G01X830080Y469591D02*
X828505Y471166D01*
G01X828930Y469114D02*
X828028Y470016D01*
G01X828505Y471166D02*
X827226D01*
G01X828028Y470016D02*
X826749D01*
G01X827226Y471166D02*
X826524Y471868D01*
G01X826749Y470016D02*
X825374Y471391D01*
G01X826524Y471868D02*
Y511975D01*
G01X825374Y471391D02*
Y504413D01*
G01X826524Y471868D02*
Y511975D01*
G01X825374Y506161D02*
Y507451D01*
G01X826524Y471868D02*
Y511975D01*
G01X825374Y509175D02*
Y511498D01*
G01X826524Y511975D02*
X823199Y515300D01*
G01X825374Y511498D02*
X824172Y512700D01*
G01X832630Y471003D02*
X829530Y474103D01*
G01X833780Y471480D02*
X830680Y474580D01*
G01X829530Y474103D02*
Y476797D01*
G01X830680Y474580D02*
Y476320D01*
G01X829530Y476797D02*
X832630Y479897D01*
G01X830680Y476320D02*
X833780Y479420D01*
G01X832630Y479897D02*
Y481983D01*
G01X833780Y479420D02*
Y482460D01*
G01X832630Y481983D02*
X831928Y482685D01*
G01X833780Y482460D02*
X832405Y483835D01*
G01X831928Y482685D02*
X830695D01*
G01X832405Y483835D02*
X831172D01*
G01X830695Y482685D02*
X829320Y484060D01*
G01X831172Y483835D02*
X830470Y484537D01*
G01X829320Y484060D02*
Y487100D01*
G01X830470Y484537D02*
Y486623D01*
G01X829320Y487100D02*
X830695Y488475D01*
G01X830470Y486623D02*
X831172Y487325D01*
G01X830695Y488475D02*
X831928D01*
G01X831172Y487325D02*
X832405D01*
G01X831928Y488475D02*
X832630Y489177D01*
G01X832405Y487325D02*
X833780Y488700D01*
G01X832630Y489177D02*
Y491263D01*
G01X833780Y488700D02*
Y491740D01*
G01X832630Y491263D02*
X831928Y491965D01*
G01X833780Y491740D02*
X832405Y493115D01*
G01X831928Y491965D02*
X830695D01*
G01X832405Y493115D02*
X831172D01*
G01X830695Y491965D02*
X829320Y493340D01*
G01X831172Y493115D02*
X830470Y493817D01*
G01X829320Y493340D02*
Y496380D01*
G01X830470Y493817D02*
Y495903D01*
G01X829320Y496380D02*
X830695Y497755D01*
G01X830470Y495903D02*
X831172Y496605D01*
G01X830695Y497755D02*
X831928D01*
G01X831172Y496605D02*
X832405D01*
G01X831928Y497755D02*
X832630Y498457D01*
G01X832405Y496605D02*
X833780Y497980D01*
G01X832630Y498457D02*
Y499851D01*
G01X833780Y497980D02*
Y500328D01*
G01X832630Y499851D02*
X828963Y503518D01*
G01X833780Y500328D02*
X830403Y503705D01*
G01X829253Y505264D02*
Y506264D01*
G01Y508264D02*
Y509264D01*
G01Y511264D02*
Y511961D01*
G01X830403Y503705D02*
Y513411D01*
G01X828930Y469114D02*
X828028Y470016D01*
G01X830080Y469591D02*
X828505Y471166D01*
G01X828028Y470016D02*
X826749D01*
G01X828505Y471166D02*
X827226D01*
G01X826749Y470016D02*
X825374Y471391D01*
G01X827226Y471166D02*
X826524Y471868D01*
G01X825374Y471391D02*
Y504413D01*
G01Y506161D02*
Y507451D01*
G01Y509175D02*
Y511498D01*
G01X826524Y471868D02*
Y511975D01*
G01X825374Y511498D02*
X824172Y512700D01*
G01X826524Y511975D02*
X823199Y515300D01*
G01X830080Y469591D02*
X828505Y471166D01*
G01X828930Y469114D02*
X828028Y470016D01*
G01X828505Y471166D02*
X827226D01*
G01X828028Y470016D02*
X826749D01*
G01X827226Y471166D02*
X826524Y471868D01*
G01X826749Y470016D02*
X825374Y471391D01*
G01X826524Y471868D02*
Y511975D01*
G01X825374Y471391D02*
Y504413D01*
G01X826524Y471868D02*
Y511975D01*
G01X825374Y506161D02*
Y507451D01*
G01X826524Y471868D02*
Y511975D01*
G01X825374Y509175D02*
Y511498D01*
G01X826524Y511975D02*
X823199Y515300D01*
G01X825374Y511498D02*
X824172Y512700D01*
G01X833780Y471480D02*
X830680Y474580D01*
G01X832630Y471003D02*
X829530Y474103D01*
G01X830680Y474580D02*
Y476320D01*
G01X829530Y474103D02*
Y476797D01*
G01X830680Y476320D02*
X833780Y479420D01*
G01X829530Y476797D02*
X832630Y479897D01*
G01X833780Y479420D02*
Y482460D01*
G01X832630Y479897D02*
Y481983D01*
G01X833780Y482460D02*
X832405Y483835D01*
G01X832630Y481983D02*
X831928Y482685D01*
G01X832405Y483835D02*
X831172D01*
G01X831928Y482685D02*
X830695D01*
G01X831172Y483835D02*
X830470Y484537D01*
G01X830695Y482685D02*
X829320Y484060D01*
G01X830470Y484537D02*
Y486623D01*
G01X829320Y484060D02*
Y487100D01*
G01X830470Y486623D02*
X831172Y487325D01*
G01X829320Y487100D02*
X830695Y488475D01*
G01X831172Y487325D02*
X832405D01*
G01X830695Y488475D02*
X831928D01*
G01X832405Y487325D02*
X833780Y488700D01*
G01X831928Y488475D02*
X832630Y489177D01*
G01X833780Y488700D02*
Y491740D01*
G01X832630Y489177D02*
Y491263D01*
G01X833780Y491740D02*
X832405Y493115D01*
G01X832630Y491263D02*
X831928Y491965D01*
G01X832405Y493115D02*
X831172D01*
G01X831928Y491965D02*
X830695D01*
G01X831172Y493115D02*
X830470Y493817D01*
G01X830695Y491965D02*
X829320Y493340D01*
G01X830470Y493817D02*
Y495903D01*
G01X829320Y493340D02*
Y496380D01*
G01X830470Y495903D02*
X831172Y496605D01*
G01X829320Y496380D02*
X830695Y497755D01*
G01X831172Y496605D02*
X832405D01*
G01X830695Y497755D02*
X831928D01*
G01X832405Y496605D02*
X833780Y497980D01*
G01X831928Y497755D02*
X832630Y498457D01*
G01X833780Y497980D02*
Y500328D01*
G01X832630Y498457D02*
Y499851D01*
G01X833780Y500328D02*
X830403Y503705D01*
G01X832630Y499851D02*
X828963Y503518D01*
G01X830403Y503705D02*
Y513411D01*
G01X829253Y505264D02*
Y506264D01*
G01X830403Y503705D02*
Y513411D01*
G01X829253Y508264D02*
Y509264D01*
G01X830403Y503705D02*
Y513411D01*
G01X829253Y511264D02*
Y511961D01*
G01X832630Y471003D02*
X829530Y474103D01*
G01X833780Y471480D02*
X830680Y474580D01*
G01X829530Y474103D02*
Y476797D01*
G01X830680Y474580D02*
Y476320D01*
G01X829530Y476797D02*
X832630Y479897D01*
G01X830680Y476320D02*
X833780Y479420D01*
G01X832630Y479897D02*
Y481983D01*
G01X833780Y479420D02*
Y482460D01*
G01X832630Y481983D02*
X831928Y482685D01*
G01X833780Y482460D02*
X832405Y483835D01*
G01X831928Y482685D02*
X830695D01*
G01X832405Y483835D02*
X831172D01*
G01X830695Y482685D02*
X829320Y484060D01*
G01X831172Y483835D02*
X830470Y484537D01*
G01X829320Y484060D02*
Y487100D01*
G01X830470Y484537D02*
Y486623D01*
G01X829320Y487100D02*
X830695Y488475D01*
G01X830470Y486623D02*
X831172Y487325D01*
G01X830695Y488475D02*
X831928D01*
G01X831172Y487325D02*
X832405D01*
G01X831928Y488475D02*
X832630Y489177D01*
G01X832405Y487325D02*
X833780Y488700D01*
G01X832630Y489177D02*
Y491263D01*
G01X833780Y488700D02*
Y491740D01*
G01X832630Y491263D02*
X831928Y491965D01*
G01X833780Y491740D02*
X832405Y493115D01*
G01X831928Y491965D02*
X830695D01*
G01X832405Y493115D02*
X831172D01*
G01X830695Y491965D02*
X829320Y493340D01*
G01X831172Y493115D02*
X830470Y493817D01*
G01X829320Y493340D02*
Y496380D01*
G01X830470Y493817D02*
Y495903D01*
G01X829320Y496380D02*
X830695Y497755D01*
G01X830470Y495903D02*
X831172Y496605D01*
G01X830695Y497755D02*
X831928D01*
G01X831172Y496605D02*
X832405D01*
G01X831928Y497755D02*
X832630Y498457D01*
G01X832405Y496605D02*
X833780Y497980D01*
G01X832630Y498457D02*
Y499851D01*
G01X833780Y497980D02*
Y500328D01*
G01X832630Y499851D02*
X828963Y503518D01*
G01X833780Y500328D02*
X830403Y503705D01*
G01X829253Y505264D02*
Y506264D01*
G01Y508264D02*
Y509264D01*
G01Y511264D02*
Y511961D01*
G01X830403Y503705D02*
Y513411D01*
G01X898330Y140597D02*
Y142683D01*
G01X899480Y141500D02*
Y143160D01*
G01X898330Y142683D02*
X897628Y143385D01*
G01X899480Y143160D02*
X898105Y144535D01*
G01X897628Y143385D02*
X896523D01*
G01X898105Y144535D02*
X897000D01*
G01X896523Y143385D02*
X895200Y144708D01*
G01X897000Y144535D02*
X896350Y145185D01*
G01X895200Y144708D02*
Y147085D01*
G01X896350Y145185D02*
Y146608D01*
G01X895200Y147085D02*
X898300Y150185D01*
G01X896350Y146608D02*
X899450Y149708D01*
G01X898300Y150185D02*
Y169092D01*
G01X899450Y149708D02*
Y168615D01*
G01X894900Y109812D02*
Y125500D01*
G01X896050Y115550D02*
Y116510D01*
G01X894900Y109812D02*
Y125500D01*
G01X896050Y118550D02*
Y119510D01*
G01X894900Y109812D02*
Y125500D01*
G01X896050Y121550D02*
Y122510D01*
G01X894900Y125500D02*
Y129240D01*
G01Y109812D02*
Y125500D01*
G01X896050Y124550D02*
Y125510D01*
G01X894900Y125500D02*
Y129240D01*
G01X896050Y127550D02*
Y128763D01*
G01X894900Y129240D02*
X896275Y130615D01*
G01X896050Y128763D02*
X896752Y129465D01*
G01X896275Y130615D02*
X897750D01*
G01X896752Y129465D02*
X898227D01*
G01X897750Y130615D02*
X898400Y131265D01*
G01X898227Y129465D02*
X899550Y130788D01*
G01X898400Y131265D02*
Y133455D01*
G01X899550Y130788D02*
Y133932D01*
G01X898400Y133455D02*
X897750Y134105D01*
G01X899550Y133932D02*
X898227Y135255D01*
G01X897750Y134105D02*
X896275D01*
G01X898227Y135255D02*
X896752D01*
G01X896275Y134105D02*
X894900Y135480D01*
G01X896752Y135255D02*
X896050Y135957D01*
G01X894900Y135480D02*
Y138520D01*
G01X896050Y135957D02*
Y138043D01*
G01X894900Y138520D02*
X896275Y139895D01*
G01X896050Y138043D02*
X896752Y138745D01*
G01X896275Y139895D02*
X897628D01*
G01X896752Y138745D02*
X898105D01*
G01X897628Y139895D02*
X898330Y140597D01*
G01X898105Y138745D02*
X899480Y140120D01*
G01X898330Y140597D02*
Y142683D01*
G01X899480Y140120D02*
Y141500D01*
G01X903370Y128999D02*
Y167293D01*
G01X902220Y135500D02*
Y167770D01*
G01X901250Y123500D02*
Y126879D01*
G01Y115350D02*
Y116310D01*
G01Y118350D02*
Y119310D01*
G01Y121350D02*
Y123500D01*
G01X900100Y114480D02*
Y127356D01*
G01X901250Y126879D02*
X903370Y128999D01*
G01X900100Y127356D02*
X902220Y129476D01*
G01X903370Y128999D02*
Y167293D01*
G01X902220Y129476D02*
Y135500D01*
G01X896050Y124550D02*
Y125510D01*
G01Y127550D02*
Y128763D01*
G01X894900Y125500D02*
Y129240D01*
G01X896050Y128763D02*
X896752Y129465D01*
G01X894900Y129240D02*
X896275Y130615D01*
G01X896752Y129465D02*
X898227D01*
G01X896275Y130615D02*
X897750D01*
G01X898227Y129465D02*
X899550Y130788D01*
G01X897750Y130615D02*
X898400Y131265D01*
G01X899550Y130788D02*
Y133932D01*
G01X898400Y131265D02*
Y133455D01*
G01X899550Y133932D02*
X898227Y135255D01*
G01X898400Y133455D02*
X897750Y134105D01*
G01X898227Y135255D02*
X896752D01*
G01X897750Y134105D02*
X896275D01*
G01X896752Y135255D02*
X896050Y135957D01*
G01X896275Y134105D02*
X894900Y135480D01*
G01X896050Y135957D02*
Y138043D01*
G01X894900Y135480D02*
Y138520D01*
G01X896050Y138043D02*
X896752Y138745D01*
G01X894900Y138520D02*
X896275Y139895D01*
G01X896752Y138745D02*
X898105D01*
G01X896275Y139895D02*
X897628D01*
G01X898105Y138745D02*
X899480Y140120D01*
G01X897628Y139895D02*
X898330Y140597D01*
G01X899480Y141500D02*
Y143160D01*
G01Y140120D02*
Y141500D01*
G01X898330Y140597D02*
Y142683D01*
G01X899480Y143160D02*
X898105Y144535D01*
G01X898330Y142683D02*
X897628Y143385D01*
G01X898105Y144535D02*
X897000D01*
G01X897628Y143385D02*
X896523D01*
G01X897000Y144535D02*
X896350Y145185D01*
G01X896523Y143385D02*
X895200Y144708D01*
G01X896350Y145185D02*
Y146608D01*
G01X895200Y144708D02*
Y147085D01*
G01X896350Y146608D02*
X899450Y149708D01*
G01X895200Y147085D02*
X898300Y150185D01*
G01X899450Y149708D02*
Y168615D01*
G01X898300Y150185D02*
Y169092D01*
G01X896050Y115550D02*
Y116510D01*
G01Y118550D02*
Y119510D01*
G01Y121550D02*
Y122510D01*
G01Y124550D02*
Y125510D01*
G01X894900Y109812D02*
Y125500D01*
G01X900100Y114480D02*
Y127356D01*
G01X901250Y123500D02*
Y126879D01*
G01X900100Y127356D02*
X902220Y129476D01*
G01X901250Y126879D02*
X903370Y128999D01*
G01X902220Y135500D02*
Y167770D01*
G01Y129476D02*
Y135500D01*
G01X903370Y128999D02*
Y167293D01*
G01X900100Y114480D02*
Y127356D01*
G01X901250Y115350D02*
Y116310D01*
G01X900100Y114480D02*
Y127356D01*
G01X901250Y118350D02*
Y119310D01*
G01X900100Y114480D02*
Y127356D01*
G01X901250Y121350D02*
Y123500D01*
G01X898330Y140597D02*
Y142683D01*
G01X899480Y141500D02*
Y143160D01*
G01X898330Y142683D02*
X897628Y143385D01*
G01X899480Y143160D02*
X898105Y144535D01*
G01X897628Y143385D02*
X896523D01*
G01X898105Y144535D02*
X897000D01*
G01X896523Y143385D02*
X895200Y144708D01*
G01X897000Y144535D02*
X896350Y145185D01*
G01X895200Y144708D02*
Y147085D01*
G01X896350Y145185D02*
Y146608D01*
G01X895200Y147085D02*
X898300Y150185D01*
G01X896350Y146608D02*
X899450Y149708D01*
G01X898300Y150185D02*
Y169092D01*
G01X899450Y149708D02*
Y168615D01*
G01X894900Y109812D02*
Y125500D01*
G01X896050Y115550D02*
Y116510D01*
G01X894900Y109812D02*
Y125500D01*
G01X896050Y118550D02*
Y119510D01*
G01X894900Y109812D02*
Y125500D01*
G01X896050Y121550D02*
Y122510D01*
G01X894900Y125500D02*
Y129240D01*
G01Y109812D02*
Y125500D01*
G01X896050Y124550D02*
Y125510D01*
G01X894900Y125500D02*
Y129240D01*
G01X896050Y127550D02*
Y128763D01*
G01X894900Y129240D02*
X896275Y130615D01*
G01X896050Y128763D02*
X896752Y129465D01*
G01X896275Y130615D02*
X897750D01*
G01X896752Y129465D02*
X898227D01*
G01X897750Y130615D02*
X898400Y131265D01*
G01X898227Y129465D02*
X899550Y130788D01*
G01X898400Y131265D02*
Y133455D01*
G01X899550Y130788D02*
Y133932D01*
G01X898400Y133455D02*
X897750Y134105D01*
G01X899550Y133932D02*
X898227Y135255D01*
G01X897750Y134105D02*
X896275D01*
G01X898227Y135255D02*
X896752D01*
G01X896275Y134105D02*
X894900Y135480D01*
G01X896752Y135255D02*
X896050Y135957D01*
G01X894900Y135480D02*
Y138520D01*
G01X896050Y135957D02*
Y138043D01*
G01X894900Y138520D02*
X896275Y139895D01*
G01X896050Y138043D02*
X896752Y138745D01*
G01X896275Y139895D02*
X897628D01*
G01X896752Y138745D02*
X898105D01*
G01X897628Y139895D02*
X898330Y140597D01*
G01X898105Y138745D02*
X899480Y140120D01*
G01X898330Y140597D02*
Y142683D01*
G01X899480Y140120D02*
Y141500D01*
G01X898330Y140597D02*
Y142683D01*
G01X899480Y141500D02*
Y143160D01*
G01X898330Y142683D02*
X897628Y143385D01*
G01X899480Y143160D02*
X898105Y144535D01*
G01X897628Y143385D02*
X896523D01*
G01X898105Y144535D02*
X897000D01*
G01X896523Y143385D02*
X895200Y144708D01*
G01X897000Y144535D02*
X896350Y145185D01*
G01X895200Y144708D02*
Y147085D01*
G01X896350Y145185D02*
Y146608D01*
G01X895200Y147085D02*
X898300Y150185D01*
G01X896350Y146608D02*
X899450Y149708D01*
G01X898300Y150185D02*
Y169092D01*
G01X899450Y149708D02*
Y168615D01*
G01X894900Y109812D02*
Y125500D01*
G01X896050Y115550D02*
Y116510D01*
G01X894900Y109812D02*
Y125500D01*
G01X896050Y118550D02*
Y119510D01*
G01X894900Y109812D02*
Y125500D01*
G01X896050Y121550D02*
Y122510D01*
G01X894900Y125500D02*
Y129240D01*
G01Y109812D02*
Y125500D01*
G01X896050Y124550D02*
Y125510D01*
G01X894900Y125500D02*
Y129240D01*
G01X896050Y127550D02*
Y128763D01*
G01X894900Y129240D02*
X896275Y130615D01*
G01X896050Y128763D02*
X896752Y129465D01*
G01X896275Y130615D02*
X897750D01*
G01X896752Y129465D02*
X898227D01*
G01X897750Y130615D02*
X898400Y131265D01*
G01X898227Y129465D02*
X899550Y130788D01*
G01X898400Y131265D02*
Y133455D01*
G01X899550Y130788D02*
Y133932D01*
G01X898400Y133455D02*
X897750Y134105D01*
G01X899550Y133932D02*
X898227Y135255D01*
G01X897750Y134105D02*
X896275D01*
G01X898227Y135255D02*
X896752D01*
G01X896275Y134105D02*
X894900Y135480D01*
G01X896752Y135255D02*
X896050Y135957D01*
G01X894900Y135480D02*
Y138520D01*
G01X896050Y135957D02*
Y138043D01*
G01X894900Y138520D02*
X896275Y139895D01*
G01X896050Y138043D02*
X896752Y138745D01*
G01X896275Y139895D02*
X897628D01*
G01X896752Y138745D02*
X898105D01*
G01X897628Y139895D02*
X898330Y140597D01*
G01X898105Y138745D02*
X899480Y140120D01*
G01X898330Y140597D02*
Y142683D01*
G01X899480Y140120D02*
Y141500D01*
G01X903370Y128999D02*
Y167293D01*
G01X902220Y135500D02*
Y167770D01*
G01X901250Y123500D02*
Y126879D01*
G01Y115350D02*
Y116310D01*
G01Y118350D02*
Y119310D01*
G01Y121350D02*
Y123500D01*
G01X900100Y114480D02*
Y127356D01*
G01X901250Y126879D02*
X903370Y128999D01*
G01X900100Y127356D02*
X902220Y129476D01*
G01X903370Y128999D02*
Y167293D01*
G01X902220Y129476D02*
Y135500D01*
G01X903370Y128999D02*
Y167293D01*
G01X902220Y135500D02*
Y167770D01*
G01X901250Y123500D02*
Y126879D01*
G01Y115350D02*
Y116310D01*
G01Y118350D02*
Y119310D01*
G01Y121350D02*
Y123500D01*
G01X900100Y114480D02*
Y127356D01*
G01X901250Y126879D02*
X903370Y128999D01*
G01X900100Y127356D02*
X902220Y129476D01*
G01X903370Y128999D02*
Y167293D01*
G01X902220Y129476D02*
Y135500D01*
G01X896050Y124550D02*
Y125510D01*
G01Y127550D02*
Y128763D01*
G01X894900Y125500D02*
Y129240D01*
G01X896050Y128763D02*
X896752Y129465D01*
G01X894900Y129240D02*
X896275Y130615D01*
G01X896752Y129465D02*
X898227D01*
G01X896275Y130615D02*
X897750D01*
G01X898227Y129465D02*
X899550Y130788D01*
G01X897750Y130615D02*
X898400Y131265D01*
G01X899550Y130788D02*
Y133932D01*
G01X898400Y131265D02*
Y133455D01*
G01X899550Y133932D02*
X898227Y135255D01*
G01X898400Y133455D02*
X897750Y134105D01*
G01X898227Y135255D02*
X896752D01*
G01X897750Y134105D02*
X896275D01*
G01X896752Y135255D02*
X896050Y135957D01*
G01X896275Y134105D02*
X894900Y135480D01*
G01X896050Y135957D02*
Y138043D01*
G01X894900Y135480D02*
Y138520D01*
G01X896050Y138043D02*
X896752Y138745D01*
G01X894900Y138520D02*
X896275Y139895D01*
G01X896752Y138745D02*
X898105D01*
G01X896275Y139895D02*
X897628D01*
G01X898105Y138745D02*
X899480Y140120D01*
G01X897628Y139895D02*
X898330Y140597D01*
G01X899480Y141500D02*
Y143160D01*
G01Y140120D02*
Y141500D01*
G01X898330Y140597D02*
Y142683D01*
G01X899480Y143160D02*
X898105Y144535D01*
G01X898330Y142683D02*
X897628Y143385D01*
G01X898105Y144535D02*
X897000D01*
G01X897628Y143385D02*
X896523D01*
G01X897000Y144535D02*
X896350Y145185D01*
G01X896523Y143385D02*
X895200Y144708D01*
G01X896350Y145185D02*
Y146608D01*
G01X895200Y144708D02*
Y147085D01*
G01X896350Y146608D02*
X899450Y149708D01*
G01X895200Y147085D02*
X898300Y150185D01*
G01X899450Y149708D02*
Y168615D01*
G01X898300Y150185D02*
Y169092D01*
G01X896050Y115550D02*
Y116510D01*
G01Y118550D02*
Y119510D01*
G01Y121550D02*
Y122510D01*
G01Y124550D02*
Y125510D01*
G01X894900Y109812D02*
Y125500D01*
G01X896050Y124550D02*
Y125510D01*
G01Y127550D02*
Y128763D01*
G01X894900Y125500D02*
Y129240D01*
G01X896050Y128763D02*
X896752Y129465D01*
G01X894900Y129240D02*
X896275Y130615D01*
G01X896752Y129465D02*
X898227D01*
G01X896275Y130615D02*
X897750D01*
G01X898227Y129465D02*
X899550Y130788D01*
G01X897750Y130615D02*
X898400Y131265D01*
G01X899550Y130788D02*
Y133932D01*
G01X898400Y131265D02*
Y133455D01*
G01X899550Y133932D02*
X898227Y135255D01*
G01X898400Y133455D02*
X897750Y134105D01*
G01X898227Y135255D02*
X896752D01*
G01X897750Y134105D02*
X896275D01*
G01X896752Y135255D02*
X896050Y135957D01*
G01X896275Y134105D02*
X894900Y135480D01*
G01X896050Y135957D02*
Y138043D01*
G01X894900Y135480D02*
Y138520D01*
G01X896050Y138043D02*
X896752Y138745D01*
G01X894900Y138520D02*
X896275Y139895D01*
G01X896752Y138745D02*
X898105D01*
G01X896275Y139895D02*
X897628D01*
G01X898105Y138745D02*
X899480Y140120D01*
G01X897628Y139895D02*
X898330Y140597D01*
G01X899480Y141500D02*
Y143160D01*
G01Y140120D02*
Y141500D01*
G01X898330Y140597D02*
Y142683D01*
G01X899480Y143160D02*
X898105Y144535D01*
G01X898330Y142683D02*
X897628Y143385D01*
G01X898105Y144535D02*
X897000D01*
G01X897628Y143385D02*
X896523D01*
G01X897000Y144535D02*
X896350Y145185D01*
G01X896523Y143385D02*
X895200Y144708D01*
G01X896350Y145185D02*
Y146608D01*
G01X895200Y144708D02*
Y147085D01*
G01X896350Y146608D02*
X899450Y149708D01*
G01X895200Y147085D02*
X898300Y150185D01*
G01X899450Y149708D02*
Y168615D01*
G01X898300Y150185D02*
Y169092D01*
G01X896050Y115550D02*
Y116510D01*
G01Y118550D02*
Y119510D01*
G01Y121550D02*
Y122510D01*
G01Y124550D02*
Y125510D01*
G01X894900Y109812D02*
Y125500D01*
G01X900100Y114480D02*
Y127356D01*
G01X901250Y123500D02*
Y126879D01*
G01X900100Y127356D02*
X902220Y129476D01*
G01X901250Y126879D02*
X903370Y128999D01*
G01X902220Y135500D02*
Y167770D01*
G01Y129476D02*
Y135500D01*
G01X903370Y128999D02*
Y167293D01*
G01X900100Y114480D02*
Y127356D01*
G01X901250Y115350D02*
Y116310D01*
G01X900100Y114480D02*
Y127356D01*
G01X901250Y118350D02*
Y119310D01*
G01X900100Y114480D02*
Y127356D01*
G01X901250Y121350D02*
Y123500D01*
G01X900100Y114480D02*
Y127356D01*
G01X901250Y123500D02*
Y126879D01*
G01X900100Y127356D02*
X902220Y129476D01*
G01X901250Y126879D02*
X903370Y128999D01*
G01X902220Y135500D02*
Y167770D01*
G01Y129476D02*
Y135500D01*
G01X903370Y128999D02*
Y167293D01*
G01X900100Y114480D02*
Y127356D01*
G01X901250Y115350D02*
Y116310D01*
G01X900100Y114480D02*
Y127356D01*
G01X901250Y118350D02*
Y119310D01*
G01X900100Y114480D02*
Y127356D01*
G01X901250Y121350D02*
Y123500D01*
G01X898300Y169092D02*
X911838Y182630D01*
G01X899450Y168615D02*
X912651Y181816D01*
G01X903370Y167293D02*
X915277Y179200D01*
G01X902220Y167770D02*
X914464Y180014D01*
G01X899450Y168615D02*
X912651Y181816D01*
G01X898300Y169092D02*
X911838Y182630D01*
G01X902220Y167770D02*
X914464Y180014D01*
G01X903370Y167293D02*
X915277Y179200D01*
G01X898300Y169092D02*
X911838Y182630D01*
G01X899450Y168615D02*
X912651Y181816D01*
G01X898300Y169092D02*
X911838Y182630D01*
G01X899450Y168615D02*
X912651Y181816D01*
G01X903370Y167293D02*
X915277Y179200D01*
G01X902220Y167770D02*
X914464Y180014D01*
G01X903370Y167293D02*
X915277Y179200D01*
G01X902220Y167770D02*
X914464Y180014D01*
G01X899450Y168615D02*
X912651Y181816D01*
G01X898300Y169092D02*
X911838Y182630D01*
G01X899450Y168615D02*
X912651Y181816D01*
G01X898300Y169092D02*
X911838Y182630D01*
G01X902220Y167770D02*
X914464Y180014D01*
G01X903370Y167293D02*
X915277Y179200D01*
G01X902220Y167770D02*
X914464Y180014D01*
G01X903370Y167293D02*
X915277Y179200D01*
G01X905076Y225291D02*
X912120D01*
G01Y224141D02*
X905553D01*
G01X905076Y225291D02*
X912120D01*
G01Y224141D02*
X905553D01*
G01X906863Y219916D02*
X912752D01*
G01Y221066D02*
X906386D01*
G01X906863Y219916D02*
X912752D01*
G01Y221066D02*
X906386D01*
G01X912120Y224141D02*
X905553D01*
G01X905076Y225291D02*
X912120D01*
G01Y224141D02*
X905553D01*
G01X905076Y225291D02*
X912120D01*
G01X912752Y221066D02*
X906386D01*
G01X906863Y219916D02*
X912752D01*
G01Y221066D02*
X906386D01*
G01X906863Y219916D02*
X912752D01*
G01X912120Y224141D02*
X905553D01*
G01X905076Y225291D02*
X912120D01*
G01X912752Y221066D02*
X906386D01*
G01X906863Y219916D02*
X912752D01*
G01X915500Y370405D02*
X908884D01*
G01X915500Y371555D02*
X909361D01*
G01X915500D02*
X909361D01*
G01X915500Y370405D02*
X908884D01*
G01X915500D02*
X908884D01*
G01X915500Y371555D02*
X909361D01*
G01X915500D02*
X909361D01*
G01X915500Y370405D02*
X908884D01*
G01X918144Y417205D02*
X895620Y439729D01*
G01X923276Y413700D02*
X896770Y440206D01*
G01X895620Y439729D02*
Y476878D01*
G01X896770Y440206D02*
Y476401D01*
G01X926968Y417409D02*
X901050Y443327D01*
G01X926968Y417409D02*
X901050Y443327D01*
G01X926968Y417409D02*
X901050Y443327D01*
G01X926968Y417409D02*
X901050Y443327D01*
G01X926968Y417409D02*
X901050Y443327D01*
G01X926968Y417409D02*
X901050Y443327D01*
G01X926968Y417409D02*
X901050Y443327D01*
G01X926968Y417409D02*
X901050Y443327D01*
G01X910581Y432169D02*
X909804Y432946D01*
G01X926968Y417409D02*
X901050Y443327D01*
G01X908318Y434432D02*
X907541Y435209D01*
G01X926968Y417409D02*
X901050Y443327D01*
G01X906055Y436695D02*
X905278Y437472D01*
G01X926968Y417409D02*
X901050Y443327D01*
G01X903792Y438958D02*
X903015Y439735D01*
G01X926968Y417409D02*
X901050Y443327D01*
G01X901529Y441221D02*
X899900Y442850D01*
G01X901050Y443327D02*
Y447273D01*
G01X899900Y442850D02*
Y444550D01*
G01X901050Y443327D02*
Y447273D01*
G01X899900Y446650D02*
Y447750D01*
G01X901050Y447273D02*
X901590Y447813D01*
G01X899900Y447750D02*
X901113Y448963D01*
G01X901590Y447813D02*
X902105D01*
G01X901113Y448963D02*
X901628D01*
G01X902105Y447813D02*
X903480Y449188D01*
G01X901628Y448963D02*
X902330Y449665D01*
G01X903480Y449188D02*
Y451468D01*
G01X902330Y449665D02*
Y450991D01*
G01X903480Y451468D02*
X902105Y452843D01*
G01X902330Y450991D02*
X901628Y451693D01*
G01X902105Y452843D02*
X901382D01*
G01X901628Y451693D02*
X900905D01*
G01X901382Y452843D02*
X900680Y453545D01*
G01X900905Y451693D02*
X899530Y453068D01*
G01X900680Y453545D02*
Y454871D01*
G01X899530Y453068D02*
Y455348D01*
G01X900680Y454871D02*
X901382Y455573D01*
G01X899530Y455348D02*
X900905Y456723D01*
G01X901382Y455573D02*
X903694D01*
G01X900905Y456723D02*
X903217D01*
G01X903694Y455573D02*
X904859Y456738D01*
G01X903217Y456723D02*
X903709Y457215D01*
G01X904859Y456738D02*
Y459413D01*
G01X903709Y457215D02*
Y458936D01*
G01X904859Y459413D02*
X903669Y460603D01*
G01X903709Y458936D02*
X903192Y459453D01*
G01X903669Y460603D02*
X901382D01*
G01X903192Y459453D02*
X900905D01*
G01X901382Y460603D02*
X900680Y461305D01*
G01X900905Y459453D02*
X899530Y460828D01*
G01X900680Y461305D02*
Y474309D01*
G01X899530Y460828D02*
Y474786D01*
G01X923276Y413700D02*
X896770Y440206D01*
G01X923276Y413700D02*
X896770Y440206D01*
G01X923276Y413700D02*
X896770Y440206D01*
G01X918144Y417205D02*
X895620Y439729D01*
G01X896770Y440206D02*
Y476401D01*
G01X895620Y439729D02*
Y476878D01*
G01X910581Y432169D02*
X909804Y432946D01*
G01X908318Y434432D02*
X907541Y435209D01*
G01X906055Y436695D02*
X905278Y437472D01*
G01X903792Y438958D02*
X903015Y439735D01*
G01X901529Y441221D02*
X899900Y442850D01*
G01X926968Y417409D02*
X901050Y443327D01*
G01X899900Y442850D02*
Y444550D01*
G01Y446650D02*
Y447750D01*
G01X901050Y443327D02*
Y447273D01*
G01X899900Y447750D02*
X901113Y448963D01*
G01X901050Y447273D02*
X901590Y447813D01*
G01X901113Y448963D02*
X901628D01*
G01X901590Y447813D02*
X902105D01*
G01X901628Y448963D02*
X902330Y449665D01*
G01X902105Y447813D02*
X903480Y449188D01*
G01X902330Y449665D02*
Y450991D01*
G01X903480Y449188D02*
Y451468D01*
G01X902330Y450991D02*
X901628Y451693D01*
G01X903480Y451468D02*
X902105Y452843D01*
G01X901628Y451693D02*
X900905D01*
G01X902105Y452843D02*
X901382D01*
G01X900905Y451693D02*
X899530Y453068D01*
G01X901382Y452843D02*
X900680Y453545D01*
G01X899530Y453068D02*
Y455348D01*
G01X900680Y453545D02*
Y454871D01*
G01X899530Y455348D02*
X900905Y456723D01*
G01X900680Y454871D02*
X901382Y455573D01*
G01X900905Y456723D02*
X903217D01*
G01X901382Y455573D02*
X903694D01*
G01X903217Y456723D02*
X903709Y457215D01*
G01X903694Y455573D02*
X904859Y456738D01*
G01X903709Y457215D02*
Y458936D01*
G01X904859Y456738D02*
Y459413D01*
G01X903709Y458936D02*
X903192Y459453D01*
G01X904859Y459413D02*
X903669Y460603D01*
G01X903192Y459453D02*
X900905D01*
G01X903669Y460603D02*
X901382D01*
G01X900905Y459453D02*
X899530Y460828D01*
G01X901382Y460603D02*
X900680Y461305D01*
G01X899530Y460828D02*
Y474786D01*
G01X900680Y461305D02*
Y474309D01*
G01X918144Y417205D02*
X895620Y439729D01*
G01X923276Y413700D02*
X896770Y440206D01*
G01X895620Y439729D02*
Y476878D01*
G01X896770Y440206D02*
Y476401D01*
G01X926968Y417409D02*
X901050Y443327D01*
G01X926968Y417409D02*
X901050Y443327D01*
G01X926968Y417409D02*
X901050Y443327D01*
G01X926968Y417409D02*
X901050Y443327D01*
G01X926968Y417409D02*
X901050Y443327D01*
G01X926968Y417409D02*
X901050Y443327D01*
G01X926968Y417409D02*
X901050Y443327D01*
G01X926968Y417409D02*
X901050Y443327D01*
G01X910581Y432169D02*
X909804Y432946D01*
G01X926968Y417409D02*
X901050Y443327D01*
G01X908318Y434432D02*
X907541Y435209D01*
G01X926968Y417409D02*
X901050Y443327D01*
G01X906055Y436695D02*
X905278Y437472D01*
G01X926968Y417409D02*
X901050Y443327D01*
G01X903792Y438958D02*
X903015Y439735D01*
G01X926968Y417409D02*
X901050Y443327D01*
G01X901529Y441221D02*
X899900Y442850D01*
G01X901050Y443327D02*
Y447273D01*
G01X899900Y442850D02*
Y444550D01*
G01X901050Y443327D02*
Y447273D01*
G01X899900Y446650D02*
Y447750D01*
G01X901050Y447273D02*
X901590Y447813D01*
G01X899900Y447750D02*
X901113Y448963D01*
G01X901590Y447813D02*
X902105D01*
G01X901113Y448963D02*
X901628D01*
G01X902105Y447813D02*
X903480Y449188D01*
G01X901628Y448963D02*
X902330Y449665D01*
G01X903480Y449188D02*
Y451468D01*
G01X902330Y449665D02*
Y450991D01*
G01X903480Y451468D02*
X902105Y452843D01*
G01X902330Y450991D02*
X901628Y451693D01*
G01X902105Y452843D02*
X901382D01*
G01X901628Y451693D02*
X900905D01*
G01X901382Y452843D02*
X900680Y453545D01*
G01X900905Y451693D02*
X899530Y453068D01*
G01X900680Y453545D02*
Y454871D01*
G01X899530Y453068D02*
Y455348D01*
G01X900680Y454871D02*
X901382Y455573D01*
G01X899530Y455348D02*
X900905Y456723D01*
G01X901382Y455573D02*
X903694D01*
G01X900905Y456723D02*
X903217D01*
G01X903694Y455573D02*
X904859Y456738D01*
G01X903217Y456723D02*
X903709Y457215D01*
G01X904859Y456738D02*
Y459413D01*
G01X903709Y457215D02*
Y458936D01*
G01X904859Y459413D02*
X903669Y460603D01*
G01X903709Y458936D02*
X903192Y459453D01*
G01X903669Y460603D02*
X901382D01*
G01X903192Y459453D02*
X900905D01*
G01X901382Y460603D02*
X900680Y461305D01*
G01X900905Y459453D02*
X899530Y460828D01*
G01X900680Y461305D02*
Y474309D01*
G01X899530Y460828D02*
Y474786D01*
G01X923276Y413700D02*
X896770Y440206D01*
G01X923276Y413700D02*
X896770Y440206D01*
G01X923276Y413700D02*
X896770Y440206D01*
G01X918144Y417205D02*
X895620Y439729D01*
G01X896770Y440206D02*
Y476401D01*
G01X895620Y439729D02*
Y476878D01*
G01X910581Y432169D02*
X909804Y432946D01*
G01X908318Y434432D02*
X907541Y435209D01*
G01X906055Y436695D02*
X905278Y437472D01*
G01X903792Y438958D02*
X903015Y439735D01*
G01X901529Y441221D02*
X899900Y442850D01*
G01X926968Y417409D02*
X901050Y443327D01*
G01X899900Y442850D02*
Y444550D01*
G01Y446650D02*
Y447750D01*
G01X901050Y443327D02*
Y447273D01*
G01X899900Y447750D02*
X901113Y448963D01*
G01X901050Y447273D02*
X901590Y447813D01*
G01X901113Y448963D02*
X901628D01*
G01X901590Y447813D02*
X902105D01*
G01X901628Y448963D02*
X902330Y449665D01*
G01X902105Y447813D02*
X903480Y449188D01*
G01X902330Y449665D02*
Y450991D01*
G01X903480Y449188D02*
Y451468D01*
G01X902330Y450991D02*
X901628Y451693D01*
G01X903480Y451468D02*
X902105Y452843D01*
G01X901628Y451693D02*
X900905D01*
G01X902105Y452843D02*
X901382D01*
G01X900905Y451693D02*
X899530Y453068D01*
G01X901382Y452843D02*
X900680Y453545D01*
G01X899530Y453068D02*
Y455348D01*
G01X900680Y453545D02*
Y454871D01*
G01X899530Y455348D02*
X900905Y456723D01*
G01X900680Y454871D02*
X901382Y455573D01*
G01X900905Y456723D02*
X903217D01*
G01X901382Y455573D02*
X903694D01*
G01X903217Y456723D02*
X903709Y457215D01*
G01X903694Y455573D02*
X904859Y456738D01*
G01X903709Y457215D02*
Y458936D01*
G01X904859Y456738D02*
Y459413D01*
G01X903709Y458936D02*
X903192Y459453D01*
G01X904859Y459413D02*
X903669Y460603D01*
G01X903192Y459453D02*
X900905D01*
G01X903669Y460603D02*
X901382D01*
G01X900905Y459453D02*
X899530Y460828D01*
G01X901382Y460603D02*
X900680Y461305D01*
G01X899530Y460828D02*
Y474786D01*
G01X900680Y461305D02*
Y474309D01*
G01X895620Y476878D02*
X896250Y477508D01*
G01X896770Y476401D02*
X897400Y477031D01*
G01X896250Y477508D02*
Y481891D01*
G01X897400Y477031D02*
Y482368D01*
G01X896250Y481891D02*
X895620Y482521D01*
G01X897400Y482368D02*
X896770Y482998D01*
G01X895620Y482521D02*
Y486648D01*
G01X896770Y482998D02*
Y486171D01*
G01X895620Y486648D02*
X896258Y487286D01*
G01X897484Y488512D02*
X898724Y489752D01*
G01X896770Y486171D02*
X899874Y489275D01*
G01X898724Y489752D02*
Y492394D01*
G01X899874Y489275D02*
Y492871D01*
G01X898724Y492394D02*
X897909Y493209D01*
G01X899874Y492871D02*
X896836Y495909D01*
G01X900680Y474309D02*
X902800Y476429D01*
G01X899530Y474786D02*
X901650Y476906D01*
G01X902800Y476429D02*
Y486973D01*
G01X901650Y476906D02*
Y477750D01*
G01X902800Y476429D02*
Y486973D01*
G01X901650Y479850D02*
Y481050D01*
G01X902800Y476429D02*
Y486973D01*
G01X901650Y483150D02*
Y484150D01*
G01X902800Y476429D02*
Y486973D01*
G01X901650Y486350D02*
Y487450D01*
G01X902800Y486973D02*
X904974Y489147D01*
G01X901650Y487450D02*
X903824Y489624D01*
G01X904974Y489147D02*
Y492761D01*
G01X903824Y489624D02*
Y492284D01*
G01X904974Y492761D02*
X901921Y495814D01*
G01X903824Y492284D02*
X902894Y493214D01*
G01X896770Y476401D02*
X897400Y477031D01*
G01X895620Y476878D02*
X896250Y477508D01*
G01X897400Y477031D02*
Y482368D01*
G01X896250Y477508D02*
Y481891D01*
G01X897400Y482368D02*
X896770Y482998D01*
G01X896250Y481891D02*
X895620Y482521D01*
G01X896770Y482998D02*
Y486171D01*
G01X895620Y482521D02*
Y486648D01*
G01X896770Y486171D02*
X899874Y489275D01*
G01X895620Y486648D02*
X896258Y487286D01*
G01X896770Y486171D02*
X899874Y489275D01*
G01X897484Y488512D02*
X898724Y489752D01*
G01X899874Y489275D02*
Y492871D01*
G01X898724Y489752D02*
Y492394D01*
G01X899874Y492871D02*
X896836Y495909D01*
G01X898724Y492394D02*
X897909Y493209D01*
G01X899530Y474786D02*
X901650Y476906D01*
G01X900680Y474309D02*
X902800Y476429D01*
G01X901650Y476906D02*
Y477750D01*
G01Y479850D02*
Y481050D01*
G01Y483150D02*
Y484150D01*
G01Y486350D02*
Y487450D01*
G01X902800Y476429D02*
Y486973D01*
G01X901650Y487450D02*
X903824Y489624D01*
G01X902800Y486973D02*
X904974Y489147D01*
G01X903824Y489624D02*
Y492284D01*
G01X904974Y489147D02*
Y492761D01*
G01X903824Y492284D02*
X902894Y493214D01*
G01X904974Y492761D02*
X901921Y495814D01*
G01X895620Y476878D02*
X896250Y477508D01*
G01X896770Y476401D02*
X897400Y477031D01*
G01X896250Y477508D02*
Y481891D01*
G01X897400Y477031D02*
Y482368D01*
G01X896250Y481891D02*
X895620Y482521D01*
G01X897400Y482368D02*
X896770Y482998D01*
G01X895620Y482521D02*
Y486648D01*
G01X896770Y482998D02*
Y486171D01*
G01X895620Y486648D02*
X896258Y487286D01*
G01X897484Y488512D02*
X898724Y489752D01*
G01X896770Y486171D02*
X899874Y489275D01*
G01X898724Y489752D02*
Y492394D01*
G01X899874Y489275D02*
Y492871D01*
G01X898724Y492394D02*
X897909Y493209D01*
G01X899874Y492871D02*
X896836Y495909D01*
G01X900680Y474309D02*
X902800Y476429D01*
G01X899530Y474786D02*
X901650Y476906D01*
G01X902800Y476429D02*
Y486973D01*
G01X901650Y476906D02*
Y477750D01*
G01X902800Y476429D02*
Y486973D01*
G01X901650Y479850D02*
Y481050D01*
G01X902800Y476429D02*
Y486973D01*
G01X901650Y483150D02*
Y484150D01*
G01X902800Y476429D02*
Y486973D01*
G01X901650Y486350D02*
Y487450D01*
G01X902800Y486973D02*
X904974Y489147D01*
G01X901650Y487450D02*
X903824Y489624D01*
G01X904974Y489147D02*
Y492761D01*
G01X903824Y489624D02*
Y492284D01*
G01X904974Y492761D02*
X901921Y495814D01*
G01X903824Y492284D02*
X902894Y493214D01*
G01X896770Y476401D02*
X897400Y477031D01*
G01X895620Y476878D02*
X896250Y477508D01*
G01X897400Y477031D02*
Y482368D01*
G01X896250Y477508D02*
Y481891D01*
G01X897400Y482368D02*
X896770Y482998D01*
G01X896250Y481891D02*
X895620Y482521D01*
G01X896770Y482998D02*
Y486171D01*
G01X895620Y482521D02*
Y486648D01*
G01X896770Y486171D02*
X899874Y489275D01*
G01X895620Y486648D02*
X896258Y487286D01*
G01X896770Y486171D02*
X899874Y489275D01*
G01X897484Y488512D02*
X898724Y489752D01*
G01X899874Y489275D02*
Y492871D01*
G01X898724Y489752D02*
Y492394D01*
G01X899874Y492871D02*
X896836Y495909D01*
G01X898724Y492394D02*
X897909Y493209D01*
G01X899530Y474786D02*
X901650Y476906D01*
G01X900680Y474309D02*
X902800Y476429D01*
G01X901650Y476906D02*
Y477750D01*
G01Y479850D02*
Y481050D01*
G01Y483150D02*
Y484150D01*
G01Y486350D02*
Y487450D01*
G01X902800Y476429D02*
Y486973D01*
G01X901650Y487450D02*
X903824Y489624D01*
G01X902800Y486973D02*
X904974Y489147D01*
G01X903824Y489624D02*
Y492284D01*
G01X904974Y489147D02*
Y492761D01*
G01X903824Y492284D02*
X902894Y493214D01*
G01X904974Y492761D02*
X901921Y495814D01*
G01X932079Y115324D02*
Y117728D01*
G01X933229Y115801D02*
Y117251D01*
G01X932079Y117728D02*
X942425Y128074D01*
G01X933229Y117251D02*
X933936Y117958D01*
G01X932079Y117728D02*
X942425Y128074D01*
G01X935351Y119373D02*
X936058Y120080D01*
G01X932079Y117728D02*
X942425Y128074D01*
G01X937473Y121495D02*
X938180Y122202D01*
G01X932079Y117728D02*
X942425Y128074D01*
G01X939595Y123617D02*
X940302Y124324D01*
G01X932079Y117728D02*
X942425Y128074D01*
G01X941717Y125739D02*
X942424Y126446D01*
G01X942425Y128074D02*
X944150Y129799D01*
G01X943839Y127861D02*
X945300Y129322D01*
G01X944150Y129799D02*
Y132190D01*
G01X945300Y129322D02*
Y132667D01*
G01X944150Y132190D02*
X943500Y132840D01*
G01X945300Y132667D02*
X943977Y133990D01*
G01X943500Y132840D02*
X941573D01*
G01X943977Y133990D02*
X942050D01*
G01X941573Y132840D02*
X940400Y134013D01*
G01X942050Y133990D02*
X941550Y134490D01*
G01X940400Y134013D02*
Y136617D01*
G01X941550Y134490D02*
Y136140D01*
G01X940400Y136617D02*
X941573Y137790D01*
G01X941550Y136140D02*
X942050Y136640D01*
G01X941573Y137790D02*
X943500D01*
G01X942050Y136640D02*
X943977D01*
G01X943500Y137790D02*
X944150Y138440D01*
G01X943977Y136640D02*
X945300Y137963D01*
G01X944150Y138440D02*
Y141434D01*
G01X945300Y137963D02*
Y140000D01*
G01X944150Y138440D02*
Y141434D01*
G01X945300Y140000D02*
Y141911D01*
G01X944150Y141434D02*
X943434Y142150D01*
G01X945300Y141911D02*
X943911Y143300D01*
G01X943434Y142150D02*
X941189D01*
G01X943911Y143300D02*
X941666D01*
G01X941189Y142150D02*
X939450Y143889D01*
G01X941666Y143300D02*
X940600Y144366D01*
G01X939450Y143889D02*
Y162232D01*
G01X940600Y144366D02*
Y145900D01*
G01X939450Y143889D02*
Y162232D01*
G01X940600Y147900D02*
Y149000D01*
G01X939450Y143889D02*
Y162232D01*
G01X940600Y151000D02*
Y152400D01*
G01X939450Y143889D02*
Y162232D01*
G01X940600Y154400D02*
Y155400D01*
G01X939450Y143889D02*
Y162232D01*
G01Y143889D02*
Y162232D01*
G01X949150Y133537D02*
Y134577D01*
G01Y136577D02*
Y137577D01*
G01Y139577D02*
Y140577D01*
G01Y142577D02*
Y143577D01*
G01X948000Y130500D02*
Y143100D01*
G01X949150Y143577D02*
X948550Y144177D01*
G01X948000Y143100D02*
X947400Y143700D01*
G01X948550Y144177D02*
Y147563D01*
G01X947400Y143700D02*
Y147086D01*
G01X948550Y147563D02*
X946650Y149463D01*
G01X947400Y147086D02*
X945500Y148986D01*
G01X946650Y149463D02*
Y150717D01*
G01Y152717D02*
Y153717D01*
G01Y155717D02*
Y156717D01*
G01X945500Y148986D02*
Y160194D01*
G01X939500Y117373D02*
X942440Y120313D01*
G01X936963Y116463D02*
X941963Y121463D01*
G01X942440Y120313D02*
X943172D01*
G01X941963Y121463D02*
X942695D01*
G01X943172Y120313D02*
X946130Y123271D01*
G01X942695Y121463D02*
X944980Y123748D01*
G01X946130Y123271D02*
Y124003D01*
G01X944980Y123748D02*
Y124480D01*
G01X946130Y124003D02*
X949150Y127023D01*
G01X944980Y124480D02*
X948000Y127500D01*
G01X949150Y127023D02*
Y131739D01*
G01X948000Y127500D02*
Y130500D01*
G01X933229Y115801D02*
Y117251D01*
G01X932079Y115324D02*
Y117728D01*
G01X933229Y117251D02*
X933936Y117958D01*
G01X935351Y119373D02*
X936058Y120080D01*
G01X937473Y121495D02*
X938180Y122202D01*
G01X939595Y123617D02*
X940302Y124324D01*
G01X941717Y125739D02*
X942424Y126446D01*
G01X932079Y117728D02*
X942425Y128074D01*
G01X943839Y127861D02*
X945300Y129322D01*
G01X942425Y128074D02*
X944150Y129799D01*
G01X945300Y129322D02*
Y132667D01*
G01X944150Y129799D02*
Y132190D01*
G01X945300Y132667D02*
X943977Y133990D01*
G01X944150Y132190D02*
X943500Y132840D01*
G01X943977Y133990D02*
X942050D01*
G01X943500Y132840D02*
X941573D01*
G01X942050Y133990D02*
X941550Y134490D01*
G01X941573Y132840D02*
X940400Y134013D01*
G01X941550Y134490D02*
Y136140D01*
G01X940400Y134013D02*
Y136617D01*
G01X941550Y136140D02*
X942050Y136640D01*
G01X940400Y136617D02*
X941573Y137790D01*
G01X942050Y136640D02*
X943977D01*
G01X941573Y137790D02*
X943500D01*
G01X943977Y136640D02*
X945300Y137963D01*
G01X943500Y137790D02*
X944150Y138440D01*
G01X945300Y137963D02*
Y140000D01*
G01D02*
Y141911D01*
G01X944150Y138440D02*
Y141434D01*
G01X945300Y141911D02*
X943911Y143300D01*
G01X944150Y141434D02*
X943434Y142150D01*
G01X943911Y143300D02*
X941666D01*
G01X943434Y142150D02*
X941189D01*
G01X941666Y143300D02*
X940600Y144366D01*
G01X941189Y142150D02*
X939450Y143889D01*
G01X940600Y144366D02*
Y145900D01*
G01Y147900D02*
Y149000D01*
G01Y151000D02*
Y152400D01*
G01Y154400D02*
Y155400D01*
G01X939450Y143889D02*
Y162232D01*
G01X936963Y116463D02*
X941963Y121463D01*
G01X939500Y117373D02*
X942440Y120313D01*
G01X941963Y121463D02*
X942695D01*
G01X942440Y120313D02*
X943172D01*
G01X942695Y121463D02*
X944980Y123748D01*
G01X943172Y120313D02*
X946130Y123271D01*
G01X944980Y123748D02*
Y124480D01*
G01X946130Y123271D02*
Y124003D01*
G01X944980Y124480D02*
X948000Y127500D01*
G01X946130Y124003D02*
X949150Y127023D01*
G01X948000Y127500D02*
Y130500D01*
G01X949150Y127023D02*
Y131739D01*
G01X948000Y130500D02*
Y143100D01*
G01X949150Y133537D02*
Y134577D01*
G01X948000Y130500D02*
Y143100D01*
G01X949150Y136577D02*
Y137577D01*
G01X948000Y130500D02*
Y143100D01*
G01X949150Y139577D02*
Y140577D01*
G01X948000Y130500D02*
Y143100D01*
G01X949150Y142577D02*
Y143577D01*
G01X948000Y143100D02*
X947400Y143700D01*
G01X949150Y143577D02*
X948550Y144177D01*
G01X947400Y143700D02*
Y147086D01*
G01X948550Y144177D02*
Y147563D01*
G01X947400Y147086D02*
X945500Y148986D01*
G01X948550Y147563D02*
X946650Y149463D01*
G01X945500Y148986D02*
Y160194D01*
G01X946650Y149463D02*
Y150717D01*
G01X945500Y148986D02*
Y160194D01*
G01X946650Y152717D02*
Y153717D01*
G01X945500Y148986D02*
Y160194D01*
G01X946650Y155717D02*
Y156717D01*
G01X945500Y148986D02*
Y160194D01*
G01X932079Y115324D02*
Y117728D01*
G01X933229Y115801D02*
Y117251D01*
G01X932079Y117728D02*
X942425Y128074D01*
G01X933229Y117251D02*
X933936Y117958D01*
G01X932079Y117728D02*
X942425Y128074D01*
G01X935351Y119373D02*
X936058Y120080D01*
G01X932079Y117728D02*
X942425Y128074D01*
G01X937473Y121495D02*
X938180Y122202D01*
G01X932079Y117728D02*
X942425Y128074D01*
G01X939595Y123617D02*
X940302Y124324D01*
G01X932079Y117728D02*
X942425Y128074D01*
G01X941717Y125739D02*
X942424Y126446D01*
G01X942425Y128074D02*
X944150Y129799D01*
G01X943839Y127861D02*
X945300Y129322D01*
G01X944150Y129799D02*
Y132190D01*
G01X945300Y129322D02*
Y132667D01*
G01X944150Y132190D02*
X943500Y132840D01*
G01X945300Y132667D02*
X943977Y133990D01*
G01X943500Y132840D02*
X941573D01*
G01X943977Y133990D02*
X942050D01*
G01X941573Y132840D02*
X940400Y134013D01*
G01X942050Y133990D02*
X941550Y134490D01*
G01X940400Y134013D02*
Y136617D01*
G01X941550Y134490D02*
Y136140D01*
G01X940400Y136617D02*
X941573Y137790D01*
G01X941550Y136140D02*
X942050Y136640D01*
G01X941573Y137790D02*
X943500D01*
G01X942050Y136640D02*
X943977D01*
G01X943500Y137790D02*
X944150Y138440D01*
G01X943977Y136640D02*
X945300Y137963D01*
G01X944150Y138440D02*
Y141434D01*
G01X945300Y137963D02*
Y140000D01*
G01X944150Y138440D02*
Y141434D01*
G01X945300Y140000D02*
Y141911D01*
G01X944150Y141434D02*
X943434Y142150D01*
G01X945300Y141911D02*
X943911Y143300D01*
G01X943434Y142150D02*
X941189D01*
G01X943911Y143300D02*
X941666D01*
G01X941189Y142150D02*
X939450Y143889D01*
G01X941666Y143300D02*
X940600Y144366D01*
G01X939450Y143889D02*
Y162232D01*
G01X940600Y144366D02*
Y145900D01*
G01X939450Y143889D02*
Y162232D01*
G01X940600Y147900D02*
Y149000D01*
G01X939450Y143889D02*
Y162232D01*
G01X940600Y151000D02*
Y152400D01*
G01X939450Y143889D02*
Y162232D01*
G01X940600Y154400D02*
Y155400D01*
G01X939450Y143889D02*
Y162232D01*
G01Y143889D02*
Y162232D01*
G01X932079Y115324D02*
Y117728D01*
G01X933229Y115801D02*
Y117251D01*
G01X932079Y117728D02*
X942425Y128074D01*
G01X933229Y117251D02*
X933936Y117958D01*
G01X932079Y117728D02*
X942425Y128074D01*
G01X935351Y119373D02*
X936058Y120080D01*
G01X932079Y117728D02*
X942425Y128074D01*
G01X937473Y121495D02*
X938180Y122202D01*
G01X932079Y117728D02*
X942425Y128074D01*
G01X939595Y123617D02*
X940302Y124324D01*
G01X932079Y117728D02*
X942425Y128074D01*
G01X941717Y125739D02*
X942424Y126446D01*
G01X942425Y128074D02*
X944150Y129799D01*
G01X943839Y127861D02*
X945300Y129322D01*
G01X944150Y129799D02*
Y132190D01*
G01X945300Y129322D02*
Y132667D01*
G01X944150Y132190D02*
X943500Y132840D01*
G01X945300Y132667D02*
X943977Y133990D01*
G01X943500Y132840D02*
X941573D01*
G01X943977Y133990D02*
X942050D01*
G01X941573Y132840D02*
X940400Y134013D01*
G01X942050Y133990D02*
X941550Y134490D01*
G01X940400Y134013D02*
Y136617D01*
G01X941550Y134490D02*
Y136140D01*
G01X940400Y136617D02*
X941573Y137790D01*
G01X941550Y136140D02*
X942050Y136640D01*
G01X941573Y137790D02*
X943500D01*
G01X942050Y136640D02*
X943977D01*
G01X943500Y137790D02*
X944150Y138440D01*
G01X943977Y136640D02*
X945300Y137963D01*
G01X944150Y138440D02*
Y141434D01*
G01X945300Y137963D02*
Y140000D01*
G01X944150Y138440D02*
Y141434D01*
G01X945300Y140000D02*
Y141911D01*
G01X944150Y141434D02*
X943434Y142150D01*
G01X945300Y141911D02*
X943911Y143300D01*
G01X943434Y142150D02*
X941189D01*
G01X943911Y143300D02*
X941666D01*
G01X941189Y142150D02*
X939450Y143889D01*
G01X941666Y143300D02*
X940600Y144366D01*
G01X939450Y143889D02*
Y162232D01*
G01X940600Y144366D02*
Y145900D01*
G01X939450Y143889D02*
Y162232D01*
G01X940600Y147900D02*
Y149000D01*
G01X939450Y143889D02*
Y162232D01*
G01X940600Y151000D02*
Y152400D01*
G01X939450Y143889D02*
Y162232D01*
G01X940600Y154400D02*
Y155400D01*
G01X939450Y143889D02*
Y162232D01*
G01Y143889D02*
Y162232D01*
G01X949150Y133537D02*
Y134577D01*
G01Y136577D02*
Y137577D01*
G01Y139577D02*
Y140577D01*
G01Y142577D02*
Y143577D01*
G01X948000Y130500D02*
Y143100D01*
G01X949150Y143577D02*
X948550Y144177D01*
G01X948000Y143100D02*
X947400Y143700D01*
G01X948550Y144177D02*
Y147563D01*
G01X947400Y143700D02*
Y147086D01*
G01X948550Y147563D02*
X946650Y149463D01*
G01X947400Y147086D02*
X945500Y148986D01*
G01X946650Y149463D02*
Y150717D01*
G01Y152717D02*
Y153717D01*
G01Y155717D02*
Y156717D01*
G01X945500Y148986D02*
Y160194D01*
G01X939500Y117373D02*
X942440Y120313D01*
G01X936963Y116463D02*
X941963Y121463D01*
G01X942440Y120313D02*
X943172D01*
G01X941963Y121463D02*
X942695D01*
G01X943172Y120313D02*
X946130Y123271D01*
G01X942695Y121463D02*
X944980Y123748D01*
G01X946130Y123271D02*
Y124003D01*
G01X944980Y123748D02*
Y124480D01*
G01X946130Y124003D02*
X949150Y127023D01*
G01X944980Y124480D02*
X948000Y127500D01*
G01X949150Y127023D02*
Y131739D01*
G01X948000Y127500D02*
Y130500D01*
G01X949150Y133537D02*
Y134577D01*
G01Y136577D02*
Y137577D01*
G01Y139577D02*
Y140577D01*
G01Y142577D02*
Y143577D01*
G01X948000Y130500D02*
Y143100D01*
G01X949150Y143577D02*
X948550Y144177D01*
G01X948000Y143100D02*
X947400Y143700D01*
G01X948550Y144177D02*
Y147563D01*
G01X947400Y143700D02*
Y147086D01*
G01X948550Y147563D02*
X946650Y149463D01*
G01X947400Y147086D02*
X945500Y148986D01*
G01X946650Y149463D02*
Y150717D01*
G01Y152717D02*
Y153717D01*
G01Y155717D02*
Y156717D01*
G01X945500Y148986D02*
Y160194D01*
G01X939500Y117373D02*
X942440Y120313D01*
G01X936963Y116463D02*
X941963Y121463D01*
G01X942440Y120313D02*
X943172D01*
G01X941963Y121463D02*
X942695D01*
G01X943172Y120313D02*
X946130Y123271D01*
G01X942695Y121463D02*
X944980Y123748D01*
G01X946130Y123271D02*
Y124003D01*
G01X944980Y123748D02*
Y124480D01*
G01X946130Y124003D02*
X949150Y127023D01*
G01X944980Y124480D02*
X948000Y127500D01*
G01X949150Y127023D02*
Y131739D01*
G01X948000Y127500D02*
Y130500D01*
G01X933229Y115801D02*
Y117251D01*
G01X932079Y115324D02*
Y117728D01*
G01X933229Y117251D02*
X933936Y117958D01*
G01X935351Y119373D02*
X936058Y120080D01*
G01X937473Y121495D02*
X938180Y122202D01*
G01X939595Y123617D02*
X940302Y124324D01*
G01X941717Y125739D02*
X942424Y126446D01*
G01X932079Y117728D02*
X942425Y128074D01*
G01X943839Y127861D02*
X945300Y129322D01*
G01X942425Y128074D02*
X944150Y129799D01*
G01X945300Y129322D02*
Y132667D01*
G01X944150Y129799D02*
Y132190D01*
G01X945300Y132667D02*
X943977Y133990D01*
G01X944150Y132190D02*
X943500Y132840D01*
G01X943977Y133990D02*
X942050D01*
G01X943500Y132840D02*
X941573D01*
G01X942050Y133990D02*
X941550Y134490D01*
G01X941573Y132840D02*
X940400Y134013D01*
G01X941550Y134490D02*
Y136140D01*
G01X940400Y134013D02*
Y136617D01*
G01X941550Y136140D02*
X942050Y136640D01*
G01X940400Y136617D02*
X941573Y137790D01*
G01X942050Y136640D02*
X943977D01*
G01X941573Y137790D02*
X943500D01*
G01X943977Y136640D02*
X945300Y137963D01*
G01X943500Y137790D02*
X944150Y138440D01*
G01X945300Y137963D02*
Y140000D01*
G01D02*
Y141911D01*
G01X944150Y138440D02*
Y141434D01*
G01X945300Y141911D02*
X943911Y143300D01*
G01X944150Y141434D02*
X943434Y142150D01*
G01X943911Y143300D02*
X941666D01*
G01X943434Y142150D02*
X941189D01*
G01X941666Y143300D02*
X940600Y144366D01*
G01X941189Y142150D02*
X939450Y143889D01*
G01X940600Y144366D02*
Y145900D01*
G01Y147900D02*
Y149000D01*
G01Y151000D02*
Y152400D01*
G01Y154400D02*
Y155400D01*
G01X939450Y143889D02*
Y162232D01*
G01X933229Y115801D02*
Y117251D01*
G01X932079Y115324D02*
Y117728D01*
G01X933229Y117251D02*
X933936Y117958D01*
G01X935351Y119373D02*
X936058Y120080D01*
G01X937473Y121495D02*
X938180Y122202D01*
G01X939595Y123617D02*
X940302Y124324D01*
G01X941717Y125739D02*
X942424Y126446D01*
G01X932079Y117728D02*
X942425Y128074D01*
G01X943839Y127861D02*
X945300Y129322D01*
G01X942425Y128074D02*
X944150Y129799D01*
G01X945300Y129322D02*
Y132667D01*
G01X944150Y129799D02*
Y132190D01*
G01X945300Y132667D02*
X943977Y133990D01*
G01X944150Y132190D02*
X943500Y132840D01*
G01X943977Y133990D02*
X942050D01*
G01X943500Y132840D02*
X941573D01*
G01X942050Y133990D02*
X941550Y134490D01*
G01X941573Y132840D02*
X940400Y134013D01*
G01X941550Y134490D02*
Y136140D01*
G01X940400Y134013D02*
Y136617D01*
G01X941550Y136140D02*
X942050Y136640D01*
G01X940400Y136617D02*
X941573Y137790D01*
G01X942050Y136640D02*
X943977D01*
G01X941573Y137790D02*
X943500D01*
G01X943977Y136640D02*
X945300Y137963D01*
G01X943500Y137790D02*
X944150Y138440D01*
G01X945300Y137963D02*
Y140000D01*
G01D02*
Y141911D01*
G01X944150Y138440D02*
Y141434D01*
G01X945300Y141911D02*
X943911Y143300D01*
G01X944150Y141434D02*
X943434Y142150D01*
G01X943911Y143300D02*
X941666D01*
G01X943434Y142150D02*
X941189D01*
G01X941666Y143300D02*
X940600Y144366D01*
G01X941189Y142150D02*
X939450Y143889D01*
G01X940600Y144366D02*
Y145900D01*
G01Y147900D02*
Y149000D01*
G01Y151000D02*
Y152400D01*
G01Y154400D02*
Y155400D01*
G01X939450Y143889D02*
Y162232D01*
G01X936963Y116463D02*
X941963Y121463D01*
G01X939500Y117373D02*
X942440Y120313D01*
G01X941963Y121463D02*
X942695D01*
G01X942440Y120313D02*
X943172D01*
G01X942695Y121463D02*
X944980Y123748D01*
G01X943172Y120313D02*
X946130Y123271D01*
G01X944980Y123748D02*
Y124480D01*
G01X946130Y123271D02*
Y124003D01*
G01X944980Y124480D02*
X948000Y127500D01*
G01X946130Y124003D02*
X949150Y127023D01*
G01X948000Y127500D02*
Y130500D01*
G01X949150Y127023D02*
Y131739D01*
G01X948000Y130500D02*
Y143100D01*
G01X949150Y133537D02*
Y134577D01*
G01X948000Y130500D02*
Y143100D01*
G01X949150Y136577D02*
Y137577D01*
G01X948000Y130500D02*
Y143100D01*
G01X949150Y139577D02*
Y140577D01*
G01X948000Y130500D02*
Y143100D01*
G01X949150Y142577D02*
Y143577D01*
G01X948000Y143100D02*
X947400Y143700D01*
G01X949150Y143577D02*
X948550Y144177D01*
G01X947400Y143700D02*
Y147086D01*
G01X948550Y144177D02*
Y147563D01*
G01X947400Y147086D02*
X945500Y148986D01*
G01X948550Y147563D02*
X946650Y149463D01*
G01X945500Y148986D02*
Y160194D01*
G01X946650Y149463D02*
Y150717D01*
G01X945500Y148986D02*
Y160194D01*
G01X946650Y152717D02*
Y153717D01*
G01X945500Y148986D02*
Y160194D01*
G01X946650Y155717D02*
Y156717D01*
G01X945500Y148986D02*
Y160194D01*
G01X940600Y157400D02*
Y158755D01*
G01Y160755D02*
Y161755D01*
G01X939450Y162232D02*
X947644Y170426D01*
G01X940600Y161755D02*
X941307Y162462D01*
G01X939450Y162232D02*
X947644Y170426D01*
G01X941307Y162462D02*
X942014D01*
G01X939450Y162232D02*
X947644Y170426D01*
G01X942722Y163877D02*
X943429Y164584D01*
G01X939450Y162232D02*
X947644Y170426D01*
G01X943429Y164584D02*
X944136D01*
G01X939450Y162232D02*
X947644Y170426D01*
G01X944844Y165999D02*
X948457Y169612D01*
G01X946650Y158717D02*
Y159717D01*
G01D02*
X948550Y161617D01*
G01X945500Y160194D02*
X947400Y162094D01*
G01X948550Y161617D02*
Y164417D01*
G01X947400Y162094D02*
Y164894D01*
G01X948550Y164417D02*
X950998Y166865D01*
G01X947400Y164894D02*
X950184Y167678D01*
G01X940600Y157400D02*
Y158755D01*
G01Y160755D02*
Y161755D01*
G01D02*
X941307Y162462D01*
G01D02*
X942014D01*
G01X942722Y163877D02*
X943429Y164584D01*
G01D02*
X944136D01*
G01X944844Y165999D02*
X948457Y169612D01*
G01X939450Y162232D02*
X947644Y170426D01*
G01X946650Y158717D02*
Y159717D01*
G01X945500Y160194D02*
X947400Y162094D01*
G01X946650Y159717D02*
X948550Y161617D01*
G01X947400Y162094D02*
Y164894D01*
G01X948550Y161617D02*
Y164417D01*
G01X947400Y164894D02*
X950184Y167678D01*
G01X948550Y164417D02*
X950998Y166865D01*
G01X940600Y157400D02*
Y158755D01*
G01Y160755D02*
Y161755D01*
G01X939450Y162232D02*
X947644Y170426D01*
G01X940600Y161755D02*
X941307Y162462D01*
G01X939450Y162232D02*
X947644Y170426D01*
G01X941307Y162462D02*
X942014D01*
G01X939450Y162232D02*
X947644Y170426D01*
G01X942722Y163877D02*
X943429Y164584D01*
G01X939450Y162232D02*
X947644Y170426D01*
G01X943429Y164584D02*
X944136D01*
G01X939450Y162232D02*
X947644Y170426D01*
G01X944844Y165999D02*
X948457Y169612D01*
G01X940600Y157400D02*
Y158755D01*
G01Y160755D02*
Y161755D01*
G01X939450Y162232D02*
X947644Y170426D01*
G01X940600Y161755D02*
X941307Y162462D01*
G01X939450Y162232D02*
X947644Y170426D01*
G01X941307Y162462D02*
X942014D01*
G01X939450Y162232D02*
X947644Y170426D01*
G01X942722Y163877D02*
X943429Y164584D01*
G01X939450Y162232D02*
X947644Y170426D01*
G01X943429Y164584D02*
X944136D01*
G01X939450Y162232D02*
X947644Y170426D01*
G01X944844Y165999D02*
X948457Y169612D01*
G01X946650Y158717D02*
Y159717D01*
G01D02*
X948550Y161617D01*
G01X945500Y160194D02*
X947400Y162094D01*
G01X948550Y161617D02*
Y164417D01*
G01X947400Y162094D02*
Y164894D01*
G01X948550Y164417D02*
X950998Y166865D01*
G01X947400Y164894D02*
X950184Y167678D01*
G01X946650Y158717D02*
Y159717D01*
G01D02*
X948550Y161617D01*
G01X945500Y160194D02*
X947400Y162094D01*
G01X948550Y161617D02*
Y164417D01*
G01X947400Y162094D02*
Y164894D01*
G01X948550Y164417D02*
X950998Y166865D01*
G01X947400Y164894D02*
X950184Y167678D01*
G01X940600Y157400D02*
Y158755D01*
G01Y160755D02*
Y161755D01*
G01D02*
X941307Y162462D01*
G01D02*
X942014D01*
G01X942722Y163877D02*
X943429Y164584D01*
G01D02*
X944136D01*
G01X944844Y165999D02*
X948457Y169612D01*
G01X939450Y162232D02*
X947644Y170426D01*
G01X940600Y157400D02*
Y158755D01*
G01Y160755D02*
Y161755D01*
G01D02*
X941307Y162462D01*
G01D02*
X942014D01*
G01X942722Y163877D02*
X943429Y164584D01*
G01D02*
X944136D01*
G01X944844Y165999D02*
X948457Y169612D01*
G01X939450Y162232D02*
X947644Y170426D01*
G01X946650Y158717D02*
Y159717D01*
G01X945500Y160194D02*
X947400Y162094D01*
G01X946650Y159717D02*
X948550Y161617D01*
G01X947400Y162094D02*
Y164894D01*
G01X948550Y161617D02*
Y164417D01*
G01X947400Y164894D02*
X950184Y167678D01*
G01X948550Y164417D02*
X950998Y166865D01*
G01X915000Y375431D02*
X911020D01*
G01X914980Y374281D02*
X910543D01*
G01X914980D02*
X910543D01*
G01X915000Y375431D02*
X911020D01*
G01X915000D02*
X911020D01*
G01X914980Y374281D02*
X910543D01*
G01X914980D02*
X910543D01*
G01X915000Y375431D02*
X911020D01*
G01X936256Y412549D02*
X935779D01*
G01X935778Y412550D02*
X922799D01*
G01X936255Y413700D02*
X923276D01*
G01X922799Y412550D02*
X921892Y413457D01*
G01X920407Y414942D02*
X919630Y415719D01*
G01X936256Y417409D02*
X926968D01*
G01X936256Y416259D02*
X926491D01*
G01D02*
X925714Y417036D01*
G01X924228Y418522D02*
X923451Y419299D01*
G01X921965Y420785D02*
X921188Y421562D01*
G01X919702Y423048D02*
X918925Y423825D01*
G01X917439Y425311D02*
X916593Y426157D01*
G01X915107Y427643D02*
X914330Y428420D01*
G01X912844Y429906D02*
X912067Y430683D01*
G01X936255Y413700D02*
X923276D01*
G01X936256Y412549D02*
X935779D01*
G01X936255Y413700D02*
X923276D01*
G01X935778Y412550D02*
X922799D01*
G01D02*
X921892Y413457D01*
G01X920407Y414942D02*
X919630Y415719D01*
G01X936256Y416259D02*
X926491D01*
G01X936256Y417409D02*
X926968D01*
G01X926491Y416259D02*
X925714Y417036D01*
G01X924228Y418522D02*
X923451Y419299D01*
G01X921965Y420785D02*
X921188Y421562D01*
G01X919702Y423048D02*
X918925Y423825D01*
G01X917439Y425311D02*
X916593Y426157D01*
G01X915107Y427643D02*
X914330Y428420D01*
G01X912844Y429906D02*
X912067Y430683D01*
G01X936256Y412549D02*
X935779D01*
G01X935778Y412550D02*
X922799D01*
G01X936255Y413700D02*
X923276D01*
G01X922799Y412550D02*
X921892Y413457D01*
G01X920407Y414942D02*
X919630Y415719D01*
G01X936256Y417409D02*
X926968D01*
G01X936256Y416259D02*
X926491D01*
G01D02*
X925714Y417036D01*
G01X924228Y418522D02*
X923451Y419299D01*
G01X921965Y420785D02*
X921188Y421562D01*
G01X919702Y423048D02*
X918925Y423825D01*
G01X917439Y425311D02*
X916593Y426157D01*
G01X915107Y427643D02*
X914330Y428420D01*
G01X912844Y429906D02*
X912067Y430683D01*
G01X936255Y413700D02*
X923276D01*
G01X936256Y412549D02*
X935779D01*
G01X936255Y413700D02*
X923276D01*
G01X935778Y412550D02*
X922799D01*
G01D02*
X921892Y413457D01*
G01X920407Y414942D02*
X919630Y415719D01*
G01X936256Y416259D02*
X926491D01*
G01X936256Y417409D02*
X926968D01*
G01X926491Y416259D02*
X925714Y417036D01*
G01X924228Y418522D02*
X923451Y419299D01*
G01X921965Y420785D02*
X921188Y421562D01*
G01X919702Y423048D02*
X918925Y423825D01*
G01X917439Y425311D02*
X916593Y426157D01*
G01X915107Y427643D02*
X914330Y428420D01*
G01X912844Y429906D02*
X912067Y430683D01*
G01X955800Y426314D02*
X935724Y446390D01*
G01X956577Y427165D02*
X936874Y446868D01*
G01X935724Y446390D02*
Y478550D01*
G01X936874Y446868D02*
Y492848D01*
G01X959267Y430477D02*
X944521Y445223D01*
G01X958454Y429663D02*
X956658Y431459D01*
G01X959267Y430477D02*
X944521Y445223D01*
G01X956658Y431459D02*
X955893D01*
G01X959267Y430477D02*
X944521Y445223D01*
G01X955186Y432931D02*
X954261Y433856D01*
G01X959267Y430477D02*
X944521Y445223D01*
G01X954261Y433856D02*
X953497D01*
G01X959267Y430477D02*
X944521Y445223D01*
G01X952790Y435327D02*
X952083Y436034D01*
G01X959267Y430477D02*
X944521Y445223D01*
G01X952083Y436034D02*
X951319D01*
G01X959267Y430477D02*
X944521Y445223D01*
G01X950612Y437505D02*
X949905Y438212D01*
G01X959267Y430477D02*
X944521Y445223D01*
G01X949905Y438212D02*
X949141D01*
G01X959267Y430477D02*
X944521Y445223D01*
G01X948434Y439683D02*
X947727Y440390D01*
G01X959267Y430477D02*
X944521Y445223D01*
G01X947727Y440390D02*
X946963D01*
G01X959267Y430477D02*
X944521Y445223D01*
G01X946256Y441861D02*
X945549Y442568D01*
G01X959267Y430477D02*
X944521Y445223D01*
G01X945549Y442568D02*
X944785D01*
G01X959267Y430477D02*
X944521Y445223D01*
G01X944078Y444039D02*
X943371Y444746D01*
G01X944521Y445223D02*
Y462060D01*
G01X943371Y444746D02*
Y445677D01*
G01X944521Y445223D02*
Y462060D01*
G01X943371Y447539D02*
Y448615D01*
G01X944521Y445223D02*
Y462060D01*
G01X943371Y450855D02*
Y451855D01*
G01X944521Y445223D02*
Y462060D01*
G01X943371Y454095D02*
Y455095D01*
G01X944521Y445223D02*
Y462060D01*
G01X943371Y457335D02*
Y458335D01*
G01X944521Y445223D02*
Y462060D01*
G01X943371Y460575D02*
Y461583D01*
G01X944521Y462060D02*
X943193Y463388D01*
G01X943371Y461583D02*
X942716Y462238D01*
G01X943193Y463388D02*
X941466D01*
G01X942716Y462238D02*
X940989D01*
G01X941466Y463388D02*
X940758Y464096D01*
G01X940989Y462238D02*
X939608Y463619D01*
G01X940758Y464096D02*
Y465585D01*
G01X939608Y463619D02*
Y466062D01*
G01X956577Y427165D02*
X936874Y446868D01*
G01X955800Y426314D02*
X935724Y446390D01*
G01X936874Y446868D02*
Y492848D01*
G01X935724Y446390D02*
Y478550D01*
G01X936874Y446868D02*
Y492848D01*
G01Y446868D02*
Y492848D01*
G01Y446868D02*
Y492848D01*
G01Y446868D02*
Y492848D01*
G01X958454Y429663D02*
X956658Y431459D01*
G01D02*
X955893D01*
G01X955186Y432931D02*
X954261Y433856D01*
G01D02*
X953497D01*
G01X952790Y435327D02*
X952083Y436034D01*
G01D02*
X951319D01*
G01X950612Y437505D02*
X949905Y438212D01*
G01D02*
X949141D01*
G01X948434Y439683D02*
X947727Y440390D01*
G01D02*
X946963D01*
G01X946256Y441861D02*
X945549Y442568D01*
G01D02*
X944785D01*
G01X944078Y444039D02*
X943371Y444746D01*
G01X959267Y430477D02*
X944521Y445223D01*
G01X943371Y444746D02*
Y445677D01*
G01Y447539D02*
Y448615D01*
G01Y450855D02*
Y451855D01*
G01Y454095D02*
Y455095D01*
G01Y457335D02*
Y458335D01*
G01Y460575D02*
Y461583D01*
G01X944521Y445223D02*
Y462060D01*
G01X943371Y461583D02*
X942716Y462238D01*
G01X944521Y462060D02*
X943193Y463388D01*
G01X942716Y462238D02*
X940989D01*
G01X943193Y463388D02*
X941466D01*
G01X940989Y462238D02*
X939608Y463619D01*
G01X941466Y463388D02*
X940758Y464096D01*
G01X939608Y463619D02*
Y466062D01*
G01X940758Y464096D02*
Y465585D01*
G01X955800Y426314D02*
X935724Y446390D01*
G01X956577Y427165D02*
X936874Y446868D01*
G01X935724Y446390D02*
Y478550D01*
G01X936874Y446868D02*
Y492848D01*
G01X959267Y430477D02*
X944521Y445223D01*
G01X958454Y429663D02*
X956658Y431459D01*
G01X959267Y430477D02*
X944521Y445223D01*
G01X956658Y431459D02*
X955893D01*
G01X959267Y430477D02*
X944521Y445223D01*
G01X955186Y432931D02*
X954261Y433856D01*
G01X959267Y430477D02*
X944521Y445223D01*
G01X954261Y433856D02*
X953497D01*
G01X959267Y430477D02*
X944521Y445223D01*
G01X952790Y435327D02*
X952083Y436034D01*
G01X959267Y430477D02*
X944521Y445223D01*
G01X952083Y436034D02*
X951319D01*
G01X959267Y430477D02*
X944521Y445223D01*
G01X950612Y437505D02*
X949905Y438212D01*
G01X959267Y430477D02*
X944521Y445223D01*
G01X949905Y438212D02*
X949141D01*
G01X959267Y430477D02*
X944521Y445223D01*
G01X948434Y439683D02*
X947727Y440390D01*
G01X959267Y430477D02*
X944521Y445223D01*
G01X947727Y440390D02*
X946963D01*
G01X959267Y430477D02*
X944521Y445223D01*
G01X946256Y441861D02*
X945549Y442568D01*
G01X959267Y430477D02*
X944521Y445223D01*
G01X945549Y442568D02*
X944785D01*
G01X959267Y430477D02*
X944521Y445223D01*
G01X944078Y444039D02*
X943371Y444746D01*
G01X944521Y445223D02*
Y462060D01*
G01X943371Y444746D02*
Y445677D01*
G01X944521Y445223D02*
Y462060D01*
G01X943371Y447539D02*
Y448615D01*
G01X944521Y445223D02*
Y462060D01*
G01X943371Y450855D02*
Y451855D01*
G01X944521Y445223D02*
Y462060D01*
G01X943371Y454095D02*
Y455095D01*
G01X944521Y445223D02*
Y462060D01*
G01X943371Y457335D02*
Y458335D01*
G01X944521Y445223D02*
Y462060D01*
G01X943371Y460575D02*
Y461583D01*
G01X944521Y462060D02*
X943193Y463388D01*
G01X943371Y461583D02*
X942716Y462238D01*
G01X943193Y463388D02*
X941466D01*
G01X942716Y462238D02*
X940989D01*
G01X941466Y463388D02*
X940758Y464096D01*
G01X940989Y462238D02*
X939608Y463619D01*
G01X940758Y464096D02*
Y465585D01*
G01X939608Y463619D02*
Y466062D01*
G01X956577Y427165D02*
X936874Y446868D01*
G01X955800Y426314D02*
X935724Y446390D01*
G01X936874Y446868D02*
Y492848D01*
G01X935724Y446390D02*
Y478550D01*
G01X936874Y446868D02*
Y492848D01*
G01Y446868D02*
Y492848D01*
G01Y446868D02*
Y492848D01*
G01Y446868D02*
Y492848D01*
G01X958454Y429663D02*
X956658Y431459D01*
G01D02*
X955893D01*
G01X955186Y432931D02*
X954261Y433856D01*
G01D02*
X953497D01*
G01X952790Y435327D02*
X952083Y436034D01*
G01D02*
X951319D01*
G01X950612Y437505D02*
X949905Y438212D01*
G01D02*
X949141D01*
G01X948434Y439683D02*
X947727Y440390D01*
G01D02*
X946963D01*
G01X946256Y441861D02*
X945549Y442568D01*
G01D02*
X944785D01*
G01X944078Y444039D02*
X943371Y444746D01*
G01X959267Y430477D02*
X944521Y445223D01*
G01X943371Y444746D02*
Y445677D01*
G01Y447539D02*
Y448615D01*
G01Y450855D02*
Y451855D01*
G01Y454095D02*
Y455095D01*
G01Y457335D02*
Y458335D01*
G01Y460575D02*
Y461583D01*
G01X944521Y445223D02*
Y462060D01*
G01X943371Y461583D02*
X942716Y462238D01*
G01X944521Y462060D02*
X943193Y463388D01*
G01X942716Y462238D02*
X940989D01*
G01X943193Y463388D02*
X941466D01*
G01X940989Y462238D02*
X939608Y463619D01*
G01X941466Y463388D02*
X940758Y464096D01*
G01X939608Y463619D02*
Y466062D01*
G01X940758Y464096D02*
Y465585D01*
G01X935724Y480450D02*
Y481500D01*
G01Y483500D02*
Y484500D01*
G01Y486500D02*
Y487460D01*
G01Y489500D02*
Y492370D01*
G01D02*
X934719Y493375D01*
G01X936874Y492848D02*
X933778Y495944D01*
G01X940758Y465585D02*
X941452Y466279D01*
G01X939608Y466062D02*
X940975Y467429D01*
G01X941452Y466279D02*
X943277D01*
G01X940975Y467429D02*
X942800D01*
G01X943277Y466279D02*
X944600Y467602D01*
G01X942800Y467429D02*
X943450Y468079D01*
G01X944600Y467602D02*
Y469856D01*
G01X943450Y468079D02*
Y469379D01*
G01X944600Y469856D02*
X943277Y471179D01*
G01X943450Y469379D02*
X942800Y470029D01*
G01X943277Y471179D02*
X941339D01*
G01X942800Y470029D02*
X940862D01*
G01X941339Y471179D02*
X940689Y471829D01*
G01X940862Y470029D02*
X939539Y471352D01*
G01X940689Y471829D02*
Y473129D01*
G01X939539Y471352D02*
Y473606D01*
G01X940689Y473129D02*
X941874Y474314D01*
G01X939539Y473606D02*
X940724Y474791D01*
G01X941874Y474314D02*
Y492802D01*
G01X940724Y474791D02*
Y478361D01*
G01X941874Y474314D02*
Y492802D01*
G01X940724Y480333D02*
Y481400D01*
G01X941874Y474314D02*
Y492802D01*
G01X940724Y483400D02*
Y484400D01*
G01X941874Y474314D02*
Y492802D01*
G01X940724Y486400D02*
Y487400D01*
G01X941874Y474314D02*
Y492802D01*
G01X940724Y489400D02*
Y492325D01*
G01X941874Y492802D02*
X938732Y495944D01*
G01X940724Y492325D02*
X939705Y493344D01*
G01X941874Y492802D02*
X938732Y495944D01*
G01X939705Y493344D02*
X938732D01*
G01X935724Y480450D02*
Y481500D01*
G01Y483500D02*
Y484500D01*
G01Y486500D02*
Y487460D01*
G01Y489500D02*
Y492370D01*
G01X936874Y492848D02*
X933778Y495944D01*
G01X935724Y492370D02*
X934719Y493375D01*
G01X939608Y466062D02*
X940975Y467429D01*
G01X940758Y465585D02*
X941452Y466279D01*
G01X940975Y467429D02*
X942800D01*
G01X941452Y466279D02*
X943277D01*
G01X942800Y467429D02*
X943450Y468079D01*
G01X943277Y466279D02*
X944600Y467602D01*
G01X943450Y468079D02*
Y469379D01*
G01X944600Y467602D02*
Y469856D01*
G01X943450Y469379D02*
X942800Y470029D01*
G01X944600Y469856D02*
X943277Y471179D01*
G01X942800Y470029D02*
X940862D01*
G01X943277Y471179D02*
X941339D01*
G01X940862Y470029D02*
X939539Y471352D01*
G01X941339Y471179D02*
X940689Y471829D01*
G01X939539Y471352D02*
Y473606D01*
G01X940689Y471829D02*
Y473129D01*
G01X939539Y473606D02*
X940724Y474791D01*
G01X940689Y473129D02*
X941874Y474314D01*
G01X940724Y474791D02*
Y478361D01*
G01Y480333D02*
Y481400D01*
G01Y483400D02*
Y484400D01*
G01Y486400D02*
Y487400D01*
G01Y489400D02*
Y492325D01*
G01X941874Y474314D02*
Y492802D01*
G01X940724Y492325D02*
X939705Y493344D01*
G01D02*
X938732D01*
G01X941874Y492802D02*
X938732Y495944D01*
G01X935724Y480450D02*
Y481500D01*
G01Y483500D02*
Y484500D01*
G01Y486500D02*
Y487460D01*
G01Y489500D02*
Y492370D01*
G01D02*
X934719Y493375D01*
G01X936874Y492848D02*
X933778Y495944D01*
G01X940758Y465585D02*
X941452Y466279D01*
G01X939608Y466062D02*
X940975Y467429D01*
G01X941452Y466279D02*
X943277D01*
G01X940975Y467429D02*
X942800D01*
G01X943277Y466279D02*
X944600Y467602D01*
G01X942800Y467429D02*
X943450Y468079D01*
G01X944600Y467602D02*
Y469856D01*
G01X943450Y468079D02*
Y469379D01*
G01X944600Y469856D02*
X943277Y471179D01*
G01X943450Y469379D02*
X942800Y470029D01*
G01X943277Y471179D02*
X941339D01*
G01X942800Y470029D02*
X940862D01*
G01X941339Y471179D02*
X940689Y471829D01*
G01X940862Y470029D02*
X939539Y471352D01*
G01X940689Y471829D02*
Y473129D01*
G01X939539Y471352D02*
Y473606D01*
G01X940689Y473129D02*
X941874Y474314D01*
G01X939539Y473606D02*
X940724Y474791D01*
G01X941874Y474314D02*
Y492802D01*
G01X940724Y474791D02*
Y478361D01*
G01X941874Y474314D02*
Y492802D01*
G01X940724Y480333D02*
Y481400D01*
G01X941874Y474314D02*
Y492802D01*
G01X940724Y483400D02*
Y484400D01*
G01X941874Y474314D02*
Y492802D01*
G01X940724Y486400D02*
Y487400D01*
G01X941874Y474314D02*
Y492802D01*
G01X940724Y489400D02*
Y492325D01*
G01X941874Y492802D02*
X938732Y495944D01*
G01X940724Y492325D02*
X939705Y493344D01*
G01X941874Y492802D02*
X938732Y495944D01*
G01X939705Y493344D02*
X938732D01*
G01X935724Y480450D02*
Y481500D01*
G01Y483500D02*
Y484500D01*
G01Y486500D02*
Y487460D01*
G01Y489500D02*
Y492370D01*
G01X936874Y492848D02*
X933778Y495944D01*
G01X935724Y492370D02*
X934719Y493375D01*
G01X939608Y466062D02*
X940975Y467429D01*
G01X940758Y465585D02*
X941452Y466279D01*
G01X940975Y467429D02*
X942800D01*
G01X941452Y466279D02*
X943277D01*
G01X942800Y467429D02*
X943450Y468079D01*
G01X943277Y466279D02*
X944600Y467602D01*
G01X943450Y468079D02*
Y469379D01*
G01X944600Y467602D02*
Y469856D01*
G01X943450Y469379D02*
X942800Y470029D01*
G01X944600Y469856D02*
X943277Y471179D01*
G01X942800Y470029D02*
X940862D01*
G01X943277Y471179D02*
X941339D01*
G01X940862Y470029D02*
X939539Y471352D01*
G01X941339Y471179D02*
X940689Y471829D01*
G01X939539Y471352D02*
Y473606D01*
G01X940689Y471829D02*
Y473129D01*
G01X939539Y473606D02*
X940724Y474791D01*
G01X940689Y473129D02*
X941874Y474314D01*
G01X940724Y474791D02*
Y478361D01*
G01Y480333D02*
Y481400D01*
G01Y483400D02*
Y484400D01*
G01Y486400D02*
Y487400D01*
G01Y489400D02*
Y492325D01*
G01X941874Y474314D02*
Y492802D01*
G01X940724Y492325D02*
X939705Y493344D01*
G01D02*
X938732D01*
G01X941874Y492802D02*
X938732Y495944D01*
G01X1025798Y90064D02*
Y95341D01*
G01X1026948Y99545D02*
Y90293D01*
G01X1027270Y86510D02*
X1026957Y87266D01*
G01D02*
X1025798Y90064D01*
G01X1026948Y90293D02*
X1028202Y87266D01*
G01X1027270Y86510D02*
X1026957Y87266D01*
G01X1028202D02*
X1028420Y86739D01*
G01X1027270Y76579D02*
Y78869D01*
G01Y81779D02*
Y86510D01*
G01X1028420Y86739D02*
Y76350D01*
G01X1025952Y73397D02*
X1027270Y76579D01*
G01X1028420Y76350D02*
X1026928Y72745D01*
G01X1024908Y72353D02*
X1025952Y73397D01*
G01X1026928Y72745D02*
X1025560Y71377D01*
G01X1019588Y70150D02*
X1024908Y72353D01*
G01X1025560Y71377D02*
X1019817Y69000D01*
G01X1015705Y70150D02*
X1019588D01*
G01X1019817Y69000D02*
X1015934D01*
G01X1013300Y69154D02*
X1015705Y70150D01*
G01X1015934Y69000D02*
X1013952Y68178D01*
G01X1011924Y67778D02*
X1013300Y69154D01*
G01X1013952Y68178D02*
X1013074Y67301D01*
G01X1011924Y66325D02*
Y67778D01*
G01X1013074Y67301D02*
Y66226D01*
G01X1012794Y92894D02*
Y96460D01*
G01X1013944Y93771D02*
Y109095D01*
G01X1011924Y82509D02*
Y83827D01*
G01X1013074Y82259D02*
Y83350D01*
G01X1011924Y83827D02*
X1013247Y85150D01*
G01X1013074Y83350D02*
X1013724Y84000D01*
G01X1013247Y85150D02*
X1020023D01*
G01X1013724Y84000D02*
X1020500D01*
G01X1020023Y85150D02*
X1021025Y86152D01*
G01X1020500Y84000D02*
X1022175Y85675D01*
G01X1021025Y86152D02*
Y88853D01*
G01X1022175Y85675D02*
Y88376D01*
G01X1021025Y88853D02*
X1022833Y90661D01*
G01X1022175Y88376D02*
X1023983Y90184D01*
G01X1022833Y90661D02*
Y93826D01*
G01X1023983Y90184D02*
Y94303D01*
G01X1022833Y93826D02*
X1022242Y94417D01*
G01X1023983Y94303D02*
X1022719Y95567D01*
G01X1022242Y94417D02*
X1017316D01*
G01D02*
X1015993Y95740D01*
G01X1012871Y88328D02*
Y88852D01*
G01X1014021Y88321D02*
Y89329D01*
G01X1012871Y88852D02*
X1012286Y89437D01*
G01X1014021Y89329D02*
X1012763Y90587D01*
G01X1012286Y89437D02*
X1010648D01*
G01X1012763Y90587D02*
X1011125D01*
G01X1010648Y89437D02*
X1009475Y90610D01*
G01X1011125Y90587D02*
X1010625Y91087D01*
G01X1009475Y90610D02*
Y94478D01*
G01X1010625Y91087D02*
Y94955D01*
G01X1009475Y94478D02*
X1009075Y94878D01*
G01X1013074Y67301D02*
Y66226D01*
G01X1011924Y66325D02*
Y67778D01*
G01X1013952Y68178D02*
X1013074Y67301D01*
G01X1011924Y67778D02*
X1013300Y69154D01*
G01X1015934Y69000D02*
X1013952Y68178D01*
G01X1013300Y69154D02*
X1015705Y70150D01*
G01X1019817Y69000D02*
X1015934D01*
G01X1015705Y70150D02*
X1019588D01*
G01X1025560Y71377D02*
X1019817Y69000D01*
G01X1019588Y70150D02*
X1024908Y72353D01*
G01X1026928Y72745D02*
X1025560Y71377D01*
G01X1024908Y72353D02*
X1025952Y73397D01*
G01X1028420Y76350D02*
X1026928Y72745D01*
G01X1025952Y73397D02*
X1027270Y76579D01*
G01X1028420Y86739D02*
Y76350D01*
G01X1027270Y76579D02*
Y78869D01*
G01X1028420Y86739D02*
Y76350D01*
G01X1027270Y81779D02*
Y86510D01*
G01X1026948Y90293D02*
X1028202Y87266D01*
G01D02*
X1028420Y86739D01*
G01X1027270Y86510D02*
X1026957Y87266D01*
G01X1026948Y90293D02*
X1028202Y87266D01*
G01X1026957D02*
X1025798Y90064D01*
G01X1026948Y99545D02*
Y90293D01*
G01X1025798Y90064D02*
Y95341D01*
G01X1026948Y99545D02*
Y90293D01*
G01X1013944Y93771D02*
Y109095D01*
G01Y93771D02*
Y109095D01*
G01X1012794Y92894D02*
Y96460D01*
G01X1013944Y93771D02*
Y109095D01*
G01Y93771D02*
Y109095D01*
G01X1013074Y82259D02*
Y83350D01*
G01X1011924Y82509D02*
Y83827D01*
G01X1013074Y83350D02*
X1013724Y84000D01*
G01X1011924Y83827D02*
X1013247Y85150D01*
G01X1013724Y84000D02*
X1020500D01*
G01X1013247Y85150D02*
X1020023D01*
G01X1020500Y84000D02*
X1022175Y85675D01*
G01X1020023Y85150D02*
X1021025Y86152D01*
G01X1022175Y85675D02*
Y88376D01*
G01X1021025Y86152D02*
Y88853D01*
G01X1022175Y88376D02*
X1023983Y90184D01*
G01X1021025Y88853D02*
X1022833Y90661D01*
G01X1023983Y90184D02*
Y94303D01*
G01X1022833Y90661D02*
Y93826D01*
G01X1023983Y94303D02*
X1022719Y95567D01*
G01X1022833Y93826D02*
X1022242Y94417D01*
G01D02*
X1017316D01*
G01D02*
X1015993Y95740D01*
G01X1014021Y88321D02*
Y89329D01*
G01X1012871Y88328D02*
Y88852D01*
G01X1014021Y89329D02*
X1012763Y90587D01*
G01X1012871Y88852D02*
X1012286Y89437D01*
G01X1012763Y90587D02*
X1011125D01*
G01X1012286Y89437D02*
X1010648D01*
G01X1011125Y90587D02*
X1010625Y91087D01*
G01X1010648Y89437D02*
X1009475Y90610D01*
G01X1010625Y91087D02*
Y94955D01*
G01X1009475Y90610D02*
Y94478D01*
G01D02*
X1009075Y94878D01*
G01X1025798Y90064D02*
Y95341D01*
G01X1026948Y99545D02*
Y90293D01*
G01X1027270Y86510D02*
X1026957Y87266D01*
G01D02*
X1025798Y90064D01*
G01X1026948Y90293D02*
X1028202Y87266D01*
G01X1027270Y86510D02*
X1026957Y87266D01*
G01X1028202D02*
X1028420Y86739D01*
G01X1027270Y76579D02*
Y78869D01*
G01Y81779D02*
Y86510D01*
G01X1028420Y86739D02*
Y76350D01*
G01X1025952Y73397D02*
X1027270Y76579D01*
G01X1028420Y76350D02*
X1026928Y72745D01*
G01X1024908Y72353D02*
X1025952Y73397D01*
G01X1026928Y72745D02*
X1025560Y71377D01*
G01X1019588Y70150D02*
X1024908Y72353D01*
G01X1025560Y71377D02*
X1019817Y69000D01*
G01X1015705Y70150D02*
X1019588D01*
G01X1019817Y69000D02*
X1015934D01*
G01X1013300Y69154D02*
X1015705Y70150D01*
G01X1015934Y69000D02*
X1013952Y68178D01*
G01X1011924Y67778D02*
X1013300Y69154D01*
G01X1013952Y68178D02*
X1013074Y67301D01*
G01X1011924Y66325D02*
Y67778D01*
G01X1013074Y67301D02*
Y66226D01*
G01X1012794Y92894D02*
Y96460D01*
G01X1013944Y93771D02*
Y109095D01*
G01X1011924Y82509D02*
Y83827D01*
G01X1013074Y82259D02*
Y83350D01*
G01X1011924Y83827D02*
X1013247Y85150D01*
G01X1013074Y83350D02*
X1013724Y84000D01*
G01X1013247Y85150D02*
X1020023D01*
G01X1013724Y84000D02*
X1020500D01*
G01X1020023Y85150D02*
X1021025Y86152D01*
G01X1020500Y84000D02*
X1022175Y85675D01*
G01X1021025Y86152D02*
Y88853D01*
G01X1022175Y85675D02*
Y88376D01*
G01X1021025Y88853D02*
X1022833Y90661D01*
G01X1022175Y88376D02*
X1023983Y90184D01*
G01X1022833Y90661D02*
Y93826D01*
G01X1023983Y90184D02*
Y94303D01*
G01X1022833Y93826D02*
X1022242Y94417D01*
G01X1023983Y94303D02*
X1022719Y95567D01*
G01X1022242Y94417D02*
X1017316D01*
G01D02*
X1015993Y95740D01*
G01X1012871Y88328D02*
Y88852D01*
G01X1014021Y88321D02*
Y89329D01*
G01X1012871Y88852D02*
X1012286Y89437D01*
G01X1014021Y89329D02*
X1012763Y90587D01*
G01X1012286Y89437D02*
X1010648D01*
G01X1012763Y90587D02*
X1011125D01*
G01X1010648Y89437D02*
X1009475Y90610D01*
G01X1011125Y90587D02*
X1010625Y91087D01*
G01X1009475Y90610D02*
Y94478D01*
G01X1010625Y91087D02*
Y94955D01*
G01X1009475Y94478D02*
X1009075Y94878D01*
G01X1013074Y67301D02*
Y66226D01*
G01X1011924Y66325D02*
Y67778D01*
G01X1013952Y68178D02*
X1013074Y67301D01*
G01X1011924Y67778D02*
X1013300Y69154D01*
G01X1015934Y69000D02*
X1013952Y68178D01*
G01X1013300Y69154D02*
X1015705Y70150D01*
G01X1019817Y69000D02*
X1015934D01*
G01X1015705Y70150D02*
X1019588D01*
G01X1025560Y71377D02*
X1019817Y69000D01*
G01X1019588Y70150D02*
X1024908Y72353D01*
G01X1026928Y72745D02*
X1025560Y71377D01*
G01X1024908Y72353D02*
X1025952Y73397D01*
G01X1028420Y76350D02*
X1026928Y72745D01*
G01X1025952Y73397D02*
X1027270Y76579D01*
G01X1028420Y86739D02*
Y76350D01*
G01X1027270Y76579D02*
Y78869D01*
G01X1028420Y86739D02*
Y76350D01*
G01X1027270Y81779D02*
Y86510D01*
G01X1026948Y90293D02*
X1028202Y87266D01*
G01D02*
X1028420Y86739D01*
G01X1027270Y86510D02*
X1026957Y87266D01*
G01X1026948Y90293D02*
X1028202Y87266D01*
G01X1026957D02*
X1025798Y90064D01*
G01X1026948Y99545D02*
Y90293D01*
G01X1025798Y90064D02*
Y95341D01*
G01X1026948Y99545D02*
Y90293D01*
G01X1013944Y93771D02*
Y109095D01*
G01Y93771D02*
Y109095D01*
G01X1012794Y92894D02*
Y96460D01*
G01X1013944Y93771D02*
Y109095D01*
G01Y93771D02*
Y109095D01*
G01X1013074Y82259D02*
Y83350D01*
G01X1011924Y82509D02*
Y83827D01*
G01X1013074Y83350D02*
X1013724Y84000D01*
G01X1011924Y83827D02*
X1013247Y85150D01*
G01X1013724Y84000D02*
X1020500D01*
G01X1013247Y85150D02*
X1020023D01*
G01X1020500Y84000D02*
X1022175Y85675D01*
G01X1020023Y85150D02*
X1021025Y86152D01*
G01X1022175Y85675D02*
Y88376D01*
G01X1021025Y86152D02*
Y88853D01*
G01X1022175Y88376D02*
X1023983Y90184D01*
G01X1021025Y88853D02*
X1022833Y90661D01*
G01X1023983Y90184D02*
Y94303D01*
G01X1022833Y90661D02*
Y93826D01*
G01X1023983Y94303D02*
X1022719Y95567D01*
G01X1022833Y93826D02*
X1022242Y94417D01*
G01D02*
X1017316D01*
G01D02*
X1015993Y95740D01*
G01X1014021Y88321D02*
Y89329D01*
G01X1012871Y88328D02*
Y88852D01*
G01X1014021Y89329D02*
X1012763Y90587D01*
G01X1012871Y88852D02*
X1012286Y89437D01*
G01X1012763Y90587D02*
X1011125D01*
G01X1012286Y89437D02*
X1010648D01*
G01X1011125Y90587D02*
X1010625Y91087D01*
G01X1010648Y89437D02*
X1009475Y90610D01*
G01X1010625Y91087D02*
Y94955D01*
G01X1009475Y90610D02*
Y94478D01*
G01D02*
X1009075Y94878D01*
G01X1026880Y108017D02*
Y181268D01*
G01X1028030Y115156D02*
Y181266D01*
G01X1026880Y103936D02*
Y105839D01*
G01Y101104D02*
Y103936D01*
G01X1028030Y115156D02*
Y100627D01*
G01X1025798Y100022D02*
X1026880Y101104D01*
G01X1028030Y100627D02*
X1026948Y99545D01*
G01X1025798Y98179D02*
Y100022D01*
G01X1018431Y115902D02*
X1019124D01*
G01D02*
X1020610Y117388D01*
G01X1019801Y114952D02*
X1021760Y116911D01*
G01X1020610Y117388D02*
Y182686D01*
G01X1021760Y116911D02*
Y182706D01*
G01X1012794Y108014D02*
Y109572D01*
G01Y98838D02*
Y100263D01*
G01Y102731D02*
Y108014D01*
G01Y109572D02*
X1017255Y114033D01*
G01X1013944Y109095D02*
X1019801Y114952D01*
G01X1023745Y109665D02*
Y183105D01*
G01X1024895D02*
Y111035D01*
G01X1022719Y95567D02*
X1017793D01*
G01D02*
X1017143Y96217D01*
G01X1015993Y95740D02*
Y100002D01*
G01X1017143Y96217D02*
Y99525D01*
G01X1015993Y100002D02*
X1017316Y101325D01*
G01X1017143Y99525D02*
X1017793Y100175D01*
G01X1017316Y101325D02*
X1019900D01*
G01X1017793Y100175D02*
X1019423D01*
G01X1019900Y101325D02*
X1020325Y100900D01*
G01X1019423Y100175D02*
X1019848Y99750D01*
G01X1020325Y100900D02*
X1022208D01*
G01X1019848Y99750D02*
X1022685D01*
G01X1022208Y100900D02*
X1023745Y102437D01*
G01X1022685Y99750D02*
X1024895Y101960D01*
G01X1023745Y102437D02*
Y103415D01*
G01X1024895Y101960D02*
Y103892D01*
G01X1023745Y103415D02*
X1023095Y104065D01*
G01X1024895Y103892D02*
X1023572Y105215D01*
G01X1019589Y104065D02*
X1017252D01*
G01X1023095D02*
X1019589D01*
G01X1023572Y105215D02*
X1017729D01*
G01X1017252Y104065D02*
X1015929Y105388D01*
G01X1017729Y105215D02*
X1017079Y105865D01*
G01X1015929Y105388D02*
Y107692D01*
G01X1017079Y105865D02*
Y107215D01*
G01X1015929Y107692D02*
X1017252Y109015D01*
G01X1017079Y107215D02*
X1017729Y107865D01*
G01X1017252Y109015D02*
X1023095D01*
G01X1017729Y107865D02*
X1023572D01*
G01X1023095Y109015D02*
X1023745Y109665D01*
G01X1023572Y107865D02*
X1024895Y109188D01*
G01X1023745Y109665D02*
Y183105D01*
G01X1024895Y109188D02*
Y111035D01*
G01X1009075Y94878D02*
Y111477D01*
G01X1010225Y103689D02*
Y111000D01*
G01X1011411Y113813D02*
X1017475Y119877D01*
G01X1009075Y111477D02*
X1011411Y113813D01*
G01X1010225Y111000D02*
X1018625Y119400D01*
G01X1017475Y119877D02*
Y184533D01*
G01X1018625Y119400D02*
Y184533D01*
G01X1010625Y94955D02*
X1010225Y95355D01*
G01X1009075Y94878D02*
Y111477D01*
G01X1010225Y95355D02*
Y103689D01*
G01X1028030Y115156D02*
Y100627D01*
G01X1026880Y103936D02*
Y105839D01*
G01X1028030Y115156D02*
Y181266D01*
G01X1026880Y108017D02*
Y181268D01*
G01X1025798Y98179D02*
Y100022D01*
G01X1028030Y100627D02*
X1026948Y99545D01*
G01X1025798Y100022D02*
X1026880Y101104D01*
G01X1028030Y115156D02*
Y100627D01*
G01X1026880Y101104D02*
Y103936D01*
G01X1012794Y108014D02*
Y109572D01*
G01X1013944Y109095D02*
X1019801Y114952D01*
G01X1012794Y109572D02*
X1017255Y114033D01*
G01X1019801Y114952D02*
X1021760Y116911D01*
G01X1018431Y115902D02*
X1019124D01*
G01X1019801Y114952D02*
X1021760Y116911D01*
G01X1019124Y115902D02*
X1020610Y117388D01*
G01X1021760Y116911D02*
Y182706D01*
G01X1020610Y117388D02*
Y182686D01*
G01X1012794Y98838D02*
Y100263D01*
G01Y102731D02*
Y108014D01*
G01X1023572Y105215D02*
X1017729D01*
G01X1019589Y104065D02*
X1017252D01*
G01X1017729Y105215D02*
X1017079Y105865D01*
G01X1017252Y104065D02*
X1015929Y105388D01*
G01X1017079Y105865D02*
Y107215D01*
G01X1015929Y105388D02*
Y107692D01*
G01X1017079Y107215D02*
X1017729Y107865D01*
G01X1015929Y107692D02*
X1017252Y109015D01*
G01X1017729Y107865D02*
X1023572D01*
G01X1017252Y109015D02*
X1023095D01*
G01X1023572Y107865D02*
X1024895Y109188D01*
G01X1023095Y109015D02*
X1023745Y109665D01*
G01X1024895Y183105D02*
Y111035D01*
G01Y109188D02*
Y111035D01*
G01X1023745Y109665D02*
Y183105D01*
G01X1022719Y95567D02*
X1017793D01*
G01D02*
X1017143Y96217D01*
G01D02*
Y99525D01*
G01X1015993Y95740D02*
Y100002D01*
G01X1017143Y99525D02*
X1017793Y100175D01*
G01X1015993Y100002D02*
X1017316Y101325D01*
G01X1017793Y100175D02*
X1019423D01*
G01X1017316Y101325D02*
X1019900D01*
G01X1019423Y100175D02*
X1019848Y99750D01*
G01X1019900Y101325D02*
X1020325Y100900D01*
G01X1019848Y99750D02*
X1022685D01*
G01X1020325Y100900D02*
X1022208D01*
G01X1022685Y99750D02*
X1024895Y101960D01*
G01X1022208Y100900D02*
X1023745Y102437D01*
G01X1024895Y101960D02*
Y103892D01*
G01X1023745Y102437D02*
Y103415D01*
G01X1024895Y103892D02*
X1023572Y105215D01*
G01X1023745Y103415D02*
X1023095Y104065D01*
G01X1023572Y105215D02*
X1017729D01*
G01X1023095Y104065D02*
X1019589D01*
G01X1010225Y111000D02*
X1018625Y119400D01*
G01X1011411Y113813D02*
X1017475Y119877D01*
G01X1018625Y119400D02*
Y184533D01*
G01X1017475Y119877D02*
Y184533D01*
G01X1010625Y94955D02*
X1010225Y95355D01*
G01Y103689D02*
Y111000D01*
G01Y95355D02*
Y103689D01*
G01X1009075Y94878D02*
Y111477D01*
G01X1010225Y111000D02*
X1018625Y119400D01*
G01X1009075Y111477D02*
X1011411Y113813D01*
G01X1026880Y108017D02*
Y181268D01*
G01X1028030Y115156D02*
Y181266D01*
G01X1026880Y103936D02*
Y105839D01*
G01Y101104D02*
Y103936D01*
G01X1028030Y115156D02*
Y100627D01*
G01X1025798Y100022D02*
X1026880Y101104D01*
G01X1028030Y100627D02*
X1026948Y99545D01*
G01X1025798Y98179D02*
Y100022D01*
G01X1018431Y115902D02*
X1019124D01*
G01D02*
X1020610Y117388D01*
G01X1019801Y114952D02*
X1021760Y116911D01*
G01X1020610Y117388D02*
Y182686D01*
G01X1021760Y116911D02*
Y182706D01*
G01X1012794Y108014D02*
Y109572D01*
G01Y98838D02*
Y100263D01*
G01Y102731D02*
Y108014D01*
G01Y109572D02*
X1017255Y114033D01*
G01X1013944Y109095D02*
X1019801Y114952D01*
G01X1023745Y109665D02*
Y183105D01*
G01X1024895D02*
Y111035D01*
G01X1022719Y95567D02*
X1017793D01*
G01D02*
X1017143Y96217D01*
G01X1015993Y95740D02*
Y100002D01*
G01X1017143Y96217D02*
Y99525D01*
G01X1015993Y100002D02*
X1017316Y101325D01*
G01X1017143Y99525D02*
X1017793Y100175D01*
G01X1017316Y101325D02*
X1019900D01*
G01X1017793Y100175D02*
X1019423D01*
G01X1019900Y101325D02*
X1020325Y100900D01*
G01X1019423Y100175D02*
X1019848Y99750D01*
G01X1020325Y100900D02*
X1022208D01*
G01X1019848Y99750D02*
X1022685D01*
G01X1022208Y100900D02*
X1023745Y102437D01*
G01X1022685Y99750D02*
X1024895Y101960D01*
G01X1023745Y102437D02*
Y103415D01*
G01X1024895Y101960D02*
Y103892D01*
G01X1023745Y103415D02*
X1023095Y104065D01*
G01X1024895Y103892D02*
X1023572Y105215D01*
G01X1019589Y104065D02*
X1017252D01*
G01X1023095D02*
X1019589D01*
G01X1023572Y105215D02*
X1017729D01*
G01X1017252Y104065D02*
X1015929Y105388D01*
G01X1017729Y105215D02*
X1017079Y105865D01*
G01X1015929Y105388D02*
Y107692D01*
G01X1017079Y105865D02*
Y107215D01*
G01X1015929Y107692D02*
X1017252Y109015D01*
G01X1017079Y107215D02*
X1017729Y107865D01*
G01X1017252Y109015D02*
X1023095D01*
G01X1017729Y107865D02*
X1023572D01*
G01X1023095Y109015D02*
X1023745Y109665D01*
G01X1023572Y107865D02*
X1024895Y109188D01*
G01X1023745Y109665D02*
Y183105D01*
G01X1024895Y109188D02*
Y111035D01*
G01X1009075Y94878D02*
Y111477D01*
G01X1010225Y103689D02*
Y111000D01*
G01X1011411Y113813D02*
X1017475Y119877D01*
G01X1009075Y111477D02*
X1011411Y113813D01*
G01X1010225Y111000D02*
X1018625Y119400D01*
G01X1017475Y119877D02*
Y184533D01*
G01X1018625Y119400D02*
Y184533D01*
G01X1010625Y94955D02*
X1010225Y95355D01*
G01X1009075Y94878D02*
Y111477D01*
G01X1010225Y95355D02*
Y103689D01*
G01X1028030Y115156D02*
Y100627D01*
G01X1026880Y103936D02*
Y105839D01*
G01X1028030Y115156D02*
Y181266D01*
G01X1026880Y108017D02*
Y181268D01*
G01X1025798Y98179D02*
Y100022D01*
G01X1028030Y100627D02*
X1026948Y99545D01*
G01X1025798Y100022D02*
X1026880Y101104D01*
G01X1028030Y115156D02*
Y100627D01*
G01X1026880Y101104D02*
Y103936D01*
G01X1012794Y108014D02*
Y109572D01*
G01X1013944Y109095D02*
X1019801Y114952D01*
G01X1012794Y109572D02*
X1017255Y114033D01*
G01X1019801Y114952D02*
X1021760Y116911D01*
G01X1018431Y115902D02*
X1019124D01*
G01X1019801Y114952D02*
X1021760Y116911D01*
G01X1019124Y115902D02*
X1020610Y117388D01*
G01X1021760Y116911D02*
Y182706D01*
G01X1020610Y117388D02*
Y182686D01*
G01X1012794Y98838D02*
Y100263D01*
G01Y102731D02*
Y108014D01*
G01X1023572Y105215D02*
X1017729D01*
G01X1019589Y104065D02*
X1017252D01*
G01X1017729Y105215D02*
X1017079Y105865D01*
G01X1017252Y104065D02*
X1015929Y105388D01*
G01X1017079Y105865D02*
Y107215D01*
G01X1015929Y105388D02*
Y107692D01*
G01X1017079Y107215D02*
X1017729Y107865D01*
G01X1015929Y107692D02*
X1017252Y109015D01*
G01X1017729Y107865D02*
X1023572D01*
G01X1017252Y109015D02*
X1023095D01*
G01X1023572Y107865D02*
X1024895Y109188D01*
G01X1023095Y109015D02*
X1023745Y109665D01*
G01X1024895Y183105D02*
Y111035D01*
G01Y109188D02*
Y111035D01*
G01X1023745Y109665D02*
Y183105D01*
G01X1022719Y95567D02*
X1017793D01*
G01D02*
X1017143Y96217D01*
G01D02*
Y99525D01*
G01X1015993Y95740D02*
Y100002D01*
G01X1017143Y99525D02*
X1017793Y100175D01*
G01X1015993Y100002D02*
X1017316Y101325D01*
G01X1017793Y100175D02*
X1019423D01*
G01X1017316Y101325D02*
X1019900D01*
G01X1019423Y100175D02*
X1019848Y99750D01*
G01X1019900Y101325D02*
X1020325Y100900D01*
G01X1019848Y99750D02*
X1022685D01*
G01X1020325Y100900D02*
X1022208D01*
G01X1022685Y99750D02*
X1024895Y101960D01*
G01X1022208Y100900D02*
X1023745Y102437D01*
G01X1024895Y101960D02*
Y103892D01*
G01X1023745Y102437D02*
Y103415D01*
G01X1024895Y103892D02*
X1023572Y105215D01*
G01X1023745Y103415D02*
X1023095Y104065D01*
G01X1023572Y105215D02*
X1017729D01*
G01X1023095Y104065D02*
X1019589D01*
G01X1010225Y111000D02*
X1018625Y119400D01*
G01X1011411Y113813D02*
X1017475Y119877D01*
G01X1018625Y119400D02*
Y184533D01*
G01X1017475Y119877D02*
Y184533D01*
G01X1010625Y94955D02*
X1010225Y95355D01*
G01Y103689D02*
Y111000D01*
G01Y95355D02*
Y103689D01*
G01X1009075Y94878D02*
Y111477D01*
G01X1010225Y111000D02*
X1018625Y119400D01*
G01X1009075Y111477D02*
X1011411Y113813D01*
G01X1026757Y464883D02*
X1021650Y469990D01*
G01X1026757Y464883D02*
X1021650Y469990D01*
G01X1026757Y461106D02*
Y464883D01*
G01Y461106D02*
Y410073D01*
G01X1027907Y465360D02*
Y410053D01*
G01X1021181Y461326D02*
X1018496Y464011D01*
G01X1007050Y473830D02*
X1020031Y460849D01*
G01X1021181Y410262D02*
Y417083D01*
G01Y419933D02*
Y421883D01*
G01Y424733D02*
Y426683D01*
G01Y429533D02*
Y431483D01*
G01Y434333D02*
Y461326D01*
G01X1020031Y460849D02*
Y410490D01*
G01X1029958Y467221D02*
Y451876D01*
G01D02*
Y410133D01*
G01X1031108D02*
Y467698D01*
G01X1024768Y410161D02*
Y463771D01*
G01X1023618Y410158D02*
Y435094D01*
G01X1024768Y410161D02*
Y463771D01*
G01X1023618Y437844D02*
Y439794D01*
G01X1024768Y410161D02*
Y463771D01*
G01X1023618Y442544D02*
Y444494D01*
G01X1024768Y410161D02*
Y463771D01*
G01X1023618Y447244D02*
Y449194D01*
G01X1024768Y410161D02*
Y463771D01*
G01X1023618Y451944D02*
Y453894D01*
G01X1024768Y410161D02*
Y463771D01*
G01X1023618Y456644D02*
Y458594D01*
G01X1024768Y410161D02*
Y463771D01*
G01X1023618Y461344D02*
Y463294D01*
G01X1024768Y463771D02*
X1012575Y475964D01*
G01X1023618Y463294D02*
X1021416Y465496D01*
G01X1024768Y463771D02*
X1012575Y475964D01*
G01X1024768Y463771D02*
X1012575Y475964D01*
G01X1024768Y463771D02*
X1012575Y475964D01*
G01X1027907Y465360D02*
Y410053D01*
G01X1026757Y461106D02*
Y464883D01*
G01D02*
X1021650Y469990D01*
G01X1027907Y465360D02*
Y410053D01*
G01X1026757Y461106D02*
Y410073D01*
G01X1020031Y460849D02*
Y410490D01*
G01X1021181Y410262D02*
Y417083D01*
G01X1020031Y460849D02*
Y410490D01*
G01X1021181Y419933D02*
Y421883D01*
G01X1020031Y460849D02*
Y410490D01*
G01X1021181Y424733D02*
Y426683D01*
G01X1020031Y460849D02*
Y410490D01*
G01X1021181Y429533D02*
Y431483D01*
G01X1020031Y460849D02*
Y410490D01*
G01X1021181Y434333D02*
Y461326D01*
G01X1007050Y473830D02*
X1020031Y460849D01*
G01X1021181Y461326D02*
X1018496Y464011D01*
G01X1007050Y473830D02*
X1020031Y460849D01*
G01X1007050Y473830D02*
X1020031Y460849D01*
G01X1007050Y473830D02*
X1020031Y460849D01*
G01X1031108Y410133D02*
Y467698D01*
G01X1029958Y467221D02*
Y451876D01*
G01X1031108Y410133D02*
Y467698D01*
G01X1029958Y451876D02*
Y410133D01*
G01X1023618Y410158D02*
Y435094D01*
G01Y437844D02*
Y439794D01*
G01Y442544D02*
Y444494D01*
G01Y447244D02*
Y449194D01*
G01Y451944D02*
Y453894D01*
G01Y456644D02*
Y458594D01*
G01Y461344D02*
Y463294D01*
G01X1024768Y410161D02*
Y463771D01*
G01X1023618Y463294D02*
X1021416Y465496D01*
G01X1024768Y463771D02*
X1012575Y475964D01*
G01X1027907Y465360D02*
Y410053D01*
G01X1026757Y461106D02*
Y464883D01*
G01D02*
X1021650Y469990D01*
G01X1027907Y465360D02*
Y410053D01*
G01X1026757Y461106D02*
Y410073D01*
G01X1031108Y410133D02*
Y467698D01*
G01X1029958Y467221D02*
Y451876D01*
G01X1031108Y410133D02*
Y467698D01*
G01X1029958Y451876D02*
Y410133D01*
G01X1026757Y464883D02*
X1021650Y469990D01*
G01X1026757Y464883D02*
X1021650Y469990D01*
G01X1026757Y461106D02*
Y464883D01*
G01Y461106D02*
Y410073D01*
G01X1027907Y465360D02*
Y410053D01*
G01X1029958Y467221D02*
Y451876D01*
G01D02*
Y410133D01*
G01X1031108D02*
Y467698D01*
G01X1014147Y518281D02*
X1013023Y519405D01*
G01X1014173Y519882D02*
X1014624Y519431D01*
G01X1015945Y518281D02*
X1014147D01*
G01X1014624Y519431D02*
X1016422D01*
G01X1021239Y512987D02*
X1015945Y518281D01*
G01X1016422Y519431D02*
X1022389Y513464D01*
G01X1021239Y488356D02*
Y512987D01*
G01X1022389Y513464D02*
Y506247D01*
G01X1021239Y488356D02*
Y512987D01*
G01X1022389Y503539D02*
Y501516D01*
G01X1021239Y488356D02*
Y512987D01*
G01X1022389Y498878D02*
Y496820D01*
G01X1021239Y488356D02*
Y512987D01*
G01X1022389Y494182D02*
Y490150D01*
G01X1021239Y488356D02*
Y512987D01*
G01X1022389Y490150D02*
Y487879D01*
G01X1020182Y487299D02*
X1021239Y488356D01*
G01X1022389Y487879D02*
X1020659Y486149D01*
G01X1016907Y487299D02*
X1020182D01*
G01X1020659Y486149D02*
X1017384D01*
G01X1015584Y485976D02*
X1016907Y487299D01*
G01X1017384Y486149D02*
X1016734Y485499D01*
G01X1015584Y483672D02*
Y485976D01*
G01X1016734Y485499D02*
Y484149D01*
G01X1016907Y482349D02*
X1015584Y483672D01*
G01X1016734Y484149D02*
X1017384Y483499D01*
G01X1023651Y482349D02*
X1016907D01*
G01X1017384Y483499D02*
X1024128D01*
G01X1024301Y481699D02*
X1023651Y482349D01*
G01X1024128Y483499D02*
X1025451Y482176D01*
G01X1024301Y480349D02*
Y481699D01*
G01X1025451Y482176D02*
Y479872D01*
G01X1023651Y479699D02*
X1024301Y480349D01*
G01X1025451Y479872D02*
X1024128Y478549D01*
G01X1016907Y479699D02*
X1023651D01*
G01X1024128Y478549D02*
X1017384D01*
G01X1015584Y478376D02*
X1016907Y479699D01*
G01X1017384Y478549D02*
X1016734Y477899D01*
G01X1015584Y476072D02*
Y478376D01*
G01X1016734Y477899D02*
Y476549D01*
G01X1016907Y474749D02*
X1015584Y476072D01*
G01X1016734Y476549D02*
X1017384Y475899D01*
G01X1021000Y474749D02*
X1016907D01*
G01X1017384Y475899D02*
X1021477D01*
G01X1021650Y474099D02*
X1021000Y474749D01*
G01X1021477Y475899D02*
X1022800Y474576D01*
G01X1021650Y469990D02*
Y474099D01*
G01X1022800Y474576D02*
Y470467D01*
G01D02*
X1024232Y469035D01*
G01X1026068Y467199D02*
X1027907Y465360D01*
G01X1011807Y516315D02*
Y515757D01*
G01X1012957Y516068D02*
Y516792D01*
G01X1011034Y517088D02*
X1011807Y516315D01*
G01X1012957Y516792D02*
X1011511Y518238D01*
G01X1007564Y517088D02*
X1011034D01*
G01X1011511Y518238D02*
X1007087D01*
G01X1006830Y516354D02*
X1007564Y517088D01*
G01X1007087Y518238D02*
X1005680Y516831D01*
G01X1006830Y514491D02*
Y516354D01*
G01X1005680Y516831D02*
Y514014D01*
G01X1007109Y511448D02*
Y514212D01*
G01X1005959Y513735D02*
Y511925D01*
G01X1006725Y511064D02*
X1007109Y511448D01*
G01X1005959Y511925D02*
X1005575Y511541D01*
G01X1006725Y508170D02*
Y511064D01*
G01X1005575Y511541D02*
Y507693D01*
G01X1008200Y506695D02*
X1006725Y508170D01*
G01X1005575Y507693D02*
X1007050Y506218D01*
G01X1008200Y474307D02*
Y475483D01*
G01Y477399D02*
Y478842D01*
G01Y481788D02*
Y483738D01*
G01Y486684D02*
Y488634D01*
G01Y491580D02*
Y493530D01*
G01Y496476D02*
Y498426D01*
G01Y501372D02*
Y502951D01*
G01Y505985D02*
Y506695D01*
G01X1007050Y506218D02*
Y473830D01*
G01X1016573Y465934D02*
X1015053Y467454D01*
G01X1013084Y469423D02*
X1011662Y470845D01*
G01X1009578Y472929D02*
X1008200Y474307D01*
G01X1025650Y513250D02*
Y511300D01*
G01Y508450D02*
Y506500D01*
G01Y503650D02*
Y501700D01*
G01X1026800Y497824D02*
Y512773D01*
G01X1027600Y515200D02*
X1025650Y513250D01*
G01X1026800Y512773D02*
X1028750Y514723D01*
G01X1027600Y523572D02*
Y515200D01*
G01X1028750Y514723D02*
Y524049D01*
G01X1026114Y525058D02*
X1027600Y523572D01*
G01X1028750Y524049D02*
X1019145Y533654D01*
G01X1027619Y469560D02*
X1029958Y467221D01*
G01X1031108Y467698D02*
X1028769Y470037D01*
G01X1027619Y484101D02*
Y475990D01*
G01Y473044D02*
Y469560D01*
G01X1028769Y470037D02*
Y484578D01*
G01X1025650Y486070D02*
X1027619Y484101D01*
G01X1028769Y484578D02*
X1026800Y486547D01*
G01X1025650Y498850D02*
Y486070D01*
G01X1026800Y486547D02*
Y497824D01*
G01X1019585Y467327D02*
X1018313Y468599D01*
G01X1016337Y470575D02*
X1014878Y472034D01*
G01X1012830Y474082D02*
X1011425Y475487D01*
G01X1012575Y475964D02*
Y488570D01*
G01X1011425Y475487D02*
Y479255D01*
G01X1012575Y475964D02*
Y488570D01*
G01X1011425Y482201D02*
Y484151D01*
G01X1012575Y475964D02*
Y488570D01*
G01X1011425Y487097D02*
Y489047D01*
G01X1012575Y488570D02*
X1013225Y489220D01*
G01X1011425Y489047D02*
X1012748Y490370D01*
G01X1013225Y489220D02*
X1016373D01*
G01X1012748Y490370D02*
X1015896D01*
G01X1016373Y489220D02*
X1017696Y490543D01*
G01X1015896Y490370D02*
X1016546Y491020D01*
G01X1017696Y490543D02*
Y492847D01*
G01X1016546Y491020D02*
Y492370D01*
G01X1017696Y492847D02*
X1016373Y494170D01*
G01X1016546Y492370D02*
X1015896Y493020D01*
G01X1016373Y494170D02*
X1013225D01*
G01X1015896Y493020D02*
X1012748D01*
G01X1013225Y494170D02*
X1012575Y494820D01*
G01X1012748Y493020D02*
X1011425Y494343D01*
G01X1012575Y494820D02*
Y496170D01*
G01X1011425Y494343D02*
Y496647D01*
G01X1012575Y496170D02*
X1013225Y496820D01*
G01X1011425Y496647D02*
X1012748Y497970D01*
G01X1013225Y496820D02*
X1016373D01*
G01X1012748Y497970D02*
X1015896D01*
G01X1016373Y496820D02*
X1017696Y498143D01*
G01X1015896Y497970D02*
X1016546Y498620D01*
G01X1017696Y498143D02*
Y500447D01*
G01X1016546Y498620D02*
Y499970D01*
G01X1017696Y500447D02*
X1016373Y501770D01*
G01X1016546Y499970D02*
X1015896Y500620D01*
G01X1016373Y501770D02*
X1013225D01*
G01X1015896Y500620D02*
X1012748D01*
G01X1013225Y501770D02*
X1012575Y502420D01*
G01X1012748Y500620D02*
X1011425Y501943D01*
G01X1012575Y502420D02*
Y504769D01*
G01X1011425Y501943D02*
Y505246D01*
G01X1012575Y504769D02*
X1013661Y505855D01*
G01X1011425Y505246D02*
X1013184Y507005D01*
G01X1013661Y505855D02*
X1017227D01*
G01X1013184Y507005D02*
X1016750D01*
G01X1017227Y505855D02*
X1019488Y508116D01*
G01X1016750Y507005D02*
X1018338Y508593D01*
G01X1019488Y508116D02*
Y511303D01*
G01X1018338Y508593D02*
Y510826D01*
G01X1019488Y511303D02*
X1017491Y513300D01*
G01X1018338Y510826D02*
X1017014Y512150D01*
G01X1017491Y513300D02*
X1013141D01*
G01X1017014Y512150D02*
X1013618D01*
G01X1013141Y513300D02*
X1011945Y512104D01*
G01X1013618Y512150D02*
X1013095Y511627D01*
G01X1011945Y512104D02*
Y510933D01*
G01X1013095Y511627D02*
Y510892D01*
G01X1022800Y470467D02*
X1024232Y469035D01*
G01X1026068Y467199D02*
X1027907Y465360D01*
G01X1022800Y474576D02*
Y470467D01*
G01X1021650Y469990D02*
Y474099D01*
G01X1021477Y475899D02*
X1022800Y474576D01*
G01X1021650Y474099D02*
X1021000Y474749D01*
G01X1017384Y475899D02*
X1021477D01*
G01X1021000Y474749D02*
X1016907D01*
G01X1016734Y476549D02*
X1017384Y475899D01*
G01X1016907Y474749D02*
X1015584Y476072D01*
G01X1016734Y477899D02*
Y476549D01*
G01X1015584Y476072D02*
Y478376D01*
G01X1017384Y478549D02*
X1016734Y477899D01*
G01X1015584Y478376D02*
X1016907Y479699D01*
G01X1024128Y478549D02*
X1017384D01*
G01X1016907Y479699D02*
X1023651D01*
G01X1025451Y479872D02*
X1024128Y478549D01*
G01X1023651Y479699D02*
X1024301Y480349D01*
G01X1025451Y482176D02*
Y479872D01*
G01X1024301Y480349D02*
Y481699D01*
G01X1024128Y483499D02*
X1025451Y482176D01*
G01X1024301Y481699D02*
X1023651Y482349D01*
G01X1017384Y483499D02*
X1024128D01*
G01X1023651Y482349D02*
X1016907D01*
G01X1016734Y484149D02*
X1017384Y483499D01*
G01X1016907Y482349D02*
X1015584Y483672D01*
G01X1016734Y485499D02*
Y484149D01*
G01X1015584Y483672D02*
Y485976D01*
G01X1017384Y486149D02*
X1016734Y485499D01*
G01X1015584Y485976D02*
X1016907Y487299D01*
G01X1020659Y486149D02*
X1017384D01*
G01X1016907Y487299D02*
X1020182D01*
G01X1022389Y487879D02*
X1020659Y486149D01*
G01X1020182Y487299D02*
X1021239Y488356D01*
G01X1022389Y513464D02*
Y506247D01*
G01Y503539D02*
Y501516D01*
G01Y498878D02*
Y496820D01*
G01Y494182D02*
Y490150D01*
G01D02*
Y487879D01*
G01X1021239Y488356D02*
Y512987D01*
G01X1016422Y519431D02*
X1022389Y513464D01*
G01X1021239Y512987D02*
X1015945Y518281D01*
G01X1014624Y519431D02*
X1016422D01*
G01X1015945Y518281D02*
X1014147D01*
G01X1014173Y519882D02*
X1014624Y519431D01*
G01X1014147Y518281D02*
X1013023Y519405D01*
G01X1016573Y465934D02*
X1015053Y467454D01*
G01X1013084Y469423D02*
X1011662Y470845D01*
G01X1009578Y472929D02*
X1008200Y474307D01*
G01X1007050Y506218D02*
Y473830D01*
G01X1008200Y474307D02*
Y475483D01*
G01X1007050Y506218D02*
Y473830D01*
G01X1008200Y477399D02*
Y478842D01*
G01X1007050Y506218D02*
Y473830D01*
G01X1008200Y481788D02*
Y483738D01*
G01X1007050Y506218D02*
Y473830D01*
G01X1008200Y486684D02*
Y488634D01*
G01X1007050Y506218D02*
Y473830D01*
G01X1008200Y491580D02*
Y493530D01*
G01X1007050Y506218D02*
Y473830D01*
G01X1008200Y496476D02*
Y498426D01*
G01X1007050Y506218D02*
Y473830D01*
G01X1008200Y501372D02*
Y502951D01*
G01X1007050Y506218D02*
Y473830D01*
G01X1008200Y505985D02*
Y506695D01*
G01X1005575Y507693D02*
X1007050Y506218D01*
G01X1008200Y506695D02*
X1006725Y508170D01*
G01X1005575Y511541D02*
Y507693D01*
G01X1006725Y508170D02*
Y511064D01*
G01X1005959Y511925D02*
X1005575Y511541D01*
G01X1006725Y511064D02*
X1007109Y511448D01*
G01X1005959Y513735D02*
Y511925D01*
G01X1007109Y511448D02*
Y514212D01*
G01X1005680Y516831D02*
Y514014D01*
G01X1006830Y514491D02*
Y516354D01*
G01X1007087Y518238D02*
X1005680Y516831D01*
G01X1006830Y516354D02*
X1007564Y517088D01*
G01X1011511Y518238D02*
X1007087D01*
G01X1007564Y517088D02*
X1011034D01*
G01X1012957Y516792D02*
X1011511Y518238D01*
G01X1011034Y517088D02*
X1011807Y516315D01*
G01X1012957Y516068D02*
Y516792D01*
G01X1011807Y516315D02*
Y515757D01*
G01X1028750Y524049D02*
X1019145Y533654D01*
G01X1028750Y524049D02*
X1019145Y533654D01*
G01X1028750Y524049D02*
X1019145Y533654D01*
G01X1026114Y525058D02*
X1027600Y523572D01*
G01X1028750Y514723D02*
Y524049D01*
G01X1027600Y523572D02*
Y515200D01*
G01X1026800Y512773D02*
X1028750Y514723D01*
G01X1027600Y515200D02*
X1025650Y513250D01*
G01X1026800Y497824D02*
Y512773D01*
G01X1025650Y513250D02*
Y511300D01*
G01X1026800Y497824D02*
Y512773D01*
G01X1025650Y508450D02*
Y506500D01*
G01X1026800Y497824D02*
Y512773D01*
G01X1025650Y503650D02*
Y501700D01*
G01X1026800Y486547D02*
Y497824D01*
G01X1025650Y498850D02*
Y486070D01*
G01X1028769Y484578D02*
X1026800Y486547D01*
G01X1025650Y486070D02*
X1027619Y484101D01*
G01X1028769Y470037D02*
Y484578D01*
G01X1027619Y484101D02*
Y475990D01*
G01X1028769Y470037D02*
Y484578D01*
G01X1027619Y473044D02*
Y469560D01*
G01X1031108Y467698D02*
X1028769Y470037D01*
G01X1027619Y469560D02*
X1029958Y467221D01*
G01X1019585Y467327D02*
X1018313Y468599D01*
G01X1016337Y470575D02*
X1014878Y472034D01*
G01X1012830Y474082D02*
X1011425Y475487D01*
G01D02*
Y479255D01*
G01Y482201D02*
Y484151D01*
G01Y487097D02*
Y489047D01*
G01X1012575Y475964D02*
Y488570D01*
G01X1011425Y489047D02*
X1012748Y490370D01*
G01X1012575Y488570D02*
X1013225Y489220D01*
G01X1012748Y490370D02*
X1015896D01*
G01X1013225Y489220D02*
X1016373D01*
G01X1015896Y490370D02*
X1016546Y491020D01*
G01X1016373Y489220D02*
X1017696Y490543D01*
G01X1016546Y491020D02*
Y492370D01*
G01X1017696Y490543D02*
Y492847D01*
G01X1016546Y492370D02*
X1015896Y493020D01*
G01X1017696Y492847D02*
X1016373Y494170D01*
G01X1015896Y493020D02*
X1012748D01*
G01X1016373Y494170D02*
X1013225D01*
G01X1012748Y493020D02*
X1011425Y494343D01*
G01X1013225Y494170D02*
X1012575Y494820D01*
G01X1011425Y494343D02*
Y496647D01*
G01X1012575Y494820D02*
Y496170D01*
G01X1011425Y496647D02*
X1012748Y497970D01*
G01X1012575Y496170D02*
X1013225Y496820D01*
G01X1012748Y497970D02*
X1015896D01*
G01X1013225Y496820D02*
X1016373D01*
G01X1015896Y497970D02*
X1016546Y498620D01*
G01X1016373Y496820D02*
X1017696Y498143D01*
G01X1016546Y498620D02*
Y499970D01*
G01X1017696Y498143D02*
Y500447D01*
G01X1016546Y499970D02*
X1015896Y500620D01*
G01X1017696Y500447D02*
X1016373Y501770D01*
G01X1015896Y500620D02*
X1012748D01*
G01X1016373Y501770D02*
X1013225D01*
G01X1012748Y500620D02*
X1011425Y501943D01*
G01X1013225Y501770D02*
X1012575Y502420D01*
G01X1011425Y501943D02*
Y505246D01*
G01X1012575Y502420D02*
Y504769D01*
G01X1011425Y505246D02*
X1013184Y507005D01*
G01X1012575Y504769D02*
X1013661Y505855D01*
G01X1013184Y507005D02*
X1016750D01*
G01X1013661Y505855D02*
X1017227D01*
G01X1016750Y507005D02*
X1018338Y508593D01*
G01X1017227Y505855D02*
X1019488Y508116D01*
G01X1018338Y508593D02*
Y510826D01*
G01X1019488Y508116D02*
Y511303D01*
G01X1018338Y510826D02*
X1017014Y512150D01*
G01X1019488Y511303D02*
X1017491Y513300D01*
G01X1017014Y512150D02*
X1013618D01*
G01X1017491Y513300D02*
X1013141D01*
G01X1013618Y512150D02*
X1013095Y511627D01*
G01X1013141Y513300D02*
X1011945Y512104D01*
G01X1013095Y511627D02*
Y510892D01*
G01X1011945Y512104D02*
Y510933D01*
G01X1022800Y470467D02*
X1024232Y469035D01*
G01X1026068Y467199D02*
X1027907Y465360D01*
G01X1022800Y474576D02*
Y470467D01*
G01X1021650Y469990D02*
Y474099D01*
G01X1021477Y475899D02*
X1022800Y474576D01*
G01X1021650Y474099D02*
X1021000Y474749D01*
G01X1017384Y475899D02*
X1021477D01*
G01X1021000Y474749D02*
X1016907D01*
G01X1016734Y476549D02*
X1017384Y475899D01*
G01X1016907Y474749D02*
X1015584Y476072D01*
G01X1016734Y477899D02*
Y476549D01*
G01X1015584Y476072D02*
Y478376D01*
G01X1017384Y478549D02*
X1016734Y477899D01*
G01X1015584Y478376D02*
X1016907Y479699D01*
G01X1024128Y478549D02*
X1017384D01*
G01X1016907Y479699D02*
X1023651D01*
G01X1025451Y479872D02*
X1024128Y478549D01*
G01X1023651Y479699D02*
X1024301Y480349D01*
G01X1025451Y482176D02*
Y479872D01*
G01X1024301Y480349D02*
Y481699D01*
G01X1024128Y483499D02*
X1025451Y482176D01*
G01X1024301Y481699D02*
X1023651Y482349D01*
G01X1017384Y483499D02*
X1024128D01*
G01X1023651Y482349D02*
X1016907D01*
G01X1016734Y484149D02*
X1017384Y483499D01*
G01X1016907Y482349D02*
X1015584Y483672D01*
G01X1016734Y485499D02*
Y484149D01*
G01X1015584Y483672D02*
Y485976D01*
G01X1017384Y486149D02*
X1016734Y485499D01*
G01X1015584Y485976D02*
X1016907Y487299D01*
G01X1020659Y486149D02*
X1017384D01*
G01X1016907Y487299D02*
X1020182D01*
G01X1022389Y487879D02*
X1020659Y486149D01*
G01X1020182Y487299D02*
X1021239Y488356D01*
G01X1022389Y513464D02*
Y506247D01*
G01Y503539D02*
Y501516D01*
G01Y498878D02*
Y496820D01*
G01Y494182D02*
Y490150D01*
G01D02*
Y487879D01*
G01X1021239Y488356D02*
Y512987D01*
G01X1016422Y519431D02*
X1022389Y513464D01*
G01X1021239Y512987D02*
X1015945Y518281D01*
G01X1014624Y519431D02*
X1016422D01*
G01X1015945Y518281D02*
X1014147D01*
G01X1014173Y519882D02*
X1014624Y519431D01*
G01X1014147Y518281D02*
X1013023Y519405D01*
G01X1028750Y524049D02*
X1019145Y533654D01*
G01X1028750Y524049D02*
X1019145Y533654D01*
G01X1028750Y524049D02*
X1019145Y533654D01*
G01X1026114Y525058D02*
X1027600Y523572D01*
G01X1028750Y514723D02*
Y524049D01*
G01X1027600Y523572D02*
Y515200D01*
G01X1026800Y512773D02*
X1028750Y514723D01*
G01X1027600Y515200D02*
X1025650Y513250D01*
G01X1026800Y497824D02*
Y512773D01*
G01X1025650Y513250D02*
Y511300D01*
G01X1026800Y497824D02*
Y512773D01*
G01X1025650Y508450D02*
Y506500D01*
G01X1026800Y497824D02*
Y512773D01*
G01X1025650Y503650D02*
Y501700D01*
G01X1026800Y486547D02*
Y497824D01*
G01X1025650Y498850D02*
Y486070D01*
G01X1028769Y484578D02*
X1026800Y486547D01*
G01X1025650Y486070D02*
X1027619Y484101D01*
G01X1028769Y470037D02*
Y484578D01*
G01X1027619Y484101D02*
Y475990D01*
G01X1028769Y470037D02*
Y484578D01*
G01X1027619Y473044D02*
Y469560D01*
G01X1031108Y467698D02*
X1028769Y470037D01*
G01X1027619Y469560D02*
X1029958Y467221D01*
G01X1014147Y518281D02*
X1013023Y519405D01*
G01X1014173Y519882D02*
X1014624Y519431D01*
G01X1015945Y518281D02*
X1014147D01*
G01X1014624Y519431D02*
X1016422D01*
G01X1021239Y512987D02*
X1015945Y518281D01*
G01X1016422Y519431D02*
X1022389Y513464D01*
G01X1021239Y488356D02*
Y512987D01*
G01X1022389Y513464D02*
Y506247D01*
G01X1021239Y488356D02*
Y512987D01*
G01X1022389Y503539D02*
Y501516D01*
G01X1021239Y488356D02*
Y512987D01*
G01X1022389Y498878D02*
Y496820D01*
G01X1021239Y488356D02*
Y512987D01*
G01X1022389Y494182D02*
Y490150D01*
G01X1021239Y488356D02*
Y512987D01*
G01X1022389Y490150D02*
Y487879D01*
G01X1020182Y487299D02*
X1021239Y488356D01*
G01X1022389Y487879D02*
X1020659Y486149D01*
G01X1016907Y487299D02*
X1020182D01*
G01X1020659Y486149D02*
X1017384D01*
G01X1015584Y485976D02*
X1016907Y487299D01*
G01X1017384Y486149D02*
X1016734Y485499D01*
G01X1015584Y483672D02*
Y485976D01*
G01X1016734Y485499D02*
Y484149D01*
G01X1016907Y482349D02*
X1015584Y483672D01*
G01X1016734Y484149D02*
X1017384Y483499D01*
G01X1023651Y482349D02*
X1016907D01*
G01X1017384Y483499D02*
X1024128D01*
G01X1024301Y481699D02*
X1023651Y482349D01*
G01X1024128Y483499D02*
X1025451Y482176D01*
G01X1024301Y480349D02*
Y481699D01*
G01X1025451Y482176D02*
Y479872D01*
G01X1023651Y479699D02*
X1024301Y480349D01*
G01X1025451Y479872D02*
X1024128Y478549D01*
G01X1016907Y479699D02*
X1023651D01*
G01X1024128Y478549D02*
X1017384D01*
G01X1015584Y478376D02*
X1016907Y479699D01*
G01X1017384Y478549D02*
X1016734Y477899D01*
G01X1015584Y476072D02*
Y478376D01*
G01X1016734Y477899D02*
Y476549D01*
G01X1016907Y474749D02*
X1015584Y476072D01*
G01X1016734Y476549D02*
X1017384Y475899D01*
G01X1021000Y474749D02*
X1016907D01*
G01X1017384Y475899D02*
X1021477D01*
G01X1021650Y474099D02*
X1021000Y474749D01*
G01X1021477Y475899D02*
X1022800Y474576D01*
G01X1021650Y469990D02*
Y474099D01*
G01X1022800Y474576D02*
Y470467D01*
G01D02*
X1024232Y469035D01*
G01X1026068Y467199D02*
X1027907Y465360D01*
G01X1025650Y513250D02*
Y511300D01*
G01Y508450D02*
Y506500D01*
G01Y503650D02*
Y501700D01*
G01X1026800Y497824D02*
Y512773D01*
G01X1027600Y515200D02*
X1025650Y513250D01*
G01X1026800Y512773D02*
X1028750Y514723D01*
G01X1027600Y523572D02*
Y515200D01*
G01X1028750Y514723D02*
Y524049D01*
G01X1026114Y525058D02*
X1027600Y523572D01*
G01X1028750Y524049D02*
X1019145Y533654D01*
G01X1027619Y469560D02*
X1029958Y467221D01*
G01X1031108Y467698D02*
X1028769Y470037D01*
G01X1027619Y484101D02*
Y475990D01*
G01Y473044D02*
Y469560D01*
G01X1028769Y470037D02*
Y484578D01*
G01X1025650Y486070D02*
X1027619Y484101D01*
G01X1028769Y484578D02*
X1026800Y486547D01*
G01X1025650Y498850D02*
Y486070D01*
G01X1026800Y486547D02*
Y497824D01*
G01X1018668Y532504D02*
X1020153Y531019D01*
G01X1021996Y529176D02*
X1024259Y526913D01*
G01X1013826Y532504D02*
X1018668D01*
G01X1019145Y533654D02*
X1014303D01*
G01X1011924Y534406D02*
X1013826Y532504D01*
G01X1014303Y533654D02*
X1013074Y534883D01*
G01X1011924Y536431D02*
Y534406D01*
G01X1013074Y534883D02*
Y536530D01*
G01Y534883D02*
Y536530D01*
G01X1011924Y536431D02*
Y534406D01*
G01X1014303Y533654D02*
X1013074Y534883D01*
G01X1011924Y534406D02*
X1013826Y532504D01*
G01X1019145Y533654D02*
X1014303D01*
G01X1013826Y532504D02*
X1018668D01*
G01D02*
X1020153Y531019D01*
G01X1021996Y529176D02*
X1024259Y526913D01*
G01X1013074Y534883D02*
Y536530D01*
G01X1011924Y536431D02*
Y534406D01*
G01X1014303Y533654D02*
X1013074Y534883D01*
G01X1011924Y534406D02*
X1013826Y532504D01*
G01X1019145Y533654D02*
X1014303D01*
G01X1013826Y532504D02*
X1018668D01*
G01D02*
X1020153Y531019D01*
G01X1021996Y529176D02*
X1024259Y526913D01*
G01X1018668Y532504D02*
X1020153Y531019D01*
G01X1021996Y529176D02*
X1024259Y526913D01*
G01X1013826Y532504D02*
X1018668D01*
G01X1019145Y533654D02*
X1014303D01*
G01X1011924Y534406D02*
X1013826Y532504D01*
G01X1014303Y533654D02*
X1013074Y534883D01*
G01X1011924Y536431D02*
Y534406D01*
G01X1013074Y534883D02*
Y536530D01*
G01X1094042Y132512D02*
X1095034D01*
G01D02*
X1096512Y131034D01*
G01X1094042Y132512D02*
X1095034D01*
G01X1095511Y133662D02*
X1093565D01*
G01X1093702Y132172D02*
X1094042Y132512D01*
G01X1093565Y133662D02*
X1093225Y133322D01*
G01X1091756Y132172D02*
X1093702D01*
G01X1093225Y133322D02*
X1092233D01*
G01X1089607Y134321D02*
X1091756Y132172D01*
G01X1092233Y133322D02*
X1090757Y134798D01*
G01X1089607Y136267D02*
Y134321D01*
G01X1090757Y134798D02*
Y135790D01*
G01X1089947Y136607D02*
X1089607Y136267D01*
G01X1090757Y135790D02*
X1091097Y136130D01*
G01X1089947Y137599D02*
Y136607D01*
G01X1091097Y136130D02*
Y138076D01*
G01X1088469Y139077D02*
X1089947Y137599D01*
G01X1091097Y138076D02*
X1088946Y140227D01*
G01X1085132Y139077D02*
X1088469D01*
G01X1088946Y140227D02*
X1085609D01*
G01X1075701Y148508D02*
X1085132Y139077D01*
G01X1085609Y140227D02*
X1082709Y143127D01*
G01X1075701Y148508D02*
X1085132Y139077D01*
G01X1081294Y144542D02*
X1080277Y145559D01*
G01X1075701Y148508D02*
X1085132Y139077D01*
G01X1078862Y146974D02*
X1076851Y148985D01*
G01X1075701Y158861D02*
Y148508D01*
G01X1076851Y148985D02*
Y158861D01*
G01X1080520Y154135D02*
X1116870Y117785D01*
G01X1080520Y154135D02*
X1116870Y117785D01*
G01X1109228Y123800D02*
X1079370Y153658D01*
G01X1080520Y158726D02*
Y154135D01*
G01X1079370Y153658D02*
Y158760D01*
G01X1076851Y148985D02*
Y158861D01*
G01X1075701D02*
Y148508D01*
G01X1085609Y140227D02*
X1082709Y143127D01*
G01X1081294Y144542D02*
X1080277Y145559D01*
G01X1078862Y146974D02*
X1076851Y148985D01*
G01X1075701Y148508D02*
X1085132Y139077D01*
G01X1088946Y140227D02*
X1085609D01*
G01X1085132Y139077D02*
X1088469D01*
G01X1091097Y138076D02*
X1088946Y140227D01*
G01X1088469Y139077D02*
X1089947Y137599D01*
G01X1091097Y136130D02*
Y138076D01*
G01X1089947Y137599D02*
Y136607D01*
G01X1090757Y135790D02*
X1091097Y136130D01*
G01X1089947Y136607D02*
X1089607Y136267D01*
G01X1090757Y134798D02*
Y135790D01*
G01X1089607Y136267D02*
Y134321D01*
G01X1092233Y133322D02*
X1090757Y134798D01*
G01X1089607Y134321D02*
X1091756Y132172D01*
G01X1093225Y133322D02*
X1092233D01*
G01X1091756Y132172D02*
X1093702D01*
G01X1093565Y133662D02*
X1093225Y133322D01*
G01X1093702Y132172D02*
X1094042Y132512D01*
G01X1095511Y133662D02*
X1093565D01*
G01X1094042Y132512D02*
X1095034D01*
G01D02*
X1096512Y131034D01*
G01X1079370Y153658D02*
Y158760D01*
G01X1080520Y158726D02*
Y154135D01*
G01X1109228Y123800D02*
X1079370Y153658D01*
G01X1080520Y154135D02*
X1116870Y117785D01*
G01X1094042Y132512D02*
X1095034D01*
G01D02*
X1096512Y131034D01*
G01X1094042Y132512D02*
X1095034D01*
G01X1095511Y133662D02*
X1093565D01*
G01X1093702Y132172D02*
X1094042Y132512D01*
G01X1093565Y133662D02*
X1093225Y133322D01*
G01X1091756Y132172D02*
X1093702D01*
G01X1093225Y133322D02*
X1092233D01*
G01X1089607Y134321D02*
X1091756Y132172D01*
G01X1092233Y133322D02*
X1090757Y134798D01*
G01X1089607Y136267D02*
Y134321D01*
G01X1090757Y134798D02*
Y135790D01*
G01X1089947Y136607D02*
X1089607Y136267D01*
G01X1090757Y135790D02*
X1091097Y136130D01*
G01X1089947Y137599D02*
Y136607D01*
G01X1091097Y136130D02*
Y138076D01*
G01X1088469Y139077D02*
X1089947Y137599D01*
G01X1091097Y138076D02*
X1088946Y140227D01*
G01X1085132Y139077D02*
X1088469D01*
G01X1088946Y140227D02*
X1085609D01*
G01X1075701Y148508D02*
X1085132Y139077D01*
G01X1085609Y140227D02*
X1082709Y143127D01*
G01X1075701Y148508D02*
X1085132Y139077D01*
G01X1081294Y144542D02*
X1080277Y145559D01*
G01X1075701Y148508D02*
X1085132Y139077D01*
G01X1078862Y146974D02*
X1076851Y148985D01*
G01X1075701Y158861D02*
Y148508D01*
G01X1076851Y148985D02*
Y158861D01*
G01X1080520Y154135D02*
X1116870Y117785D01*
G01X1080520Y154135D02*
X1116870Y117785D01*
G01X1109228Y123800D02*
X1079370Y153658D01*
G01X1080520Y158726D02*
Y154135D01*
G01X1079370Y153658D02*
Y158760D01*
G01X1080520Y154135D02*
X1116870Y117785D01*
G01X1080520Y154135D02*
X1116870Y117785D01*
G01X1109228Y123800D02*
X1079370Y153658D01*
G01X1080520Y158726D02*
Y154135D01*
G01X1079370Y153658D02*
Y158760D01*
G01X1076851Y148985D02*
Y158861D01*
G01X1075701D02*
Y148508D01*
G01X1085609Y140227D02*
X1082709Y143127D01*
G01X1081294Y144542D02*
X1080277Y145559D01*
G01X1078862Y146974D02*
X1076851Y148985D01*
G01X1075701Y148508D02*
X1085132Y139077D01*
G01X1088946Y140227D02*
X1085609D01*
G01X1085132Y139077D02*
X1088469D01*
G01X1091097Y138076D02*
X1088946Y140227D01*
G01X1088469Y139077D02*
X1089947Y137599D01*
G01X1091097Y136130D02*
Y138076D01*
G01X1089947Y137599D02*
Y136607D01*
G01X1090757Y135790D02*
X1091097Y136130D01*
G01X1089947Y136607D02*
X1089607Y136267D01*
G01X1090757Y134798D02*
Y135790D01*
G01X1089607Y136267D02*
Y134321D01*
G01X1092233Y133322D02*
X1090757Y134798D01*
G01X1089607Y134321D02*
X1091756Y132172D01*
G01X1093225Y133322D02*
X1092233D01*
G01X1091756Y132172D02*
X1093702D01*
G01X1093565Y133662D02*
X1093225Y133322D01*
G01X1093702Y132172D02*
X1094042Y132512D01*
G01X1095511Y133662D02*
X1093565D01*
G01X1094042Y132512D02*
X1095034D01*
G01D02*
X1096512Y131034D01*
G01X1076851Y148985D02*
Y158861D01*
G01X1075701D02*
Y148508D01*
G01X1085609Y140227D02*
X1082709Y143127D01*
G01X1081294Y144542D02*
X1080277Y145559D01*
G01X1078862Y146974D02*
X1076851Y148985D01*
G01X1075701Y148508D02*
X1085132Y139077D01*
G01X1088946Y140227D02*
X1085609D01*
G01X1085132Y139077D02*
X1088469D01*
G01X1091097Y138076D02*
X1088946Y140227D01*
G01X1088469Y139077D02*
X1089947Y137599D01*
G01X1091097Y136130D02*
Y138076D01*
G01X1089947Y137599D02*
Y136607D01*
G01X1090757Y135790D02*
X1091097Y136130D01*
G01X1089947Y136607D02*
X1089607Y136267D01*
G01X1090757Y134798D02*
Y135790D01*
G01X1089607Y136267D02*
Y134321D01*
G01X1092233Y133322D02*
X1090757Y134798D01*
G01X1089607Y134321D02*
X1091756Y132172D01*
G01X1093225Y133322D02*
X1092233D01*
G01X1091756Y132172D02*
X1093702D01*
G01X1093565Y133662D02*
X1093225Y133322D01*
G01X1093702Y132172D02*
X1094042Y132512D01*
G01X1095511Y133662D02*
X1093565D01*
G01X1094042Y132512D02*
X1095034D01*
G01D02*
X1096512Y131034D01*
G01X1079370Y153658D02*
Y158760D01*
G01X1080520Y158726D02*
Y154135D01*
G01X1109228Y123800D02*
X1079370Y153658D01*
G01X1080520Y154135D02*
X1116870Y117785D01*
G01X1079370Y153658D02*
Y158760D01*
G01X1080520Y158726D02*
Y154135D01*
G01X1109228Y123800D02*
X1079370Y153658D01*
G01X1080520Y154135D02*
X1116870Y117785D01*
G01X1079650Y448100D02*
Y450177D01*
G01X1080800Y448100D02*
Y449700D01*
G01X1079650Y450177D02*
X1087220Y457747D01*
G01X1080800Y449700D02*
X1088370Y457270D01*
G01X1087220Y457747D02*
Y461050D01*
G01Y463350D02*
Y466550D01*
G01X1088370Y457270D02*
Y469914D01*
G01X1080800Y448100D02*
Y449700D01*
G01X1079650Y448100D02*
Y450177D01*
G01X1080800Y449700D02*
X1088370Y457270D01*
G01X1079650Y450177D02*
X1087220Y457747D01*
G01X1088370Y457270D02*
Y469914D01*
G01X1087220Y457747D02*
Y461050D01*
G01X1088370Y457270D02*
Y469914D01*
G01X1087220Y463350D02*
Y466550D01*
G01X1088370Y457270D02*
Y469914D01*
G01X1083561Y446411D02*
Y447987D01*
G01X1084711Y446289D02*
Y447510D01*
G01X1083561Y447987D02*
X1085068Y449494D01*
G01X1086483Y450909D02*
X1087190Y451616D01*
G01X1088605Y453031D02*
X1089312Y453738D01*
G01X1090727Y455153D02*
X1091813Y456239D01*
G01X1084711Y447510D02*
X1092963Y455762D01*
G01X1091813Y456239D02*
Y460739D01*
G01Y462739D02*
Y465541D01*
G01X1092963Y455762D02*
Y466018D01*
G01X1084711Y446289D02*
Y447510D01*
G01X1083561Y446411D02*
Y447987D01*
G01X1084711Y447510D02*
X1092963Y455762D01*
G01X1083561Y447987D02*
X1085068Y449494D01*
G01X1084711Y447510D02*
X1092963Y455762D01*
G01X1086483Y450909D02*
X1087190Y451616D01*
G01X1084711Y447510D02*
X1092963Y455762D01*
G01X1088605Y453031D02*
X1089312Y453738D01*
G01X1084711Y447510D02*
X1092963Y455762D01*
G01X1090727Y455153D02*
X1091813Y456239D01*
G01X1092963Y455762D02*
Y466018D01*
G01X1091813Y456239D02*
Y460739D01*
G01X1092963Y455762D02*
Y466018D01*
G01X1091813Y462739D02*
Y465541D01*
G01X1079650Y448100D02*
Y450177D01*
G01X1080800Y448100D02*
Y449700D01*
G01X1079650Y450177D02*
X1087220Y457747D01*
G01X1080800Y449700D02*
X1088370Y457270D01*
G01X1087220Y457747D02*
Y461050D01*
G01Y463350D02*
Y466550D01*
G01X1088370Y457270D02*
Y469914D01*
G01X1080800Y448100D02*
Y449700D01*
G01X1079650Y448100D02*
Y450177D01*
G01X1080800Y449700D02*
X1088370Y457270D01*
G01X1079650Y450177D02*
X1087220Y457747D01*
G01X1088370Y457270D02*
Y469914D01*
G01X1087220Y457747D02*
Y461050D01*
G01X1088370Y457270D02*
Y469914D01*
G01X1087220Y463350D02*
Y466550D01*
G01X1088370Y457270D02*
Y469914D01*
G01X1084711Y446289D02*
Y447510D01*
G01X1083561Y446411D02*
Y447987D01*
G01X1084711Y447510D02*
X1092963Y455762D01*
G01X1083561Y447987D02*
X1085068Y449494D01*
G01X1084711Y447510D02*
X1092963Y455762D01*
G01X1086483Y450909D02*
X1087190Y451616D01*
G01X1084711Y447510D02*
X1092963Y455762D01*
G01X1088605Y453031D02*
X1089312Y453738D01*
G01X1084711Y447510D02*
X1092963Y455762D01*
G01X1090727Y455153D02*
X1091813Y456239D01*
G01X1092963Y455762D02*
Y466018D01*
G01X1091813Y456239D02*
Y460739D01*
G01X1092963Y455762D02*
Y466018D01*
G01X1091813Y462739D02*
Y465541D01*
G01X1083561Y446411D02*
Y447987D01*
G01X1084711Y446289D02*
Y447510D01*
G01X1083561Y447987D02*
X1085068Y449494D01*
G01X1086483Y450909D02*
X1087190Y451616D01*
G01X1088605Y453031D02*
X1089312Y453738D01*
G01X1090727Y455153D02*
X1091813Y456239D01*
G01X1084711Y447510D02*
X1092963Y455762D01*
G01X1091813Y456239D02*
Y460739D01*
G01Y462739D02*
Y465541D01*
G01X1092963Y455762D02*
Y466018D01*
G01X1087220Y468850D02*
Y470391D01*
G01D02*
X1099351Y482522D01*
G01X1088370Y469914D02*
X1118400Y499944D01*
G01X1087220Y468850D02*
Y470391D01*
G01X1088370Y469914D02*
X1118400Y499944D01*
G01X1087220Y470391D02*
X1099351Y482522D01*
G01X1088370Y469914D02*
X1118400Y499944D01*
G01X1091813Y465541D02*
X1090972Y466382D01*
G01X1092963Y466018D02*
X1092122Y466859D01*
G01X1090972Y466382D02*
Y468356D01*
G01X1092122Y466859D02*
Y467879D01*
G01X1090972Y468356D02*
X1092603Y469987D01*
G01X1092122Y467879D02*
X1093080Y468837D01*
G01X1090972Y468356D02*
X1092603Y469987D01*
G01D02*
X1094373D01*
G01X1093080Y468837D02*
X1093896D01*
G01X1094373Y469987D02*
X1095164Y469196D01*
G01D02*
X1096236D01*
G01X1093896Y468837D02*
X1094687Y468046D01*
G01X1095164Y469196D02*
X1096236D01*
G01X1094687Y468046D02*
X1096713D01*
G01X1095164Y469196D02*
X1096236D01*
G01X1092963Y466018D02*
X1092122Y466859D01*
G01X1091813Y465541D02*
X1090972Y466382D01*
G01X1092122Y466859D02*
Y467879D01*
G01X1090972Y466382D02*
Y468356D01*
G01X1092122Y467879D02*
X1093080Y468837D01*
G01D02*
X1093896D01*
G01X1090972Y468356D02*
X1092603Y469987D01*
G01X1093080Y468837D02*
X1093896D01*
G01X1092603Y469987D02*
X1094373D01*
G01X1093896Y468837D02*
X1094687Y468046D01*
G01X1094373Y469987D02*
X1095164Y469196D01*
G01X1093896Y468837D02*
X1094687Y468046D01*
G01D02*
X1096713D01*
G01X1095164Y469196D02*
X1096236D01*
G01X1087220Y468850D02*
Y470391D01*
G01D02*
X1099351Y482522D01*
G01X1088370Y469914D02*
X1118400Y499944D01*
G01X1087220Y468850D02*
Y470391D01*
G01X1088370Y469914D02*
X1118400Y499944D01*
G01X1087220Y470391D02*
X1099351Y482522D01*
G01X1088370Y469914D02*
X1118400Y499944D01*
G01X1092963Y466018D02*
X1092122Y466859D01*
G01X1091813Y465541D02*
X1090972Y466382D01*
G01X1092122Y466859D02*
Y467879D01*
G01X1090972Y466382D02*
Y468356D01*
G01X1092122Y467879D02*
X1093080Y468837D01*
G01D02*
X1093896D01*
G01X1090972Y468356D02*
X1092603Y469987D01*
G01X1093080Y468837D02*
X1093896D01*
G01X1092603Y469987D02*
X1094373D01*
G01X1093896Y468837D02*
X1094687Y468046D01*
G01X1094373Y469987D02*
X1095164Y469196D01*
G01X1093896Y468837D02*
X1094687Y468046D01*
G01D02*
X1096713D01*
G01X1095164Y469196D02*
X1096236D01*
G01X1091813Y465541D02*
X1090972Y466382D01*
G01X1092963Y466018D02*
X1092122Y466859D01*
G01X1090972Y466382D02*
Y468356D01*
G01X1092122Y466859D02*
Y467879D01*
G01X1090972Y468356D02*
X1092603Y469987D01*
G01X1092122Y467879D02*
X1093080Y468837D01*
G01X1090972Y468356D02*
X1092603Y469987D01*
G01D02*
X1094373D01*
G01X1093080Y468837D02*
X1093896D01*
G01X1094373Y469987D02*
X1095164Y469196D01*
G01D02*
X1096236D01*
G01X1093896Y468837D02*
X1094687Y468046D01*
G01X1095164Y469196D02*
X1096236D01*
G01X1094687Y468046D02*
X1096713D01*
G01X1095164Y469196D02*
X1096236D01*
G01X1111750Y95151D02*
X1112450Y94451D01*
G01X1116870Y96657D02*
X1118927Y94600D01*
G01X1117645Y94255D02*
X1115720Y96180D01*
G01X1111750Y95151D02*
X1112450Y94451D01*
G01X1117645Y94255D02*
X1115720Y96180D01*
G01X1116870Y96657D02*
X1118927Y94600D01*
G01X1111750Y95151D02*
X1112450Y94451D01*
G01X1116870Y96657D02*
X1118927Y94600D01*
G01X1117645Y94255D02*
X1115720Y96180D01*
G01X1116870Y96657D02*
X1118927Y94600D01*
G01X1117645Y94255D02*
X1115720Y96180D01*
G01X1111750Y95151D02*
X1112450Y94451D01*
G01X1111750Y95151D02*
X1112450Y94451D01*
G01X1117645Y94255D02*
X1115720Y96180D01*
G01X1116870Y96657D02*
X1118927Y94600D01*
G01X1117645Y94255D02*
X1115720Y96180D01*
G01X1116870Y96657D02*
X1118927Y94600D01*
G01X1113428Y95100D02*
X1112900Y95628D01*
G01X1111750Y105350D02*
Y95151D01*
G01X1112900Y95628D02*
Y105827D01*
G01X1109100Y108000D02*
X1111750Y105350D01*
G01X1112900Y105827D02*
X1110250Y108477D01*
G01X1109100Y111026D02*
Y108000D01*
G01X1110250Y108477D02*
Y110549D01*
G01X1109900Y111826D02*
X1109100Y111026D01*
G01X1110250Y110549D02*
X1111050Y111349D01*
G01X1109900Y115000D02*
Y111826D01*
G01Y117646D02*
Y115000D01*
G01X1111050Y111349D02*
Y118123D01*
G01X1107172Y119382D02*
X1108164D01*
G01D02*
X1109900Y117646D01*
G01X1111050Y118123D02*
X1108641Y120532D01*
G01X1107172Y119382D02*
X1108164D01*
G01X1108641Y120532D02*
X1106695D01*
G01X1106832Y119042D02*
X1107172Y119382D01*
G01D02*
X1108164D01*
G01X1106695Y120532D02*
X1106355Y120192D01*
G01X1104886Y119042D02*
X1106832D01*
G01X1106355Y120192D02*
X1105363D01*
G01X1102737Y121191D02*
X1104886Y119042D01*
G01X1105363Y120192D02*
X1103887Y121668D01*
G01X1102737Y123137D02*
Y121191D01*
G01X1103887Y121668D02*
Y122660D01*
G01X1103077Y123477D02*
X1102737Y123137D01*
G01X1103887Y122660D02*
X1104227Y123000D01*
G01X1103077Y124469D02*
Y123477D01*
G01X1104227Y123000D02*
Y124946D01*
G01X1100607Y125947D02*
X1101599D01*
G01D02*
X1103077Y124469D01*
G01X1104227Y124946D02*
X1102076Y127097D01*
G01X1100607Y125947D02*
X1101599D01*
G01X1102076Y127097D02*
X1100130D01*
G01X1100267Y125607D02*
X1100607Y125947D01*
G01X1100130Y127097D02*
X1099790Y126757D01*
G01X1098321Y125607D02*
X1100267D01*
G01X1099790Y126757D02*
X1098798D01*
G01X1096172Y127756D02*
X1098321Y125607D01*
G01X1098798Y126757D02*
X1097322Y128233D01*
G01X1096172Y129702D02*
Y127756D01*
G01X1097322Y128233D02*
Y129225D01*
G01X1096512Y130042D02*
X1096172Y129702D01*
G01X1097322Y129225D02*
X1097662Y129565D01*
G01X1096512Y131034D02*
Y130042D01*
G01X1097662Y129565D02*
Y131511D01*
G01D02*
X1095511Y133662D01*
G01X1116870Y109000D02*
Y96657D01*
G01Y117785D02*
Y109000D01*
G01X1115720Y96180D02*
Y117308D01*
G01D02*
X1109228Y123800D01*
G01X1111050Y111349D02*
Y118123D01*
G01X1109900Y115000D02*
Y111826D01*
G01X1110250Y110549D02*
X1111050Y111349D01*
G01X1109900Y111826D02*
X1109100Y111026D01*
G01X1110250Y108477D02*
Y110549D01*
G01X1109100Y111026D02*
Y108000D01*
G01X1112900Y105827D02*
X1110250Y108477D01*
G01X1109100Y108000D02*
X1111750Y105350D01*
G01X1112900Y95628D02*
Y105827D01*
G01X1111750Y105350D02*
Y95151D01*
G01X1113428Y95100D02*
X1112900Y95628D01*
G01X1097662Y131511D02*
X1095511Y133662D01*
G01X1097662Y131511D02*
X1095511Y133662D01*
G01X1097662Y129565D02*
Y131511D01*
G01X1096512Y131034D02*
Y130042D01*
G01X1097322Y129225D02*
X1097662Y129565D01*
G01X1096512Y130042D02*
X1096172Y129702D01*
G01X1097322Y128233D02*
Y129225D01*
G01X1096172Y129702D02*
Y127756D01*
G01X1098798Y126757D02*
X1097322Y128233D01*
G01X1096172Y127756D02*
X1098321Y125607D01*
G01X1099790Y126757D02*
X1098798D01*
G01X1098321Y125607D02*
X1100267D01*
G01X1100130Y127097D02*
X1099790Y126757D01*
G01X1100267Y125607D02*
X1100607Y125947D01*
G01X1104227Y124946D02*
X1102076Y127097D01*
G01D02*
X1100130D01*
G01X1100607Y125947D02*
X1101599D01*
G01X1104227Y124946D02*
X1102076Y127097D01*
G01X1101599Y125947D02*
X1103077Y124469D01*
G01X1104227Y123000D02*
Y124946D01*
G01X1103077Y124469D02*
Y123477D01*
G01X1103887Y122660D02*
X1104227Y123000D01*
G01X1103077Y123477D02*
X1102737Y123137D01*
G01X1103887Y121668D02*
Y122660D01*
G01X1102737Y123137D02*
Y121191D01*
G01X1105363Y120192D02*
X1103887Y121668D01*
G01X1102737Y121191D02*
X1104886Y119042D01*
G01X1106355Y120192D02*
X1105363D01*
G01X1104886Y119042D02*
X1106832D01*
G01X1106695Y120532D02*
X1106355Y120192D01*
G01X1106832Y119042D02*
X1107172Y119382D01*
G01X1111050Y118123D02*
X1108641Y120532D01*
G01D02*
X1106695D01*
G01D02*
X1106355Y120192D01*
G01X1107172Y119382D02*
X1108164D01*
G01X1111050Y118123D02*
X1108641Y120532D01*
G01X1108164Y119382D02*
X1109900Y117646D01*
G01X1111050Y111349D02*
Y118123D01*
G01X1109900Y117646D02*
Y115000D01*
G01X1115720Y96180D02*
Y117308D01*
G01X1116870Y109000D02*
Y96657D01*
G01X1115720Y117308D02*
X1109228Y123800D01*
G01X1115720Y96180D02*
Y117308D01*
G01X1116870Y117785D02*
Y109000D01*
G01X1138102Y137698D02*
X1130300Y145500D01*
G01X1134363Y143064D02*
X1139252Y138175D01*
G01X1138102Y136778D02*
Y137698D01*
G01X1139252Y138175D02*
Y136301D01*
G01X1136992Y135668D02*
X1138102Y136778D01*
G01X1139252Y136301D02*
X1138142Y135191D01*
G01X1136992Y134008D02*
Y135668D01*
G01X1138142Y135191D02*
Y134485D01*
G01X1138835Y132165D02*
X1136992Y134008D01*
G01X1138142Y134485D02*
X1139312Y133315D01*
G01X1140495Y132165D02*
X1138835D01*
G01D02*
X1136992Y134008D01*
G01X1139312Y133315D02*
X1140018D01*
G01X1142525Y133275D02*
X1141605D01*
G01D02*
X1140495Y132165D01*
G01X1140018Y133315D02*
X1141128Y134425D01*
G01X1142525Y133275D02*
X1141605D01*
G01X1141128Y134425D02*
X1143002D01*
G01X1144773Y131027D02*
X1142525Y133275D01*
G01X1143002Y134425D02*
X1145923Y131504D01*
G01X1144773Y130107D02*
Y131027D01*
G01X1145923Y131504D02*
Y129630D01*
G01X1144200Y129534D02*
X1144773Y130107D01*
G01X1145923Y129630D02*
X1145350Y129057D01*
G01X1144200Y127272D02*
Y129534D01*
G01X1145350Y129057D02*
Y127749D01*
G01X1146422Y125050D02*
X1144200Y127272D01*
G01X1145350Y127749D02*
X1146899Y126200D01*
G01X1150200Y125050D02*
X1146422D01*
G01X1146899Y126200D02*
X1150677D01*
G01X1150700Y124550D02*
X1150200Y125050D01*
G01X1150677Y126200D02*
X1151850Y125027D01*
G01X1150700Y118799D02*
Y124550D01*
G01X1151850Y125027D02*
Y118322D01*
G01X1149377Y117476D02*
X1150700Y118799D01*
G01X1151850Y118322D02*
X1150527Y116999D01*
G01X1149377Y109666D02*
Y117476D01*
G01X1150527Y116999D02*
Y115573D01*
G01X1138102Y137698D02*
X1130300Y145500D01*
G01X1134363Y143064D02*
X1130777Y146650D01*
G01X1130300Y145500D02*
X1126399D01*
G01X1130777Y146650D02*
X1126876D01*
G01X1126399Y145500D02*
X1114012Y157887D01*
G01X1126876Y146650D02*
X1124143Y149383D01*
G01X1126399Y145500D02*
X1114012Y157887D01*
G01X1122728Y150798D02*
X1122021Y151505D01*
G01X1126399Y145500D02*
X1114012Y157887D01*
G01X1120605Y152921D02*
X1119406Y154120D01*
G01X1126399Y145500D02*
X1114012Y157887D01*
G01X1117991Y155535D02*
X1117284Y156242D01*
G01X1126399Y145500D02*
X1114012Y157887D01*
G01X1155612Y127087D02*
X1132049Y150650D01*
G01X1141231Y139841D02*
X1154462Y126610D01*
G01X1155612Y116287D02*
Y127087D01*
G01X1154462Y126610D02*
Y115180D01*
G01X1155612Y127087D02*
X1132049Y150650D01*
G01X1141231Y139841D02*
X1131572Y149500D01*
G01X1132049Y150650D02*
X1129677D01*
G01X1131572Y149500D02*
X1129200D01*
G01X1129677Y150650D02*
X1127950Y152377D01*
G01X1126535Y153792D02*
X1125828Y154499D01*
G01X1124413Y155914D02*
X1123706Y156621D01*
G01X1129200Y149500D02*
X1118312Y160388D01*
G01X1150527Y116999D02*
Y115573D01*
G01X1149377Y109666D02*
Y117476D01*
G01X1151850Y118322D02*
X1150527Y116999D01*
G01X1149377Y117476D02*
X1150700Y118799D01*
G01X1151850Y125027D02*
Y118322D01*
G01X1150700Y118799D02*
Y124550D01*
G01X1150677Y126200D02*
X1151850Y125027D01*
G01X1150700Y124550D02*
X1150200Y125050D01*
G01X1146899Y126200D02*
X1150677D01*
G01X1150200Y125050D02*
X1146422D01*
G01X1145350Y127749D02*
X1146899Y126200D01*
G01X1146422Y125050D02*
X1144200Y127272D01*
G01X1145350Y129057D02*
Y127749D01*
G01X1144200Y127272D02*
Y129534D01*
G01X1145923Y129630D02*
X1145350Y129057D01*
G01X1144200Y129534D02*
X1144773Y130107D01*
G01X1145923Y131504D02*
Y129630D01*
G01X1144773Y130107D02*
Y131027D01*
G01X1143002Y134425D02*
X1145923Y131504D01*
G01X1144773Y131027D02*
X1142525Y133275D01*
G01X1140018Y133315D02*
X1141128Y134425D01*
G01D02*
X1143002D01*
G01X1142525Y133275D02*
X1141605D01*
G01X1140018Y133315D02*
X1141128Y134425D01*
G01X1141605Y133275D02*
X1140495Y132165D01*
G01X1139312Y133315D02*
X1140018D01*
G01X1140495Y132165D02*
X1138835D01*
G01X1138142Y134485D02*
X1139312Y133315D01*
G01D02*
X1140018D01*
G01X1138835Y132165D02*
X1136992Y134008D01*
G01X1138142Y135191D02*
Y134485D01*
G01X1136992Y134008D02*
Y135668D01*
G01X1139252Y136301D02*
X1138142Y135191D01*
G01X1136992Y135668D02*
X1138102Y136778D01*
G01X1139252Y138175D02*
Y136301D01*
G01X1138102Y136778D02*
Y137698D01*
G01X1134363Y143064D02*
X1139252Y138175D01*
G01X1134363Y143064D02*
X1130777Y146650D01*
G01X1138102Y137698D02*
X1130300Y145500D01*
G01X1130777Y146650D02*
X1126876D01*
G01X1130300Y145500D02*
X1126399D01*
G01X1126876Y146650D02*
X1124143Y149383D01*
G01X1122728Y150798D02*
X1122021Y151505D01*
G01X1120605Y152921D02*
X1119406Y154120D01*
G01X1117991Y155535D02*
X1117284Y156242D01*
G01X1126399Y145500D02*
X1114012Y157887D01*
G01X1154462Y126610D02*
Y115180D01*
G01X1155612Y116287D02*
Y127087D01*
G01X1141231Y139841D02*
X1154462Y126610D01*
G01X1141231Y139841D02*
X1131572Y149500D01*
G01X1155612Y127087D02*
X1132049Y150650D01*
G01X1131572Y149500D02*
X1129200D01*
G01X1132049Y150650D02*
X1129677D01*
G01X1129200Y149500D02*
X1118312Y160388D01*
G01X1129677Y150650D02*
X1127950Y152377D01*
G01X1129200Y149500D02*
X1118312Y160388D01*
G01X1126535Y153792D02*
X1125828Y154499D01*
G01X1129200Y149500D02*
X1118312Y160388D01*
G01X1124413Y155914D02*
X1123706Y156621D01*
G01X1129200Y149500D02*
X1118312Y160388D01*
G01X1129200Y149500D02*
X1118312Y160388D01*
G01X1113428Y95100D02*
X1112900Y95628D01*
G01X1111750Y105350D02*
Y95151D01*
G01X1112900Y95628D02*
Y105827D01*
G01X1109100Y108000D02*
X1111750Y105350D01*
G01X1112900Y105827D02*
X1110250Y108477D01*
G01X1109100Y111026D02*
Y108000D01*
G01X1110250Y108477D02*
Y110549D01*
G01X1109900Y111826D02*
X1109100Y111026D01*
G01X1110250Y110549D02*
X1111050Y111349D01*
G01X1109900Y115000D02*
Y111826D01*
G01Y117646D02*
Y115000D01*
G01X1111050Y111349D02*
Y118123D01*
G01X1107172Y119382D02*
X1108164D01*
G01D02*
X1109900Y117646D01*
G01X1111050Y118123D02*
X1108641Y120532D01*
G01X1107172Y119382D02*
X1108164D01*
G01X1108641Y120532D02*
X1106695D01*
G01X1106832Y119042D02*
X1107172Y119382D01*
G01D02*
X1108164D01*
G01X1106695Y120532D02*
X1106355Y120192D01*
G01X1104886Y119042D02*
X1106832D01*
G01X1106355Y120192D02*
X1105363D01*
G01X1102737Y121191D02*
X1104886Y119042D01*
G01X1105363Y120192D02*
X1103887Y121668D01*
G01X1102737Y123137D02*
Y121191D01*
G01X1103887Y121668D02*
Y122660D01*
G01X1103077Y123477D02*
X1102737Y123137D01*
G01X1103887Y122660D02*
X1104227Y123000D01*
G01X1103077Y124469D02*
Y123477D01*
G01X1104227Y123000D02*
Y124946D01*
G01X1100607Y125947D02*
X1101599D01*
G01D02*
X1103077Y124469D01*
G01X1104227Y124946D02*
X1102076Y127097D01*
G01X1100607Y125947D02*
X1101599D01*
G01X1102076Y127097D02*
X1100130D01*
G01X1100267Y125607D02*
X1100607Y125947D01*
G01X1100130Y127097D02*
X1099790Y126757D01*
G01X1098321Y125607D02*
X1100267D01*
G01X1099790Y126757D02*
X1098798D01*
G01X1096172Y127756D02*
X1098321Y125607D01*
G01X1098798Y126757D02*
X1097322Y128233D01*
G01X1096172Y129702D02*
Y127756D01*
G01X1097322Y128233D02*
Y129225D01*
G01X1096512Y130042D02*
X1096172Y129702D01*
G01X1097322Y129225D02*
X1097662Y129565D01*
G01X1096512Y131034D02*
Y130042D01*
G01X1097662Y129565D02*
Y131511D01*
G01D02*
X1095511Y133662D01*
G01X1116870Y109000D02*
Y96657D01*
G01Y117785D02*
Y109000D01*
G01X1115720Y96180D02*
Y117308D01*
G01D02*
X1109228Y123800D01*
G01X1116870Y109000D02*
Y96657D01*
G01Y117785D02*
Y109000D01*
G01X1115720Y96180D02*
Y117308D01*
G01D02*
X1109228Y123800D01*
G01X1111050Y111349D02*
Y118123D01*
G01X1109900Y115000D02*
Y111826D01*
G01X1110250Y110549D02*
X1111050Y111349D01*
G01X1109900Y111826D02*
X1109100Y111026D01*
G01X1110250Y108477D02*
Y110549D01*
G01X1109100Y111026D02*
Y108000D01*
G01X1112900Y105827D02*
X1110250Y108477D01*
G01X1109100Y108000D02*
X1111750Y105350D01*
G01X1112900Y95628D02*
Y105827D01*
G01X1111750Y105350D02*
Y95151D01*
G01X1113428Y95100D02*
X1112900Y95628D01*
G01X1097662Y131511D02*
X1095511Y133662D01*
G01X1097662Y131511D02*
X1095511Y133662D01*
G01X1097662Y129565D02*
Y131511D01*
G01X1096512Y131034D02*
Y130042D01*
G01X1097322Y129225D02*
X1097662Y129565D01*
G01X1096512Y130042D02*
X1096172Y129702D01*
G01X1097322Y128233D02*
Y129225D01*
G01X1096172Y129702D02*
Y127756D01*
G01X1098798Y126757D02*
X1097322Y128233D01*
G01X1096172Y127756D02*
X1098321Y125607D01*
G01X1099790Y126757D02*
X1098798D01*
G01X1098321Y125607D02*
X1100267D01*
G01X1100130Y127097D02*
X1099790Y126757D01*
G01X1100267Y125607D02*
X1100607Y125947D01*
G01X1104227Y124946D02*
X1102076Y127097D01*
G01D02*
X1100130D01*
G01X1100607Y125947D02*
X1101599D01*
G01X1104227Y124946D02*
X1102076Y127097D01*
G01X1101599Y125947D02*
X1103077Y124469D01*
G01X1104227Y123000D02*
Y124946D01*
G01X1103077Y124469D02*
Y123477D01*
G01X1103887Y122660D02*
X1104227Y123000D01*
G01X1103077Y123477D02*
X1102737Y123137D01*
G01X1103887Y121668D02*
Y122660D01*
G01X1102737Y123137D02*
Y121191D01*
G01X1105363Y120192D02*
X1103887Y121668D01*
G01X1102737Y121191D02*
X1104886Y119042D01*
G01X1106355Y120192D02*
X1105363D01*
G01X1104886Y119042D02*
X1106832D01*
G01X1106695Y120532D02*
X1106355Y120192D01*
G01X1106832Y119042D02*
X1107172Y119382D01*
G01X1111050Y118123D02*
X1108641Y120532D01*
G01D02*
X1106695D01*
G01D02*
X1106355Y120192D01*
G01X1107172Y119382D02*
X1108164D01*
G01X1111050Y118123D02*
X1108641Y120532D01*
G01X1108164Y119382D02*
X1109900Y117646D01*
G01X1111050Y111349D02*
Y118123D01*
G01X1109900Y117646D02*
Y115000D01*
G01X1111050Y111349D02*
Y118123D01*
G01X1109900Y115000D02*
Y111826D01*
G01X1110250Y110549D02*
X1111050Y111349D01*
G01X1109900Y111826D02*
X1109100Y111026D01*
G01X1110250Y108477D02*
Y110549D01*
G01X1109100Y111026D02*
Y108000D01*
G01X1112900Y105827D02*
X1110250Y108477D01*
G01X1109100Y108000D02*
X1111750Y105350D01*
G01X1112900Y95628D02*
Y105827D01*
G01X1111750Y105350D02*
Y95151D01*
G01X1113428Y95100D02*
X1112900Y95628D01*
G01X1097662Y131511D02*
X1095511Y133662D01*
G01X1097662Y131511D02*
X1095511Y133662D01*
G01X1097662Y129565D02*
Y131511D01*
G01X1096512Y131034D02*
Y130042D01*
G01X1097322Y129225D02*
X1097662Y129565D01*
G01X1096512Y130042D02*
X1096172Y129702D01*
G01X1097322Y128233D02*
Y129225D01*
G01X1096172Y129702D02*
Y127756D01*
G01X1098798Y126757D02*
X1097322Y128233D01*
G01X1096172Y127756D02*
X1098321Y125607D01*
G01X1099790Y126757D02*
X1098798D01*
G01X1098321Y125607D02*
X1100267D01*
G01X1100130Y127097D02*
X1099790Y126757D01*
G01X1100267Y125607D02*
X1100607Y125947D01*
G01X1104227Y124946D02*
X1102076Y127097D01*
G01D02*
X1100130D01*
G01X1100607Y125947D02*
X1101599D01*
G01X1104227Y124946D02*
X1102076Y127097D01*
G01X1101599Y125947D02*
X1103077Y124469D01*
G01X1104227Y123000D02*
Y124946D01*
G01X1103077Y124469D02*
Y123477D01*
G01X1103887Y122660D02*
X1104227Y123000D01*
G01X1103077Y123477D02*
X1102737Y123137D01*
G01X1103887Y121668D02*
Y122660D01*
G01X1102737Y123137D02*
Y121191D01*
G01X1105363Y120192D02*
X1103887Y121668D01*
G01X1102737Y121191D02*
X1104886Y119042D01*
G01X1106355Y120192D02*
X1105363D01*
G01X1104886Y119042D02*
X1106832D01*
G01X1106695Y120532D02*
X1106355Y120192D01*
G01X1106832Y119042D02*
X1107172Y119382D01*
G01X1111050Y118123D02*
X1108641Y120532D01*
G01D02*
X1106695D01*
G01D02*
X1106355Y120192D01*
G01X1107172Y119382D02*
X1108164D01*
G01X1111050Y118123D02*
X1108641Y120532D01*
G01X1108164Y119382D02*
X1109900Y117646D01*
G01X1111050Y111349D02*
Y118123D01*
G01X1109900Y117646D02*
Y115000D01*
G01X1115720Y96180D02*
Y117308D01*
G01X1116870Y109000D02*
Y96657D01*
G01X1115720Y117308D02*
X1109228Y123800D01*
G01X1115720Y96180D02*
Y117308D01*
G01X1116870Y117785D02*
Y109000D01*
G01X1115720Y96180D02*
Y117308D01*
G01X1116870Y109000D02*
Y96657D01*
G01X1115720Y117308D02*
X1109228Y123800D01*
G01X1115720Y96180D02*
Y117308D01*
G01X1116870Y117785D02*
Y109000D01*
G01X1138102Y137698D02*
X1130300Y145500D01*
G01X1134363Y143064D02*
X1139252Y138175D01*
G01X1138102Y136778D02*
Y137698D01*
G01X1139252Y138175D02*
Y136301D01*
G01X1136992Y135668D02*
X1138102Y136778D01*
G01X1139252Y136301D02*
X1138142Y135191D01*
G01X1136992Y134008D02*
Y135668D01*
G01X1138142Y135191D02*
Y134485D01*
G01X1138835Y132165D02*
X1136992Y134008D01*
G01X1138142Y134485D02*
X1139312Y133315D01*
G01X1140495Y132165D02*
X1138835D01*
G01D02*
X1136992Y134008D01*
G01X1139312Y133315D02*
X1140018D01*
G01X1142525Y133275D02*
X1141605D01*
G01D02*
X1140495Y132165D01*
G01X1140018Y133315D02*
X1141128Y134425D01*
G01X1142525Y133275D02*
X1141605D01*
G01X1141128Y134425D02*
X1143002D01*
G01X1144773Y131027D02*
X1142525Y133275D01*
G01X1143002Y134425D02*
X1145923Y131504D01*
G01X1144773Y130107D02*
Y131027D01*
G01X1145923Y131504D02*
Y129630D01*
G01X1144200Y129534D02*
X1144773Y130107D01*
G01X1145923Y129630D02*
X1145350Y129057D01*
G01X1144200Y127272D02*
Y129534D01*
G01X1145350Y129057D02*
Y127749D01*
G01X1146422Y125050D02*
X1144200Y127272D01*
G01X1145350Y127749D02*
X1146899Y126200D01*
G01X1150200Y125050D02*
X1146422D01*
G01X1146899Y126200D02*
X1150677D01*
G01X1150700Y124550D02*
X1150200Y125050D01*
G01X1150677Y126200D02*
X1151850Y125027D01*
G01X1150700Y118799D02*
Y124550D01*
G01X1151850Y125027D02*
Y118322D01*
G01X1149377Y117476D02*
X1150700Y118799D01*
G01X1151850Y118322D02*
X1150527Y116999D01*
G01X1149377Y109666D02*
Y117476D01*
G01X1150527Y116999D02*
Y115573D01*
G01X1138102Y137698D02*
X1130300Y145500D01*
G01X1134363Y143064D02*
X1130777Y146650D01*
G01X1130300Y145500D02*
X1126399D01*
G01X1130777Y146650D02*
X1126876D01*
G01X1126399Y145500D02*
X1114012Y157887D01*
G01X1126876Y146650D02*
X1124143Y149383D01*
G01X1126399Y145500D02*
X1114012Y157887D01*
G01X1122728Y150798D02*
X1122021Y151505D01*
G01X1126399Y145500D02*
X1114012Y157887D01*
G01X1120605Y152921D02*
X1119406Y154120D01*
G01X1126399Y145500D02*
X1114012Y157887D01*
G01X1117991Y155535D02*
X1117284Y156242D01*
G01X1126399Y145500D02*
X1114012Y157887D01*
G01X1138102Y137698D02*
X1130300Y145500D01*
G01X1134363Y143064D02*
X1139252Y138175D01*
G01X1138102Y136778D02*
Y137698D01*
G01X1139252Y138175D02*
Y136301D01*
G01X1136992Y135668D02*
X1138102Y136778D01*
G01X1139252Y136301D02*
X1138142Y135191D01*
G01X1136992Y134008D02*
Y135668D01*
G01X1138142Y135191D02*
Y134485D01*
G01X1138835Y132165D02*
X1136992Y134008D01*
G01X1138142Y134485D02*
X1139312Y133315D01*
G01X1140495Y132165D02*
X1138835D01*
G01D02*
X1136992Y134008D01*
G01X1139312Y133315D02*
X1140018D01*
G01X1142525Y133275D02*
X1141605D01*
G01D02*
X1140495Y132165D01*
G01X1140018Y133315D02*
X1141128Y134425D01*
G01X1142525Y133275D02*
X1141605D01*
G01X1141128Y134425D02*
X1143002D01*
G01X1144773Y131027D02*
X1142525Y133275D01*
G01X1143002Y134425D02*
X1145923Y131504D01*
G01X1144773Y130107D02*
Y131027D01*
G01X1145923Y131504D02*
Y129630D01*
G01X1144200Y129534D02*
X1144773Y130107D01*
G01X1145923Y129630D02*
X1145350Y129057D01*
G01X1144200Y127272D02*
Y129534D01*
G01X1145350Y129057D02*
Y127749D01*
G01X1146422Y125050D02*
X1144200Y127272D01*
G01X1145350Y127749D02*
X1146899Y126200D01*
G01X1150200Y125050D02*
X1146422D01*
G01X1146899Y126200D02*
X1150677D01*
G01X1150700Y124550D02*
X1150200Y125050D01*
G01X1150677Y126200D02*
X1151850Y125027D01*
G01X1150700Y118799D02*
Y124550D01*
G01X1151850Y125027D02*
Y118322D01*
G01X1149377Y117476D02*
X1150700Y118799D01*
G01X1151850Y118322D02*
X1150527Y116999D01*
G01X1149377Y109666D02*
Y117476D01*
G01X1150527Y116999D02*
Y115573D01*
G01X1138102Y137698D02*
X1130300Y145500D01*
G01X1134363Y143064D02*
X1130777Y146650D01*
G01X1130300Y145500D02*
X1126399D01*
G01X1130777Y146650D02*
X1126876D01*
G01X1126399Y145500D02*
X1114012Y157887D01*
G01X1126876Y146650D02*
X1124143Y149383D01*
G01X1126399Y145500D02*
X1114012Y157887D01*
G01X1122728Y150798D02*
X1122021Y151505D01*
G01X1126399Y145500D02*
X1114012Y157887D01*
G01X1120605Y152921D02*
X1119406Y154120D01*
G01X1126399Y145500D02*
X1114012Y157887D01*
G01X1117991Y155535D02*
X1117284Y156242D01*
G01X1126399Y145500D02*
X1114012Y157887D01*
G01X1155612Y127087D02*
X1132049Y150650D01*
G01X1141231Y139841D02*
X1154462Y126610D01*
G01X1155612Y116287D02*
Y127087D01*
G01X1154462Y126610D02*
Y115180D01*
G01X1155612Y127087D02*
X1132049Y150650D01*
G01X1141231Y139841D02*
X1131572Y149500D01*
G01X1132049Y150650D02*
X1129677D01*
G01X1131572Y149500D02*
X1129200D01*
G01X1129677Y150650D02*
X1127950Y152377D01*
G01X1126535Y153792D02*
X1125828Y154499D01*
G01X1124413Y155914D02*
X1123706Y156621D01*
G01X1129200Y149500D02*
X1118312Y160388D01*
G01X1155612Y127087D02*
X1132049Y150650D01*
G01X1141231Y139841D02*
X1154462Y126610D01*
G01X1155612Y116287D02*
Y127087D01*
G01X1154462Y126610D02*
Y115180D01*
G01X1155612Y127087D02*
X1132049Y150650D01*
G01X1141231Y139841D02*
X1131572Y149500D01*
G01X1132049Y150650D02*
X1129677D01*
G01X1131572Y149500D02*
X1129200D01*
G01X1129677Y150650D02*
X1127950Y152377D01*
G01X1126535Y153792D02*
X1125828Y154499D01*
G01X1124413Y155914D02*
X1123706Y156621D01*
G01X1129200Y149500D02*
X1118312Y160388D01*
G01X1150527Y116999D02*
Y115573D01*
G01X1149377Y109666D02*
Y117476D01*
G01X1151850Y118322D02*
X1150527Y116999D01*
G01X1149377Y117476D02*
X1150700Y118799D01*
G01X1151850Y125027D02*
Y118322D01*
G01X1150700Y118799D02*
Y124550D01*
G01X1150677Y126200D02*
X1151850Y125027D01*
G01X1150700Y124550D02*
X1150200Y125050D01*
G01X1146899Y126200D02*
X1150677D01*
G01X1150200Y125050D02*
X1146422D01*
G01X1145350Y127749D02*
X1146899Y126200D01*
G01X1146422Y125050D02*
X1144200Y127272D01*
G01X1145350Y129057D02*
Y127749D01*
G01X1144200Y127272D02*
Y129534D01*
G01X1145923Y129630D02*
X1145350Y129057D01*
G01X1144200Y129534D02*
X1144773Y130107D01*
G01X1145923Y131504D02*
Y129630D01*
G01X1144773Y130107D02*
Y131027D01*
G01X1143002Y134425D02*
X1145923Y131504D01*
G01X1144773Y131027D02*
X1142525Y133275D01*
G01X1140018Y133315D02*
X1141128Y134425D01*
G01D02*
X1143002D01*
G01X1142525Y133275D02*
X1141605D01*
G01X1140018Y133315D02*
X1141128Y134425D01*
G01X1141605Y133275D02*
X1140495Y132165D01*
G01X1139312Y133315D02*
X1140018D01*
G01X1140495Y132165D02*
X1138835D01*
G01X1138142Y134485D02*
X1139312Y133315D01*
G01D02*
X1140018D01*
G01X1138835Y132165D02*
X1136992Y134008D01*
G01X1138142Y135191D02*
Y134485D01*
G01X1136992Y134008D02*
Y135668D01*
G01X1139252Y136301D02*
X1138142Y135191D01*
G01X1136992Y135668D02*
X1138102Y136778D01*
G01X1139252Y138175D02*
Y136301D01*
G01X1138102Y136778D02*
Y137698D01*
G01X1134363Y143064D02*
X1139252Y138175D01*
G01X1134363Y143064D02*
X1130777Y146650D01*
G01X1138102Y137698D02*
X1130300Y145500D01*
G01X1130777Y146650D02*
X1126876D01*
G01X1130300Y145500D02*
X1126399D01*
G01X1126876Y146650D02*
X1124143Y149383D01*
G01X1122728Y150798D02*
X1122021Y151505D01*
G01X1120605Y152921D02*
X1119406Y154120D01*
G01X1117991Y155535D02*
X1117284Y156242D01*
G01X1126399Y145500D02*
X1114012Y157887D01*
G01X1154462Y126610D02*
Y115180D01*
G01X1155612Y116287D02*
Y127087D01*
G01X1141231Y139841D02*
X1154462Y126610D01*
G01X1141231Y139841D02*
X1131572Y149500D01*
G01X1155612Y127087D02*
X1132049Y150650D01*
G01X1131572Y149500D02*
X1129200D01*
G01X1132049Y150650D02*
X1129677D01*
G01X1129200Y149500D02*
X1118312Y160388D01*
G01X1129677Y150650D02*
X1127950Y152377D01*
G01X1129200Y149500D02*
X1118312Y160388D01*
G01X1126535Y153792D02*
X1125828Y154499D01*
G01X1129200Y149500D02*
X1118312Y160388D01*
G01X1124413Y155914D02*
X1123706Y156621D01*
G01X1129200Y149500D02*
X1118312Y160388D01*
G01X1129200Y149500D02*
X1118312Y160388D01*
G01X1115869Y157657D02*
X1115162Y158364D01*
G01X1114012Y157887D02*
Y161600D01*
G01X1115162Y158364D02*
Y161600D01*
G01X1122291Y158036D02*
X1121584Y158743D01*
G01X1120169Y160158D02*
X1119462Y160865D01*
G01D02*
Y161700D01*
G01X1118312Y160388D02*
Y161700D01*
G01X1115869Y157657D02*
X1115162Y158364D01*
G01D02*
Y161600D01*
G01X1114012Y157887D02*
Y161600D01*
G01X1122291Y158036D02*
X1121584Y158743D01*
G01X1120169Y160158D02*
X1119462Y160865D01*
G01X1118312Y160388D02*
Y161700D01*
G01X1119462Y160865D02*
Y161700D01*
G01X1115869Y157657D02*
X1115162Y158364D01*
G01X1114012Y157887D02*
Y161600D01*
G01X1115162Y158364D02*
Y161600D01*
G01X1115869Y157657D02*
X1115162Y158364D01*
G01X1114012Y157887D02*
Y161600D01*
G01X1115162Y158364D02*
Y161600D01*
G01X1122291Y158036D02*
X1121584Y158743D01*
G01X1120169Y160158D02*
X1119462Y160865D01*
G01D02*
Y161700D01*
G01X1118312Y160388D02*
Y161700D01*
G01X1122291Y158036D02*
X1121584Y158743D01*
G01X1120169Y160158D02*
X1119462Y160865D01*
G01D02*
Y161700D01*
G01X1118312Y160388D02*
Y161700D01*
G01X1115869Y157657D02*
X1115162Y158364D01*
G01D02*
Y161600D01*
G01X1114012Y157887D02*
Y161600D01*
G01X1122291Y158036D02*
X1121584Y158743D01*
G01X1120169Y160158D02*
X1119462Y160865D01*
G01X1118312Y160388D02*
Y161700D01*
G01X1119462Y160865D02*
Y161700D01*
G01X1123748Y451748D02*
X1141970Y469970D01*
G01X1124561Y450934D02*
X1142447Y468820D01*
G01X1123748Y451748D02*
X1141970Y469970D01*
G01X1124561Y450934D02*
X1142447Y468820D01*
G01X1123748Y451748D02*
X1141970Y469970D01*
G01X1125873Y447400D02*
X1126367Y447895D01*
G01X1127570Y449098D02*
X1128064Y449592D01*
G01X1129268Y450796D02*
X1129762Y451290D01*
G01X1130965Y452494D02*
X1131459Y452988D01*
G01X1132663Y454192D02*
X1133157Y454686D01*
G01X1134361Y455890D02*
X1134855Y456384D01*
G01X1136059Y457588D02*
X1136553Y458082D01*
G01X1137757Y459286D02*
X1138251Y459780D01*
G01X1139455Y460984D02*
X1139949Y461478D01*
G01X1141155Y462682D02*
X1141649Y463176D01*
G01X1142853Y464380D02*
X1143823Y465350D01*
G01X1126600Y446500D02*
X1144300Y464200D01*
G01D02*
X1147700D01*
G01D02*
X1157893Y474393D01*
G01X1126600Y446500D02*
X1144300Y464200D01*
G01X1125873Y447400D02*
X1126367Y447895D01*
G01X1126600Y446500D02*
X1144300Y464200D01*
G01X1127570Y449098D02*
X1128064Y449592D01*
G01X1126600Y446500D02*
X1144300Y464200D01*
G01X1129268Y450796D02*
X1129762Y451290D01*
G01X1126600Y446500D02*
X1144300Y464200D01*
G01X1130965Y452494D02*
X1131459Y452988D01*
G01X1126600Y446500D02*
X1144300Y464200D01*
G01X1132663Y454192D02*
X1133157Y454686D01*
G01X1126600Y446500D02*
X1144300Y464200D01*
G01X1134361Y455890D02*
X1134855Y456384D01*
G01X1126600Y446500D02*
X1144300Y464200D01*
G01X1136059Y457588D02*
X1136553Y458082D01*
G01X1126600Y446500D02*
X1144300Y464200D01*
G01X1137757Y459286D02*
X1138251Y459780D01*
G01X1126600Y446500D02*
X1144300Y464200D01*
G01X1139455Y460984D02*
X1139949Y461478D01*
G01X1126600Y446500D02*
X1144300Y464200D01*
G01X1141155Y462682D02*
X1141649Y463176D01*
G01X1126600Y446500D02*
X1144300Y464200D01*
G01X1142853Y464380D02*
X1143823Y465350D01*
G01X1144300Y464200D02*
X1147700D01*
G01D02*
X1157893Y474393D01*
G01X1147700Y464200D02*
X1157893Y474393D01*
G01X1147700Y464200D02*
X1157893Y474393D01*
G01X1147700Y464200D02*
X1157893Y474393D01*
G01X1123748Y451748D02*
X1141970Y469970D01*
G01X1124561Y450934D02*
X1142447Y468820D01*
G01X1123748Y451748D02*
X1141970Y469970D01*
G01X1126600Y446500D02*
X1144300Y464200D01*
G01X1125873Y447400D02*
X1126367Y447895D01*
G01X1126600Y446500D02*
X1144300Y464200D01*
G01X1127570Y449098D02*
X1128064Y449592D01*
G01X1126600Y446500D02*
X1144300Y464200D01*
G01X1129268Y450796D02*
X1129762Y451290D01*
G01X1126600Y446500D02*
X1144300Y464200D01*
G01X1130965Y452494D02*
X1131459Y452988D01*
G01X1126600Y446500D02*
X1144300Y464200D01*
G01X1132663Y454192D02*
X1133157Y454686D01*
G01X1126600Y446500D02*
X1144300Y464200D01*
G01X1134361Y455890D02*
X1134855Y456384D01*
G01X1126600Y446500D02*
X1144300Y464200D01*
G01X1136059Y457588D02*
X1136553Y458082D01*
G01X1126600Y446500D02*
X1144300Y464200D01*
G01X1137757Y459286D02*
X1138251Y459780D01*
G01X1126600Y446500D02*
X1144300Y464200D01*
G01X1139455Y460984D02*
X1139949Y461478D01*
G01X1126600Y446500D02*
X1144300Y464200D01*
G01X1141155Y462682D02*
X1141649Y463176D01*
G01X1126600Y446500D02*
X1144300Y464200D01*
G01X1142853Y464380D02*
X1143823Y465350D01*
G01X1144300Y464200D02*
X1147700D01*
G01D02*
X1157893Y474393D01*
G01X1147700Y464200D02*
X1157893Y474393D01*
G01X1147700Y464200D02*
X1157893Y474393D01*
G01X1147700Y464200D02*
X1157893Y474393D01*
G01X1124561Y450934D02*
X1142447Y468820D01*
G01X1123748Y451748D02*
X1141970Y469970D01*
G01X1125873Y447400D02*
X1126367Y447895D01*
G01X1127570Y449098D02*
X1128064Y449592D01*
G01X1129268Y450796D02*
X1129762Y451290D01*
G01X1130965Y452494D02*
X1131459Y452988D01*
G01X1132663Y454192D02*
X1133157Y454686D01*
G01X1134361Y455890D02*
X1134855Y456384D01*
G01X1136059Y457588D02*
X1136553Y458082D01*
G01X1137757Y459286D02*
X1138251Y459780D01*
G01X1139455Y460984D02*
X1139949Y461478D01*
G01X1141155Y462682D02*
X1141649Y463176D01*
G01X1142853Y464380D02*
X1143823Y465350D01*
G01X1126600Y446500D02*
X1144300Y464200D01*
G01D02*
X1147700D01*
G01D02*
X1157893Y474393D01*
G01X1100978Y484149D02*
X1117250Y500421D01*
G01D02*
Y501523D01*
G01X1118400Y499944D02*
Y502000D01*
G01X1117250Y501523D02*
X1116500Y502273D01*
G01X1118400Y502000D02*
X1117650Y502750D01*
G01X1116500Y502273D02*
Y505527D01*
G01X1117650Y502750D02*
Y505050D01*
G01X1116500Y505527D02*
X1117250Y506277D01*
G01X1117650Y505050D02*
X1118400Y505800D01*
G01X1117250Y506277D02*
Y510851D01*
G01X1118400Y505800D02*
Y511328D01*
G01X1117250Y510851D02*
X1115401Y512700D01*
G01X1118400Y511328D02*
X1114428Y515300D01*
G01X1100978Y484149D02*
X1117250Y500421D01*
G01X1118400Y499944D02*
Y502000D01*
G01X1117250Y500421D02*
Y501523D01*
G01X1118400Y502000D02*
X1117650Y502750D01*
G01X1117250Y501523D02*
X1116500Y502273D01*
G01X1117650Y502750D02*
Y505050D01*
G01X1116500Y502273D02*
Y505527D01*
G01X1117650Y505050D02*
X1118400Y505800D01*
G01X1116500Y505527D02*
X1117250Y506277D01*
G01X1118400Y505800D02*
Y511328D01*
G01X1117250Y506277D02*
Y510851D01*
G01X1118400Y511328D02*
X1114428Y515300D01*
G01X1117250Y510851D02*
X1115401Y512700D01*
G01X1096236Y469196D02*
X1097583Y470543D01*
G01X1096713Y468046D02*
X1098733Y470066D01*
G01X1097583Y470543D02*
Y471782D01*
G01X1098733Y470066D02*
Y472259D01*
G01X1097583Y471782D02*
X1096845Y472520D01*
G01X1098733Y472259D02*
X1097995Y472997D01*
G01X1096845Y472520D02*
Y474466D01*
G01X1097995Y472997D02*
Y473989D01*
G01X1096845Y474466D02*
X1098742Y476363D01*
G01X1097995Y473989D02*
X1099219Y475213D01*
G01X1098742Y476363D02*
X1100839D01*
G01D02*
X1101727Y475475D01*
G01X1099219Y475213D02*
X1100362D01*
G01X1100839Y476363D02*
X1101727Y475475D01*
G01X1100362Y475213D02*
X1101250Y474325D01*
G01X1101727Y475475D02*
X1102518D01*
G01X1101250Y474325D02*
X1102995D01*
G01X1102518Y475475D02*
X1103643Y476600D01*
G01X1102995Y474325D02*
X1104793Y476123D01*
G01X1103643Y476600D02*
Y477592D01*
G01X1104793Y476123D02*
Y478069D01*
G01X1103643Y477592D02*
X1103065Y478170D01*
G01X1104793Y478069D02*
X1104215Y478647D01*
G01X1103065Y478170D02*
Y480136D01*
G01X1104215Y478647D02*
Y479659D01*
G01X1103065Y480136D02*
X1105229Y482300D01*
G01X1105937Y483885D02*
X1106814D01*
G01D02*
X1107521Y484592D01*
G01X1108228Y486176D02*
X1109105D01*
G01D02*
X1109900Y486971D01*
G01X1110608Y488556D02*
X1111485D01*
G01D02*
X1112192Y489263D01*
G01X1112900Y490848D02*
X1113777D01*
G01D02*
X1114484Y491555D01*
G01X1115192Y493140D02*
X1116069D01*
G01D02*
X1116776Y493847D01*
G01X1117484Y495432D02*
X1118361D01*
G01D02*
X1119068Y496139D01*
G01X1119776Y497724D02*
X1120653D01*
G01D02*
X1121360Y498431D01*
G01X1104215Y479659D02*
X1122510Y497954D01*
G01X1121360Y498431D02*
Y499577D01*
G01Y501577D02*
Y502577D01*
G01Y504577D02*
Y505577D01*
G01Y507577D02*
Y508577D01*
G01Y510577D02*
Y511968D01*
G01X1122510Y497954D02*
Y512445D01*
G01X1121360Y511968D02*
X1120414Y512914D01*
G01X1122510Y512445D02*
X1119441Y515514D01*
G01X1096713Y468046D02*
X1098733Y470066D01*
G01X1096713Y468046D02*
X1098733Y470066D01*
G01X1096236Y469196D02*
X1097583Y470543D01*
G01X1098733Y470066D02*
Y472259D01*
G01X1097583Y470543D02*
Y471782D01*
G01X1098733Y472259D02*
X1097995Y472997D01*
G01X1097583Y471782D02*
X1096845Y472520D01*
G01X1097995Y472997D02*
Y473989D01*
G01X1096845Y472520D02*
Y474466D01*
G01X1097995Y473989D02*
X1099219Y475213D01*
G01X1096845Y474466D02*
X1098742Y476363D01*
G01X1099219Y475213D02*
X1100362D01*
G01X1098742Y476363D02*
X1100839D01*
G01X1099219Y475213D02*
X1100362D01*
G01D02*
X1101250Y474325D01*
G01X1100839Y476363D02*
X1101727Y475475D01*
G01X1101250Y474325D02*
X1102995D01*
G01X1101727Y475475D02*
X1102518D01*
G01X1102995Y474325D02*
X1104793Y476123D01*
G01X1102518Y475475D02*
X1103643Y476600D01*
G01X1104793Y476123D02*
Y478069D01*
G01X1103643Y476600D02*
Y477592D01*
G01X1104793Y478069D02*
X1104215Y478647D01*
G01X1103643Y477592D02*
X1103065Y478170D01*
G01X1104215Y478647D02*
Y479659D01*
G01X1103065Y478170D02*
Y480136D01*
G01X1104215Y479659D02*
X1122510Y497954D01*
G01X1103065Y480136D02*
X1105229Y482300D01*
G01X1104215Y479659D02*
X1122510Y497954D01*
G01X1105937Y483885D02*
X1106814D01*
G01X1104215Y479659D02*
X1122510Y497954D01*
G01X1106814Y483885D02*
X1107521Y484592D01*
G01X1104215Y479659D02*
X1122510Y497954D01*
G01X1108228Y486176D02*
X1109105D01*
G01X1104215Y479659D02*
X1122510Y497954D01*
G01X1109105Y486176D02*
X1109900Y486971D01*
G01X1104215Y479659D02*
X1122510Y497954D01*
G01X1110608Y488556D02*
X1111485D01*
G01X1104215Y479659D02*
X1122510Y497954D01*
G01X1111485Y488556D02*
X1112192Y489263D01*
G01X1104215Y479659D02*
X1122510Y497954D01*
G01X1112900Y490848D02*
X1113777D01*
G01X1104215Y479659D02*
X1122510Y497954D01*
G01X1113777Y490848D02*
X1114484Y491555D01*
G01X1104215Y479659D02*
X1122510Y497954D01*
G01X1115192Y493140D02*
X1116069D01*
G01X1104215Y479659D02*
X1122510Y497954D01*
G01X1116069Y493140D02*
X1116776Y493847D01*
G01X1104215Y479659D02*
X1122510Y497954D01*
G01X1117484Y495432D02*
X1118361D01*
G01X1104215Y479659D02*
X1122510Y497954D01*
G01X1118361Y495432D02*
X1119068Y496139D01*
G01X1104215Y479659D02*
X1122510Y497954D01*
G01X1119776Y497724D02*
X1120653D01*
G01X1104215Y479659D02*
X1122510Y497954D01*
G01X1120653Y497724D02*
X1121360Y498431D01*
G01X1122510Y497954D02*
Y512445D01*
G01X1121360Y498431D02*
Y499577D01*
G01X1122510Y497954D02*
Y512445D01*
G01X1121360Y501577D02*
Y502577D01*
G01X1122510Y497954D02*
Y512445D01*
G01X1121360Y504577D02*
Y505577D01*
G01X1122510Y497954D02*
Y512445D01*
G01X1121360Y507577D02*
Y508577D01*
G01X1122510Y497954D02*
Y512445D01*
G01X1121360Y510577D02*
Y511968D01*
G01X1122510Y512445D02*
X1119441Y515514D01*
G01X1121360Y511968D02*
X1120414Y512914D01*
G01X1141970Y469970D02*
X1143843D01*
G01X1142447Y468820D02*
X1144320D01*
G01X1143843Y469970D02*
X1145000Y471127D01*
G01X1146773Y472900D02*
X1147700Y473827D01*
G01X1149373Y475500D02*
X1150600Y476727D01*
G01X1152239Y478366D02*
X1153030Y479157D01*
G01X1144320Y468820D02*
X1154180Y478680D01*
G01X1153030Y479157D02*
Y492823D01*
G01X1154180Y478680D02*
Y493300D01*
G01X1153030Y492823D02*
X1152386Y493467D01*
G01X1154180Y493300D02*
X1152863Y494617D01*
G01X1142447Y468820D02*
X1144320D01*
G01X1142447D02*
X1144320D01*
G01X1141970Y469970D02*
X1143843D01*
G01X1144320Y468820D02*
X1154180Y478680D01*
G01X1143843Y469970D02*
X1145000Y471127D01*
G01X1144320Y468820D02*
X1154180Y478680D01*
G01X1146773Y472900D02*
X1147700Y473827D01*
G01X1144320Y468820D02*
X1154180Y478680D01*
G01X1149373Y475500D02*
X1150600Y476727D01*
G01X1144320Y468820D02*
X1154180Y478680D01*
G01X1152239Y478366D02*
X1153030Y479157D01*
G01X1154180Y478680D02*
Y493300D01*
G01X1153030Y479157D02*
Y492823D01*
G01X1154180Y493300D02*
X1152863Y494617D01*
G01X1153030Y492823D02*
X1152386Y493467D01*
G01X1143823Y465350D02*
X1147223D01*
G01D02*
X1148000Y466127D01*
G01X1149573Y467700D02*
X1150400Y468527D01*
G01X1151973Y470100D02*
X1152800Y470927D01*
G01X1154373Y472500D02*
X1156743Y474870D01*
G01D02*
Y475856D01*
G01Y477644D02*
Y480457D01*
G01D02*
X1158195Y481909D01*
G01X1158199Y485159D02*
X1156950Y486408D01*
G01Y488577D02*
X1158224Y489851D01*
G01X1159374Y493045D02*
X1156252Y496167D01*
G01X1143823Y465350D02*
X1147223D01*
G01D02*
X1148000Y466127D01*
G01X1149573Y467700D02*
X1150400Y468527D01*
G01X1151973Y470100D02*
X1152800Y470927D01*
G01X1154373Y472500D02*
X1156743Y474870D01*
G01D02*
Y475856D01*
G01Y477644D02*
Y480457D01*
G01D02*
X1158195Y481909D01*
G01X1158199Y485159D02*
X1156950Y486408D01*
G01Y488577D02*
X1158224Y489851D01*
G01X1159374Y493045D02*
X1156252Y496167D01*
G01X1100978Y484149D02*
X1117250Y500421D01*
G01D02*
Y501523D01*
G01X1118400Y499944D02*
Y502000D01*
G01X1117250Y501523D02*
X1116500Y502273D01*
G01X1118400Y502000D02*
X1117650Y502750D01*
G01X1116500Y502273D02*
Y505527D01*
G01X1117650Y502750D02*
Y505050D01*
G01X1116500Y505527D02*
X1117250Y506277D01*
G01X1117650Y505050D02*
X1118400Y505800D01*
G01X1117250Y506277D02*
Y510851D01*
G01X1118400Y505800D02*
Y511328D01*
G01X1117250Y510851D02*
X1115401Y512700D01*
G01X1118400Y511328D02*
X1114428Y515300D01*
G01X1100978Y484149D02*
X1117250Y500421D01*
G01X1118400Y499944D02*
Y502000D01*
G01X1117250Y500421D02*
Y501523D01*
G01X1118400Y502000D02*
X1117650Y502750D01*
G01X1117250Y501523D02*
X1116500Y502273D01*
G01X1117650Y502750D02*
Y505050D01*
G01X1116500Y502273D02*
Y505527D01*
G01X1117650Y505050D02*
X1118400Y505800D01*
G01X1116500Y505527D02*
X1117250Y506277D01*
G01X1118400Y505800D02*
Y511328D01*
G01X1117250Y506277D02*
Y510851D01*
G01X1118400Y511328D02*
X1114428Y515300D01*
G01X1117250Y510851D02*
X1115401Y512700D01*
G01X1096713Y468046D02*
X1098733Y470066D01*
G01X1096713Y468046D02*
X1098733Y470066D01*
G01X1096236Y469196D02*
X1097583Y470543D01*
G01X1098733Y470066D02*
Y472259D01*
G01X1097583Y470543D02*
Y471782D01*
G01X1098733Y472259D02*
X1097995Y472997D01*
G01X1097583Y471782D02*
X1096845Y472520D01*
G01X1097995Y472997D02*
Y473989D01*
G01X1096845Y472520D02*
Y474466D01*
G01X1097995Y473989D02*
X1099219Y475213D01*
G01X1096845Y474466D02*
X1098742Y476363D01*
G01X1099219Y475213D02*
X1100362D01*
G01X1098742Y476363D02*
X1100839D01*
G01X1099219Y475213D02*
X1100362D01*
G01D02*
X1101250Y474325D01*
G01X1100839Y476363D02*
X1101727Y475475D01*
G01X1101250Y474325D02*
X1102995D01*
G01X1101727Y475475D02*
X1102518D01*
G01X1102995Y474325D02*
X1104793Y476123D01*
G01X1102518Y475475D02*
X1103643Y476600D01*
G01X1104793Y476123D02*
Y478069D01*
G01X1103643Y476600D02*
Y477592D01*
G01X1104793Y478069D02*
X1104215Y478647D01*
G01X1103643Y477592D02*
X1103065Y478170D01*
G01X1104215Y478647D02*
Y479659D01*
G01X1103065Y478170D02*
Y480136D01*
G01X1104215Y479659D02*
X1122510Y497954D01*
G01X1103065Y480136D02*
X1105229Y482300D01*
G01X1104215Y479659D02*
X1122510Y497954D01*
G01X1105937Y483885D02*
X1106814D01*
G01X1104215Y479659D02*
X1122510Y497954D01*
G01X1106814Y483885D02*
X1107521Y484592D01*
G01X1104215Y479659D02*
X1122510Y497954D01*
G01X1108228Y486176D02*
X1109105D01*
G01X1104215Y479659D02*
X1122510Y497954D01*
G01X1109105Y486176D02*
X1109900Y486971D01*
G01X1104215Y479659D02*
X1122510Y497954D01*
G01X1110608Y488556D02*
X1111485D01*
G01X1104215Y479659D02*
X1122510Y497954D01*
G01X1111485Y488556D02*
X1112192Y489263D01*
G01X1104215Y479659D02*
X1122510Y497954D01*
G01X1112900Y490848D02*
X1113777D01*
G01X1104215Y479659D02*
X1122510Y497954D01*
G01X1113777Y490848D02*
X1114484Y491555D01*
G01X1104215Y479659D02*
X1122510Y497954D01*
G01X1115192Y493140D02*
X1116069D01*
G01X1104215Y479659D02*
X1122510Y497954D01*
G01X1116069Y493140D02*
X1116776Y493847D01*
G01X1104215Y479659D02*
X1122510Y497954D01*
G01X1117484Y495432D02*
X1118361D01*
G01X1104215Y479659D02*
X1122510Y497954D01*
G01X1118361Y495432D02*
X1119068Y496139D01*
G01X1104215Y479659D02*
X1122510Y497954D01*
G01X1119776Y497724D02*
X1120653D01*
G01X1104215Y479659D02*
X1122510Y497954D01*
G01X1120653Y497724D02*
X1121360Y498431D01*
G01X1122510Y497954D02*
Y512445D01*
G01X1121360Y498431D02*
Y499577D01*
G01X1122510Y497954D02*
Y512445D01*
G01X1121360Y501577D02*
Y502577D01*
G01X1122510Y497954D02*
Y512445D01*
G01X1121360Y504577D02*
Y505577D01*
G01X1122510Y497954D02*
Y512445D01*
G01X1121360Y507577D02*
Y508577D01*
G01X1122510Y497954D02*
Y512445D01*
G01X1121360Y510577D02*
Y511968D01*
G01X1122510Y512445D02*
X1119441Y515514D01*
G01X1121360Y511968D02*
X1120414Y512914D01*
G01X1096236Y469196D02*
X1097583Y470543D01*
G01X1096713Y468046D02*
X1098733Y470066D01*
G01X1097583Y470543D02*
Y471782D01*
G01X1098733Y470066D02*
Y472259D01*
G01X1097583Y471782D02*
X1096845Y472520D01*
G01X1098733Y472259D02*
X1097995Y472997D01*
G01X1096845Y472520D02*
Y474466D01*
G01X1097995Y472997D02*
Y473989D01*
G01X1096845Y474466D02*
X1098742Y476363D01*
G01X1097995Y473989D02*
X1099219Y475213D01*
G01X1098742Y476363D02*
X1100839D01*
G01D02*
X1101727Y475475D01*
G01X1099219Y475213D02*
X1100362D01*
G01X1100839Y476363D02*
X1101727Y475475D01*
G01X1100362Y475213D02*
X1101250Y474325D01*
G01X1101727Y475475D02*
X1102518D01*
G01X1101250Y474325D02*
X1102995D01*
G01X1102518Y475475D02*
X1103643Y476600D01*
G01X1102995Y474325D02*
X1104793Y476123D01*
G01X1103643Y476600D02*
Y477592D01*
G01X1104793Y476123D02*
Y478069D01*
G01X1103643Y477592D02*
X1103065Y478170D01*
G01X1104793Y478069D02*
X1104215Y478647D01*
G01X1103065Y478170D02*
Y480136D01*
G01X1104215Y478647D02*
Y479659D01*
G01X1103065Y480136D02*
X1105229Y482300D01*
G01X1105937Y483885D02*
X1106814D01*
G01D02*
X1107521Y484592D01*
G01X1108228Y486176D02*
X1109105D01*
G01D02*
X1109900Y486971D01*
G01X1110608Y488556D02*
X1111485D01*
G01D02*
X1112192Y489263D01*
G01X1112900Y490848D02*
X1113777D01*
G01D02*
X1114484Y491555D01*
G01X1115192Y493140D02*
X1116069D01*
G01D02*
X1116776Y493847D01*
G01X1117484Y495432D02*
X1118361D01*
G01D02*
X1119068Y496139D01*
G01X1119776Y497724D02*
X1120653D01*
G01D02*
X1121360Y498431D01*
G01X1104215Y479659D02*
X1122510Y497954D01*
G01X1121360Y498431D02*
Y499577D01*
G01Y501577D02*
Y502577D01*
G01Y504577D02*
Y505577D01*
G01Y507577D02*
Y508577D01*
G01Y510577D02*
Y511968D01*
G01X1122510Y497954D02*
Y512445D01*
G01X1121360Y511968D02*
X1120414Y512914D01*
G01X1122510Y512445D02*
X1119441Y515514D01*
G01X1141970Y469970D02*
X1143843D01*
G01X1142447Y468820D02*
X1144320D01*
G01X1143843Y469970D02*
X1145000Y471127D01*
G01X1146773Y472900D02*
X1147700Y473827D01*
G01X1149373Y475500D02*
X1150600Y476727D01*
G01X1152239Y478366D02*
X1153030Y479157D01*
G01X1144320Y468820D02*
X1154180Y478680D01*
G01X1153030Y479157D02*
Y492823D01*
G01X1154180Y478680D02*
Y493300D01*
G01X1153030Y492823D02*
X1152386Y493467D01*
G01X1154180Y493300D02*
X1152863Y494617D01*
G01X1143823Y465350D02*
X1147223D01*
G01D02*
X1148000Y466127D01*
G01X1149573Y467700D02*
X1150400Y468527D01*
G01X1151973Y470100D02*
X1152800Y470927D01*
G01X1154373Y472500D02*
X1156743Y474870D01*
G01D02*
Y475856D01*
G01Y477644D02*
Y480457D01*
G01D02*
X1158195Y481909D01*
G01X1158199Y485159D02*
X1156950Y486408D01*
G01Y488577D02*
X1158224Y489851D01*
G01X1159374Y493045D02*
X1156252Y496167D01*
G01X1142447Y468820D02*
X1144320D01*
G01X1142447D02*
X1144320D01*
G01X1141970Y469970D02*
X1143843D01*
G01X1144320Y468820D02*
X1154180Y478680D01*
G01X1143843Y469970D02*
X1145000Y471127D01*
G01X1144320Y468820D02*
X1154180Y478680D01*
G01X1146773Y472900D02*
X1147700Y473827D01*
G01X1144320Y468820D02*
X1154180Y478680D01*
G01X1149373Y475500D02*
X1150600Y476727D01*
G01X1144320Y468820D02*
X1154180Y478680D01*
G01X1152239Y478366D02*
X1153030Y479157D01*
G01X1154180Y478680D02*
Y493300D01*
G01X1153030Y479157D02*
Y492823D01*
G01X1154180Y493300D02*
X1152863Y494617D01*
G01X1153030Y492823D02*
X1152386Y493467D01*
G01X1143823Y465350D02*
X1147223D01*
G01D02*
X1148000Y466127D01*
G01X1149573Y467700D02*
X1150400Y468527D01*
G01X1151973Y470100D02*
X1152800Y470927D01*
G01X1154373Y472500D02*
X1156743Y474870D01*
G01D02*
Y475856D01*
G01Y477644D02*
Y480457D01*
G01D02*
X1158195Y481909D01*
G01X1158199Y485159D02*
X1156950Y486408D01*
G01Y488577D02*
X1158224Y489851D01*
G01X1159374Y493045D02*
X1156252Y496167D01*
G01X1189450Y142850D02*
Y139500D01*
G01X1190600Y141000D02*
Y139023D01*
G01X1189450Y139500D02*
X1187119Y137169D01*
G01X1190600Y139023D02*
X1188269Y136692D01*
G01X1187119Y135500D02*
Y132981D01*
G01Y137169D02*
Y135500D01*
G01X1188269Y136692D02*
Y133458D01*
G01X1187119Y132981D02*
X1189450Y130650D01*
G01X1188269Y133458D02*
X1190600Y131127D01*
G01X1189450Y130650D02*
Y129752D01*
G01X1190600Y131127D02*
Y129275D01*
G01X1189450Y129752D02*
X1188748Y129050D01*
G01X1190600Y129275D02*
X1189225Y127900D01*
G01X1188748Y129050D02*
X1186705D01*
G01X1189225Y127900D02*
X1187182D01*
G01X1186705Y129050D02*
X1185330Y127675D01*
G01X1187182Y127900D02*
X1186480Y127198D01*
G01X1185330Y127675D02*
Y124975D01*
G01X1186480Y127198D02*
Y125452D01*
G01X1185330Y124975D02*
X1186705Y123600D01*
G01X1186480Y125452D02*
X1187182Y124750D01*
G01X1186705Y123600D02*
X1188848D01*
G01X1187182Y124750D02*
X1189325D01*
G01X1188848Y123600D02*
X1189550Y122898D01*
G01X1189325Y124750D02*
X1190700Y123375D01*
G01X1189550Y122898D02*
Y121395D01*
G01X1190700Y123375D02*
Y120918D01*
G01X1189550Y121395D02*
X1188848Y120693D01*
G01X1190700Y120918D02*
X1189325Y119543D01*
G01X1188848Y120693D02*
X1186503D01*
G01X1189325Y119543D02*
X1186980D01*
G01X1186503Y120693D02*
X1185330Y119520D01*
G01X1186980Y119543D02*
X1186480Y119043D01*
G01X1185330Y119520D02*
Y115343D01*
G01X1186480Y119043D02*
Y115820D01*
G01X1185330Y115343D02*
X1186000Y114673D01*
G01X1186480Y115820D02*
X1187300Y115000D01*
G01X1170850Y161450D02*
X1189450Y142850D01*
G01X1170850Y161450D02*
X1189450Y142850D01*
G01X1170850Y161450D02*
X1189450Y142850D01*
G01X1176521Y157406D02*
X1190600Y143327D01*
G01X1189450Y142850D02*
Y139500D01*
G01X1190600Y143327D02*
Y141000D01*
G01X1194417Y135000D02*
Y119445D01*
G01X1193267Y126500D02*
Y119922D01*
G01X1194417Y119445D02*
X1192464Y117492D01*
G01X1193267Y119922D02*
X1191314Y117969D01*
G01X1192464Y117492D02*
Y116036D01*
G01X1191314Y117969D02*
Y109404D01*
G01X1183221Y157006D02*
X1183928Y156299D01*
G01X1185343Y154884D02*
X1186050Y154177D01*
G01X1187465Y152762D02*
X1194417Y145810D01*
G01X1175550Y163050D02*
X1193267Y145333D01*
G01X1194417Y145810D02*
Y135000D01*
G01X1193267Y145333D02*
Y126500D01*
G01X1188269Y136692D02*
Y133458D01*
G01X1187119Y135500D02*
Y132981D01*
G01X1188269Y133458D02*
X1190600Y131127D01*
G01X1187119Y132981D02*
X1189450Y130650D01*
G01X1190600Y131127D02*
Y129275D01*
G01X1189450Y130650D02*
Y129752D01*
G01X1190600Y129275D02*
X1189225Y127900D01*
G01X1189450Y129752D02*
X1188748Y129050D01*
G01X1189225Y127900D02*
X1187182D01*
G01X1188748Y129050D02*
X1186705D01*
G01X1187182Y127900D02*
X1186480Y127198D01*
G01X1186705Y129050D02*
X1185330Y127675D01*
G01X1186480Y127198D02*
Y125452D01*
G01X1185330Y127675D02*
Y124975D01*
G01X1186480Y125452D02*
X1187182Y124750D01*
G01X1185330Y124975D02*
X1186705Y123600D01*
G01X1187182Y124750D02*
X1189325D01*
G01X1186705Y123600D02*
X1188848D01*
G01X1189325Y124750D02*
X1190700Y123375D01*
G01X1188848Y123600D02*
X1189550Y122898D01*
G01X1190700Y123375D02*
Y120918D01*
G01X1189550Y122898D02*
Y121395D01*
G01X1190700Y120918D02*
X1189325Y119543D01*
G01X1189550Y121395D02*
X1188848Y120693D01*
G01X1189325Y119543D02*
X1186980D01*
G01X1188848Y120693D02*
X1186503D01*
G01X1186980Y119543D02*
X1186480Y119043D01*
G01X1186503Y120693D02*
X1185330Y119520D01*
G01X1186480Y119043D02*
Y115820D01*
G01X1185330Y119520D02*
Y115343D01*
G01X1186480Y115820D02*
X1187300Y115000D01*
G01X1185330Y115343D02*
X1186000Y114673D01*
G01X1176521Y157406D02*
X1190600Y143327D01*
G01X1170850Y161450D02*
X1189450Y142850D01*
G01X1190600Y141000D02*
Y139023D01*
G01Y143327D02*
Y141000D01*
G01X1189450Y142850D02*
Y139500D01*
G01X1190600Y139023D02*
X1188269Y136692D01*
G01X1189450Y139500D02*
X1187119Y137169D01*
G01X1188269Y136692D02*
Y133458D01*
G01X1187119Y137169D02*
Y135500D01*
G01X1193267Y126500D02*
Y119922D01*
G01X1194417Y135000D02*
Y119445D01*
G01X1193267Y119922D02*
X1191314Y117969D01*
G01X1194417Y119445D02*
X1192464Y117492D01*
G01X1191314Y117969D02*
Y109404D01*
G01X1192464Y117492D02*
Y116036D01*
G01X1175550Y163050D02*
X1193267Y145333D01*
G01X1175550Y163050D02*
X1193267Y145333D01*
G01X1175550Y163050D02*
X1193267Y145333D01*
G01X1175550Y163050D02*
X1193267Y145333D01*
G01X1183221Y157006D02*
X1183928Y156299D01*
G01X1175550Y163050D02*
X1193267Y145333D01*
G01X1185343Y154884D02*
X1186050Y154177D01*
G01X1175550Y163050D02*
X1193267Y145333D01*
G01X1187465Y152762D02*
X1194417Y145810D01*
G01X1193267Y145333D02*
Y126500D01*
G01X1194417Y145810D02*
Y135000D01*
G01X1189450Y142850D02*
Y139500D01*
G01X1190600Y141000D02*
Y139023D01*
G01X1189450Y139500D02*
X1187119Y137169D01*
G01X1190600Y139023D02*
X1188269Y136692D01*
G01X1187119Y135500D02*
Y132981D01*
G01Y137169D02*
Y135500D01*
G01X1188269Y136692D02*
Y133458D01*
G01X1187119Y132981D02*
X1189450Y130650D01*
G01X1188269Y133458D02*
X1190600Y131127D01*
G01X1189450Y130650D02*
Y129752D01*
G01X1190600Y131127D02*
Y129275D01*
G01X1189450Y129752D02*
X1188748Y129050D01*
G01X1190600Y129275D02*
X1189225Y127900D01*
G01X1188748Y129050D02*
X1186705D01*
G01X1189225Y127900D02*
X1187182D01*
G01X1186705Y129050D02*
X1185330Y127675D01*
G01X1187182Y127900D02*
X1186480Y127198D01*
G01X1185330Y127675D02*
Y124975D01*
G01X1186480Y127198D02*
Y125452D01*
G01X1185330Y124975D02*
X1186705Y123600D01*
G01X1186480Y125452D02*
X1187182Y124750D01*
G01X1186705Y123600D02*
X1188848D01*
G01X1187182Y124750D02*
X1189325D01*
G01X1188848Y123600D02*
X1189550Y122898D01*
G01X1189325Y124750D02*
X1190700Y123375D01*
G01X1189550Y122898D02*
Y121395D01*
G01X1190700Y123375D02*
Y120918D01*
G01X1189550Y121395D02*
X1188848Y120693D01*
G01X1190700Y120918D02*
X1189325Y119543D01*
G01X1188848Y120693D02*
X1186503D01*
G01X1189325Y119543D02*
X1186980D01*
G01X1186503Y120693D02*
X1185330Y119520D01*
G01X1186980Y119543D02*
X1186480Y119043D01*
G01X1185330Y119520D02*
Y115343D01*
G01X1186480Y119043D02*
Y115820D01*
G01X1185330Y115343D02*
X1186000Y114673D01*
G01X1186480Y115820D02*
X1187300Y115000D01*
G01X1170850Y161450D02*
X1189450Y142850D01*
G01X1170850Y161450D02*
X1189450Y142850D01*
G01X1170850Y161450D02*
X1189450Y142850D01*
G01X1176521Y157406D02*
X1190600Y143327D01*
G01X1189450Y142850D02*
Y139500D01*
G01X1190600Y143327D02*
Y141000D01*
G01X1194417Y135000D02*
Y119445D01*
G01X1193267Y126500D02*
Y119922D01*
G01X1194417Y119445D02*
X1192464Y117492D01*
G01X1193267Y119922D02*
X1191314Y117969D01*
G01X1192464Y117492D02*
Y116036D01*
G01X1191314Y117969D02*
Y109404D01*
G01X1183221Y157006D02*
X1183928Y156299D01*
G01X1185343Y154884D02*
X1186050Y154177D01*
G01X1187465Y152762D02*
X1194417Y145810D01*
G01X1175550Y163050D02*
X1193267Y145333D01*
G01X1194417Y145810D02*
Y135000D01*
G01X1193267Y145333D02*
Y126500D01*
G01X1188269Y136692D02*
Y133458D01*
G01X1187119Y135500D02*
Y132981D01*
G01X1188269Y133458D02*
X1190600Y131127D01*
G01X1187119Y132981D02*
X1189450Y130650D01*
G01X1190600Y131127D02*
Y129275D01*
G01X1189450Y130650D02*
Y129752D01*
G01X1190600Y129275D02*
X1189225Y127900D01*
G01X1189450Y129752D02*
X1188748Y129050D01*
G01X1189225Y127900D02*
X1187182D01*
G01X1188748Y129050D02*
X1186705D01*
G01X1187182Y127900D02*
X1186480Y127198D01*
G01X1186705Y129050D02*
X1185330Y127675D01*
G01X1186480Y127198D02*
Y125452D01*
G01X1185330Y127675D02*
Y124975D01*
G01X1186480Y125452D02*
X1187182Y124750D01*
G01X1185330Y124975D02*
X1186705Y123600D01*
G01X1187182Y124750D02*
X1189325D01*
G01X1186705Y123600D02*
X1188848D01*
G01X1189325Y124750D02*
X1190700Y123375D01*
G01X1188848Y123600D02*
X1189550Y122898D01*
G01X1190700Y123375D02*
Y120918D01*
G01X1189550Y122898D02*
Y121395D01*
G01X1190700Y120918D02*
X1189325Y119543D01*
G01X1189550Y121395D02*
X1188848Y120693D01*
G01X1189325Y119543D02*
X1186980D01*
G01X1188848Y120693D02*
X1186503D01*
G01X1186980Y119543D02*
X1186480Y119043D01*
G01X1186503Y120693D02*
X1185330Y119520D01*
G01X1186480Y119043D02*
Y115820D01*
G01X1185330Y119520D02*
Y115343D01*
G01X1186480Y115820D02*
X1187300Y115000D01*
G01X1185330Y115343D02*
X1186000Y114673D01*
G01X1176521Y157406D02*
X1190600Y143327D01*
G01X1170850Y161450D02*
X1189450Y142850D01*
G01X1190600Y141000D02*
Y139023D01*
G01Y143327D02*
Y141000D01*
G01X1189450Y142850D02*
Y139500D01*
G01X1190600Y139023D02*
X1188269Y136692D01*
G01X1189450Y139500D02*
X1187119Y137169D01*
G01X1188269Y136692D02*
Y133458D01*
G01X1187119Y137169D02*
Y135500D01*
G01X1193267Y126500D02*
Y119922D01*
G01X1194417Y135000D02*
Y119445D01*
G01X1193267Y119922D02*
X1191314Y117969D01*
G01X1194417Y119445D02*
X1192464Y117492D01*
G01X1191314Y117969D02*
Y109404D01*
G01X1192464Y117492D02*
Y116036D01*
G01X1175550Y163050D02*
X1193267Y145333D01*
G01X1175550Y163050D02*
X1193267Y145333D01*
G01X1175550Y163050D02*
X1193267Y145333D01*
G01X1175550Y163050D02*
X1193267Y145333D01*
G01X1183221Y157006D02*
X1183928Y156299D01*
G01X1175550Y163050D02*
X1193267Y145333D01*
G01X1185343Y154884D02*
X1186050Y154177D01*
G01X1175550Y163050D02*
X1193267Y145333D01*
G01X1187465Y152762D02*
X1194417Y145810D01*
G01X1193267Y145333D02*
Y126500D01*
G01X1194417Y145810D02*
Y135000D01*
G01X1189450Y142850D02*
Y139500D01*
G01X1190600Y141000D02*
Y139023D01*
G01X1189450Y139500D02*
X1187119Y137169D01*
G01X1190600Y139023D02*
X1188269Y136692D01*
G01X1187119Y135500D02*
Y132981D01*
G01Y137169D02*
Y135500D01*
G01X1188269Y136692D02*
Y133458D01*
G01X1187119Y132981D02*
X1189450Y130650D01*
G01X1188269Y133458D02*
X1190600Y131127D01*
G01X1189450Y130650D02*
Y129752D01*
G01X1190600Y131127D02*
Y129275D01*
G01X1189450Y129752D02*
X1188748Y129050D01*
G01X1190600Y129275D02*
X1189225Y127900D01*
G01X1188748Y129050D02*
X1186705D01*
G01X1189225Y127900D02*
X1187182D01*
G01X1186705Y129050D02*
X1185330Y127675D01*
G01X1187182Y127900D02*
X1186480Y127198D01*
G01X1185330Y127675D02*
Y124975D01*
G01X1186480Y127198D02*
Y125452D01*
G01X1185330Y124975D02*
X1186705Y123600D01*
G01X1186480Y125452D02*
X1187182Y124750D01*
G01X1186705Y123600D02*
X1188848D01*
G01X1187182Y124750D02*
X1189325D01*
G01X1188848Y123600D02*
X1189550Y122898D01*
G01X1189325Y124750D02*
X1190700Y123375D01*
G01X1189550Y122898D02*
Y121395D01*
G01X1190700Y123375D02*
Y120918D01*
G01X1189550Y121395D02*
X1188848Y120693D01*
G01X1190700Y120918D02*
X1189325Y119543D01*
G01X1188848Y120693D02*
X1186503D01*
G01X1189325Y119543D02*
X1186980D01*
G01X1186503Y120693D02*
X1185330Y119520D01*
G01X1186980Y119543D02*
X1186480Y119043D01*
G01X1185330Y119520D02*
Y115343D01*
G01X1186480Y119043D02*
Y115820D01*
G01X1185330Y115343D02*
X1186000Y114673D01*
G01X1186480Y115820D02*
X1187300Y115000D01*
G01X1170850Y161450D02*
X1189450Y142850D01*
G01X1170850Y161450D02*
X1189450Y142850D01*
G01X1170850Y161450D02*
X1189450Y142850D01*
G01X1176521Y157406D02*
X1190600Y143327D01*
G01X1189450Y142850D02*
Y139500D01*
G01X1190600Y143327D02*
Y141000D01*
G01X1194417Y135000D02*
Y119445D01*
G01X1193267Y126500D02*
Y119922D01*
G01X1194417Y119445D02*
X1192464Y117492D01*
G01X1193267Y119922D02*
X1191314Y117969D01*
G01X1192464Y117492D02*
Y116036D01*
G01X1191314Y117969D02*
Y109404D01*
G01X1183221Y157006D02*
X1183928Y156299D01*
G01X1185343Y154884D02*
X1186050Y154177D01*
G01X1187465Y152762D02*
X1194417Y145810D01*
G01X1175550Y163050D02*
X1193267Y145333D01*
G01X1194417Y145810D02*
Y135000D01*
G01X1193267Y145333D02*
Y126500D01*
G01X1188269Y136692D02*
Y133458D01*
G01X1187119Y135500D02*
Y132981D01*
G01X1188269Y133458D02*
X1190600Y131127D01*
G01X1187119Y132981D02*
X1189450Y130650D01*
G01X1190600Y131127D02*
Y129275D01*
G01X1189450Y130650D02*
Y129752D01*
G01X1190600Y129275D02*
X1189225Y127900D01*
G01X1189450Y129752D02*
X1188748Y129050D01*
G01X1189225Y127900D02*
X1187182D01*
G01X1188748Y129050D02*
X1186705D01*
G01X1187182Y127900D02*
X1186480Y127198D01*
G01X1186705Y129050D02*
X1185330Y127675D01*
G01X1186480Y127198D02*
Y125452D01*
G01X1185330Y127675D02*
Y124975D01*
G01X1186480Y125452D02*
X1187182Y124750D01*
G01X1185330Y124975D02*
X1186705Y123600D01*
G01X1187182Y124750D02*
X1189325D01*
G01X1186705Y123600D02*
X1188848D01*
G01X1189325Y124750D02*
X1190700Y123375D01*
G01X1188848Y123600D02*
X1189550Y122898D01*
G01X1190700Y123375D02*
Y120918D01*
G01X1189550Y122898D02*
Y121395D01*
G01X1190700Y120918D02*
X1189325Y119543D01*
G01X1189550Y121395D02*
X1188848Y120693D01*
G01X1189325Y119543D02*
X1186980D01*
G01X1188848Y120693D02*
X1186503D01*
G01X1186980Y119543D02*
X1186480Y119043D01*
G01X1186503Y120693D02*
X1185330Y119520D01*
G01X1186480Y119043D02*
Y115820D01*
G01X1185330Y119520D02*
Y115343D01*
G01X1186480Y115820D02*
X1187300Y115000D01*
G01X1185330Y115343D02*
X1186000Y114673D01*
G01X1176521Y157406D02*
X1190600Y143327D01*
G01X1170850Y161450D02*
X1189450Y142850D01*
G01X1190600Y141000D02*
Y139023D01*
G01Y143327D02*
Y141000D01*
G01X1189450Y142850D02*
Y139500D01*
G01X1190600Y139023D02*
X1188269Y136692D01*
G01X1189450Y139500D02*
X1187119Y137169D01*
G01X1188269Y136692D02*
Y133458D01*
G01X1187119Y137169D02*
Y135500D01*
G01X1193267Y126500D02*
Y119922D01*
G01X1194417Y135000D02*
Y119445D01*
G01X1193267Y119922D02*
X1191314Y117969D01*
G01X1194417Y119445D02*
X1192464Y117492D01*
G01X1191314Y117969D02*
Y109404D01*
G01X1192464Y117492D02*
Y116036D01*
G01X1175550Y163050D02*
X1193267Y145333D01*
G01X1175550Y163050D02*
X1193267Y145333D01*
G01X1175550Y163050D02*
X1193267Y145333D01*
G01X1175550Y163050D02*
X1193267Y145333D01*
G01X1183221Y157006D02*
X1183928Y156299D01*
G01X1175550Y163050D02*
X1193267Y145333D01*
G01X1185343Y154884D02*
X1186050Y154177D01*
G01X1175550Y163050D02*
X1193267Y145333D01*
G01X1187465Y152762D02*
X1194417Y145810D01*
G01X1193267Y145333D02*
Y126500D01*
G01X1194417Y145810D02*
Y135000D01*
G01X1170850Y164900D02*
Y161450D01*
G01X1172000Y164900D02*
Y161927D01*
G01D02*
X1172707Y161220D01*
G01X1174122Y159805D02*
X1175106Y158821D01*
G01X1176700Y164800D02*
Y163527D01*
G01X1175550Y164800D02*
Y163050D01*
G01X1176700Y163527D02*
X1177407Y162820D01*
G01X1178822Y161405D02*
X1179606Y160621D01*
G01X1181021Y159206D02*
X1181806Y158421D01*
G01X1172000Y164900D02*
Y161927D01*
G01X1170850Y164900D02*
Y161450D01*
G01X1172000Y161927D02*
X1172707Y161220D01*
G01X1174122Y159805D02*
X1175106Y158821D01*
G01X1175550Y164800D02*
Y163050D01*
G01X1176700Y164800D02*
Y163527D01*
G01D02*
X1177407Y162820D01*
G01X1178822Y161405D02*
X1179606Y160621D01*
G01X1181021Y159206D02*
X1181806Y158421D01*
G01X1170850Y164900D02*
Y161450D01*
G01X1172000Y164900D02*
Y161927D01*
G01D02*
X1172707Y161220D01*
G01X1174122Y159805D02*
X1175106Y158821D01*
G01X1176700Y164800D02*
Y163527D01*
G01X1175550Y164800D02*
Y163050D01*
G01X1176700Y163527D02*
X1177407Y162820D01*
G01X1178822Y161405D02*
X1179606Y160621D01*
G01X1181021Y159206D02*
X1181806Y158421D01*
G01X1172000Y164900D02*
Y161927D01*
G01X1170850Y164900D02*
Y161450D01*
G01X1172000Y161927D02*
X1172707Y161220D01*
G01X1174122Y159805D02*
X1175106Y158821D01*
G01X1175550Y164800D02*
Y163050D01*
G01X1176700Y164800D02*
Y163527D01*
G01D02*
X1177407Y162820D01*
G01X1178822Y161405D02*
X1179606Y160621D01*
G01X1181021Y159206D02*
X1181806Y158421D01*
G01X1170850Y164900D02*
Y161450D01*
G01X1172000Y164900D02*
Y161927D01*
G01D02*
X1172707Y161220D01*
G01X1174122Y159805D02*
X1175106Y158821D01*
G01X1176700Y164800D02*
Y163527D01*
G01X1175550Y164800D02*
Y163050D01*
G01X1176700Y163527D02*
X1177407Y162820D01*
G01X1178822Y161405D02*
X1179606Y160621D01*
G01X1181021Y159206D02*
X1181806Y158421D01*
G01X1172000Y164900D02*
Y161927D01*
G01X1170850Y164900D02*
Y161450D01*
G01X1172000Y161927D02*
X1172707Y161220D01*
G01X1174122Y159805D02*
X1175106Y158821D01*
G01X1175550Y164800D02*
Y163050D01*
G01X1176700Y164800D02*
Y163527D01*
G01D02*
X1177407Y162820D01*
G01X1178822Y161405D02*
X1179606Y160621D01*
G01X1181021Y159206D02*
X1181806Y158421D01*
G01X1189500Y480828D02*
Y449127D01*
G01D02*
X1186796Y446423D01*
G01X1185381Y445008D02*
X1184674Y444301D01*
G01X1183259Y442886D02*
X1182552Y442179D01*
G01X1181137Y440764D02*
X1180430Y440057D01*
G01X1179015Y438642D02*
X1178308Y437935D01*
G01X1176893Y436520D02*
X1176186Y435813D01*
G01X1177000Y435000D02*
X1190650Y448650D01*
G01X1189500Y480828D02*
Y449127D01*
G01X1190650Y448650D02*
Y466472D01*
G01Y448650D02*
Y466472D01*
G01X1189500Y480828D02*
Y449127D01*
G01X1177000Y435000D02*
X1190650Y448650D01*
G01X1189500Y449127D02*
X1186796Y446423D01*
G01X1177000Y435000D02*
X1190650Y448650D01*
G01X1185381Y445008D02*
X1184674Y444301D01*
G01X1177000Y435000D02*
X1190650Y448650D01*
G01X1183259Y442886D02*
X1182552Y442179D01*
G01X1177000Y435000D02*
X1190650Y448650D01*
G01X1181137Y440764D02*
X1180430Y440057D01*
G01X1177000Y435000D02*
X1190650Y448650D01*
G01X1179015Y438642D02*
X1178308Y437935D01*
G01X1177000Y435000D02*
X1190650Y448650D01*
G01X1176893Y436520D02*
X1176186Y435813D01*
G01X1179236Y432900D02*
X1179942Y433607D01*
G01X1180649Y435022D02*
X1181357D01*
G01D02*
X1182063Y435729D01*
G01X1182770Y437144D02*
X1183478D01*
G01D02*
X1184000Y437667D01*
G01D02*
X1184184Y437851D01*
G01X1184891Y439266D02*
X1185599D01*
G01D02*
X1186305Y439973D01*
G01X1187012Y441388D02*
X1187720D01*
G01D02*
X1188426Y442095D01*
G01X1189133Y443510D02*
X1189841D01*
G01D02*
X1190548Y444217D01*
G01X1191254Y445632D02*
X1191963D01*
G01D02*
X1193820Y447490D01*
G01X1180000Y432041D02*
X1194970Y447011D01*
G01X1193820Y447490D02*
Y450408D01*
G01Y452408D02*
Y453408D01*
G01Y455408D02*
Y456408D01*
G01Y458408D02*
Y459500D01*
G01Y461500D02*
Y462500D01*
G01Y464500D02*
Y465500D01*
G01X1194970Y447011D02*
Y474489D01*
G01X1180000Y432041D02*
X1194970Y447011D01*
G01X1179236Y432900D02*
X1179942Y433607D01*
G01X1180000Y432041D02*
X1194970Y447011D01*
G01X1180649Y435022D02*
X1181357D01*
G01X1180000Y432041D02*
X1194970Y447011D01*
G01X1181357Y435022D02*
X1182063Y435729D01*
G01X1180000Y432041D02*
X1194970Y447011D01*
G01X1182770Y437144D02*
X1183478D01*
G01X1180000Y432041D02*
X1194970Y447011D01*
G01X1183478Y437144D02*
X1184000Y437667D01*
G01X1180000Y432041D02*
X1194970Y447011D01*
G01X1184000Y437667D02*
X1184184Y437851D01*
G01X1180000Y432041D02*
X1194970Y447011D01*
G01X1184891Y439266D02*
X1185599D01*
G01X1180000Y432041D02*
X1194970Y447011D01*
G01X1185599Y439266D02*
X1186305Y439973D01*
G01X1180000Y432041D02*
X1194970Y447011D01*
G01X1187012Y441388D02*
X1187720D01*
G01X1180000Y432041D02*
X1194970Y447011D01*
G01X1187720Y441388D02*
X1188426Y442095D01*
G01X1180000Y432041D02*
X1194970Y447011D01*
G01X1189133Y443510D02*
X1189841D01*
G01X1180000Y432041D02*
X1194970Y447011D01*
G01X1189841Y443510D02*
X1190548Y444217D01*
G01X1180000Y432041D02*
X1194970Y447011D01*
G01X1191254Y445632D02*
X1191963D01*
G01X1180000Y432041D02*
X1194970Y447011D01*
G01X1191963Y445632D02*
X1193820Y447490D01*
G01X1194970Y447011D02*
Y474489D01*
G01X1193820Y447490D02*
Y450408D01*
G01X1194970Y447011D02*
Y474489D01*
G01X1193820Y452408D02*
Y453408D01*
G01X1194970Y447011D02*
Y474489D01*
G01X1193820Y455408D02*
Y456408D01*
G01X1194970Y447011D02*
Y474489D01*
G01X1193820Y458408D02*
Y459500D01*
G01X1194970Y447011D02*
Y474489D01*
G01X1193820Y461500D02*
Y462500D01*
G01X1194970Y447011D02*
Y474489D01*
G01X1193820Y464500D02*
Y465500D01*
G01X1194970Y447011D02*
Y474489D01*
G01Y447011D02*
Y474489D01*
G01Y447011D02*
Y474489D01*
G01X1189500Y480828D02*
Y449127D01*
G01D02*
X1186796Y446423D01*
G01X1185381Y445008D02*
X1184674Y444301D01*
G01X1183259Y442886D02*
X1182552Y442179D01*
G01X1181137Y440764D02*
X1180430Y440057D01*
G01X1179015Y438642D02*
X1178308Y437935D01*
G01X1176893Y436520D02*
X1176186Y435813D01*
G01X1177000Y435000D02*
X1190650Y448650D01*
G01X1189500Y480828D02*
Y449127D01*
G01X1190650Y448650D02*
Y466472D01*
G01X1179236Y432900D02*
X1179942Y433607D01*
G01X1180649Y435022D02*
X1181357D01*
G01D02*
X1182063Y435729D01*
G01X1182770Y437144D02*
X1183478D01*
G01D02*
X1184000Y437667D01*
G01D02*
X1184184Y437851D01*
G01X1184891Y439266D02*
X1185599D01*
G01D02*
X1186305Y439973D01*
G01X1187012Y441388D02*
X1187720D01*
G01D02*
X1188426Y442095D01*
G01X1189133Y443510D02*
X1189841D01*
G01D02*
X1190548Y444217D01*
G01X1191254Y445632D02*
X1191963D01*
G01D02*
X1193820Y447490D01*
G01X1180000Y432041D02*
X1194970Y447011D01*
G01X1193820Y447490D02*
Y450408D01*
G01Y452408D02*
Y453408D01*
G01Y455408D02*
Y456408D01*
G01Y458408D02*
Y459500D01*
G01Y461500D02*
Y462500D01*
G01Y464500D02*
Y465500D01*
G01X1194970Y447011D02*
Y474489D01*
G01X1189500Y480828D02*
Y449127D01*
G01D02*
X1186796Y446423D01*
G01X1185381Y445008D02*
X1184674Y444301D01*
G01X1183259Y442886D02*
X1182552Y442179D01*
G01X1181137Y440764D02*
X1180430Y440057D01*
G01X1179015Y438642D02*
X1178308Y437935D01*
G01X1176893Y436520D02*
X1176186Y435813D01*
G01X1177000Y435000D02*
X1190650Y448650D01*
G01X1189500Y480828D02*
Y449127D01*
G01X1190650Y448650D02*
Y466472D01*
G01X1180000Y432041D02*
X1194970Y447011D01*
G01X1179236Y432900D02*
X1179942Y433607D01*
G01X1180000Y432041D02*
X1194970Y447011D01*
G01X1180649Y435022D02*
X1181357D01*
G01X1180000Y432041D02*
X1194970Y447011D01*
G01X1181357Y435022D02*
X1182063Y435729D01*
G01X1180000Y432041D02*
X1194970Y447011D01*
G01X1182770Y437144D02*
X1183478D01*
G01X1180000Y432041D02*
X1194970Y447011D01*
G01X1183478Y437144D02*
X1184000Y437667D01*
G01X1180000Y432041D02*
X1194970Y447011D01*
G01X1184000Y437667D02*
X1184184Y437851D01*
G01X1180000Y432041D02*
X1194970Y447011D01*
G01X1184891Y439266D02*
X1185599D01*
G01X1180000Y432041D02*
X1194970Y447011D01*
G01X1185599Y439266D02*
X1186305Y439973D01*
G01X1180000Y432041D02*
X1194970Y447011D01*
G01X1187012Y441388D02*
X1187720D01*
G01X1180000Y432041D02*
X1194970Y447011D01*
G01X1187720Y441388D02*
X1188426Y442095D01*
G01X1180000Y432041D02*
X1194970Y447011D01*
G01X1189133Y443510D02*
X1189841D01*
G01X1180000Y432041D02*
X1194970Y447011D01*
G01X1189841Y443510D02*
X1190548Y444217D01*
G01X1180000Y432041D02*
X1194970Y447011D01*
G01X1191254Y445632D02*
X1191963D01*
G01X1180000Y432041D02*
X1194970Y447011D01*
G01X1191963Y445632D02*
X1193820Y447490D01*
G01X1194970Y447011D02*
Y474489D01*
G01X1193820Y447490D02*
Y450408D01*
G01X1194970Y447011D02*
Y474489D01*
G01X1193820Y452408D02*
Y453408D01*
G01X1194970Y447011D02*
Y474489D01*
G01X1193820Y455408D02*
Y456408D01*
G01X1194970Y447011D02*
Y474489D01*
G01X1193820Y458408D02*
Y459500D01*
G01X1194970Y447011D02*
Y474489D01*
G01X1193820Y461500D02*
Y462500D01*
G01X1194970Y447011D02*
Y474489D01*
G01X1193820Y464500D02*
Y465500D01*
G01X1194970Y447011D02*
Y474489D01*
G01Y447011D02*
Y474489D01*
G01Y447011D02*
Y474489D01*
G01X1190650Y448650D02*
Y466472D01*
G01X1189500Y480828D02*
Y449127D01*
G01X1177000Y435000D02*
X1190650Y448650D01*
G01X1189500Y449127D02*
X1186796Y446423D01*
G01X1177000Y435000D02*
X1190650Y448650D01*
G01X1185381Y445008D02*
X1184674Y444301D01*
G01X1177000Y435000D02*
X1190650Y448650D01*
G01X1183259Y442886D02*
X1182552Y442179D01*
G01X1177000Y435000D02*
X1190650Y448650D01*
G01X1181137Y440764D02*
X1180430Y440057D01*
G01X1177000Y435000D02*
X1190650Y448650D01*
G01X1179015Y438642D02*
X1178308Y437935D01*
G01X1177000Y435000D02*
X1190650Y448650D01*
G01X1176893Y436520D02*
X1176186Y435813D01*
G01X1179236Y432900D02*
X1179942Y433607D01*
G01X1180649Y435022D02*
X1181357D01*
G01D02*
X1182063Y435729D01*
G01X1182770Y437144D02*
X1183478D01*
G01D02*
X1184000Y437667D01*
G01D02*
X1184184Y437851D01*
G01X1184891Y439266D02*
X1185599D01*
G01D02*
X1186305Y439973D01*
G01X1187012Y441388D02*
X1187720D01*
G01D02*
X1188426Y442095D01*
G01X1189133Y443510D02*
X1189841D01*
G01D02*
X1190548Y444217D01*
G01X1191254Y445632D02*
X1191963D01*
G01D02*
X1193820Y447490D01*
G01X1180000Y432041D02*
X1194970Y447011D01*
G01X1193820Y447490D02*
Y450408D01*
G01Y452408D02*
Y453408D01*
G01Y455408D02*
Y456408D01*
G01Y458408D02*
Y459500D01*
G01Y461500D02*
Y462500D01*
G01Y464500D02*
Y465500D01*
G01X1194970Y447011D02*
Y474489D01*
G01X1190650Y466472D02*
Y480351D01*
G01X1189874Y481202D02*
X1189500Y480828D01*
G01X1190650Y480351D02*
X1191024Y480725D01*
G01X1189874Y491313D02*
Y481202D01*
G01X1191024Y480725D02*
Y491790D01*
G01X1187978Y493209D02*
X1189874Y491313D01*
G01X1191024Y491790D02*
X1189874Y492940D01*
G01X1191024Y491790D02*
X1189874Y492940D01*
G01X1187978Y493209D02*
X1189874Y491313D01*
G01X1191024Y480725D02*
Y491790D01*
G01X1189874Y491313D02*
Y481202D01*
G01X1190650Y480351D02*
X1191024Y480725D01*
G01X1189874Y481202D02*
X1189500Y480828D01*
G01X1190650Y466472D02*
Y480351D01*
G01X1157893Y474393D02*
Y479980D01*
G01D02*
X1158672Y480759D01*
G01X1158195Y481909D02*
X1159900D01*
G01X1158672Y480759D02*
X1160377D01*
G01X1159900Y481909D02*
X1160400Y482409D01*
G01X1160377Y480759D02*
X1161550Y481932D01*
G01X1160400Y482409D02*
Y484659D01*
G01X1161550Y481932D02*
Y485136D01*
G01X1160400Y484659D02*
X1159900Y485159D01*
G01X1161550Y485136D02*
X1160377Y486309D01*
G01X1159900Y485159D02*
X1158199D01*
G01X1160377Y486309D02*
X1158676D01*
G01D02*
X1158100Y486885D01*
G01X1156950Y486408D02*
Y488577D01*
G01X1158100Y486885D02*
Y488100D01*
G01D02*
X1159374Y489374D01*
G01X1158224Y489851D02*
Y492568D01*
G01X1159374Y489374D02*
Y493045D01*
G01X1158224Y492568D02*
X1157225Y493567D01*
G01X1193820Y473500D02*
Y474500D01*
G01Y476500D02*
Y478023D01*
G01X1194970Y474489D02*
Y477546D01*
G01X1193820Y478023D02*
X1194897Y479100D01*
G01X1194970Y477546D02*
X1195374Y477950D01*
G01X1194897Y479100D02*
X1196268D01*
G01X1195374Y477950D02*
X1196745D01*
G01X1196268Y479100D02*
X1196768Y479600D01*
G01X1196745Y477950D02*
X1197918Y479123D01*
G01X1196768Y479600D02*
Y481250D01*
G01X1197918Y479123D02*
Y481727D01*
G01X1196768Y481250D02*
X1196268Y481750D01*
G01X1197918Y481727D02*
X1196745Y482900D01*
G01X1196268Y481750D02*
X1195097D01*
G01X1196745Y482900D02*
X1195574D01*
G01X1195097Y481750D02*
X1193774Y483073D01*
G01X1195574Y482900D02*
X1194924Y483550D01*
G01X1193774Y483073D02*
Y485401D01*
G01X1194924Y483550D02*
Y484924D01*
G01X1193774Y485401D02*
X1195174Y486801D01*
G01X1194924Y484924D02*
X1196324Y486324D01*
G01X1195174Y486801D02*
Y487600D01*
G01Y489600D02*
Y492426D01*
G01X1196324Y486324D02*
Y492920D01*
G01X1193820Y467500D02*
Y468500D01*
G01Y470500D02*
Y471500D01*
G01Y473500D02*
Y474500D01*
G01X1157893Y474393D02*
Y479980D01*
G01Y474393D02*
Y479980D01*
G01D02*
X1158672Y480759D01*
G01D02*
X1160377D01*
G01X1158195Y481909D02*
X1159900D01*
G01X1160377Y480759D02*
X1161550Y481932D01*
G01X1159900Y481909D02*
X1160400Y482409D01*
G01X1161550Y481932D02*
Y485136D01*
G01X1160400Y482409D02*
Y484659D01*
G01X1161550Y485136D02*
X1160377Y486309D01*
G01X1160400Y484659D02*
X1159900Y485159D01*
G01X1160377Y486309D02*
X1158676D01*
G01X1159900Y485159D02*
X1158199D01*
G01X1158676Y486309D02*
X1158100Y486885D01*
G01D02*
Y488100D01*
G01X1156950Y486408D02*
Y488577D01*
G01X1158100Y488100D02*
X1159374Y489374D01*
G01D02*
Y493045D01*
G01X1158224Y489851D02*
Y492568D01*
G01D02*
X1157225Y493567D01*
G01X1193820Y467500D02*
Y468500D01*
G01Y470500D02*
Y471500D01*
G01X1194970Y474489D02*
Y477546D01*
G01X1193820Y473500D02*
Y474500D01*
G01X1194970Y474489D02*
Y477546D01*
G01X1193820Y476500D02*
Y478023D01*
G01X1194970Y477546D02*
X1195374Y477950D01*
G01X1193820Y478023D02*
X1194897Y479100D01*
G01X1195374Y477950D02*
X1196745D01*
G01X1194897Y479100D02*
X1196268D01*
G01X1196745Y477950D02*
X1197918Y479123D01*
G01X1196268Y479100D02*
X1196768Y479600D01*
G01X1197918Y479123D02*
Y481727D01*
G01X1196768Y479600D02*
Y481250D01*
G01X1197918Y481727D02*
X1196745Y482900D01*
G01X1196768Y481250D02*
X1196268Y481750D01*
G01X1196745Y482900D02*
X1195574D01*
G01X1196268Y481750D02*
X1195097D01*
G01X1195574Y482900D02*
X1194924Y483550D01*
G01X1195097Y481750D02*
X1193774Y483073D01*
G01X1194924Y483550D02*
Y484924D01*
G01X1193774Y483073D02*
Y485401D01*
G01X1194924Y484924D02*
X1196324Y486324D01*
G01X1193774Y485401D02*
X1195174Y486801D01*
G01X1196324Y486324D02*
Y492920D01*
G01X1195174Y486801D02*
Y487600D01*
G01X1196324Y486324D02*
Y492920D01*
G01X1195174Y489600D02*
Y492426D01*
G01X1157893Y474393D02*
Y479980D01*
G01Y474393D02*
Y479980D01*
G01D02*
X1158672Y480759D01*
G01D02*
X1160377D01*
G01X1158195Y481909D02*
X1159900D01*
G01X1160377Y480759D02*
X1161550Y481932D01*
G01X1159900Y481909D02*
X1160400Y482409D01*
G01X1161550Y481932D02*
Y485136D01*
G01X1160400Y482409D02*
Y484659D01*
G01X1161550Y485136D02*
X1160377Y486309D01*
G01X1160400Y484659D02*
X1159900Y485159D01*
G01X1160377Y486309D02*
X1158676D01*
G01X1159900Y485159D02*
X1158199D01*
G01X1158676Y486309D02*
X1158100Y486885D01*
G01D02*
Y488100D01*
G01X1156950Y486408D02*
Y488577D01*
G01X1158100Y488100D02*
X1159374Y489374D01*
G01D02*
Y493045D01*
G01X1158224Y489851D02*
Y492568D01*
G01D02*
X1157225Y493567D01*
G01X1157893Y474393D02*
Y479980D01*
G01D02*
X1158672Y480759D01*
G01X1158195Y481909D02*
X1159900D01*
G01X1158672Y480759D02*
X1160377D01*
G01X1159900Y481909D02*
X1160400Y482409D01*
G01X1160377Y480759D02*
X1161550Y481932D01*
G01X1160400Y482409D02*
Y484659D01*
G01X1161550Y481932D02*
Y485136D01*
G01X1160400Y484659D02*
X1159900Y485159D01*
G01X1161550Y485136D02*
X1160377Y486309D01*
G01X1159900Y485159D02*
X1158199D01*
G01X1160377Y486309D02*
X1158676D01*
G01D02*
X1158100Y486885D01*
G01X1156950Y486408D02*
Y488577D01*
G01X1158100Y486885D02*
Y488100D01*
G01D02*
X1159374Y489374D01*
G01X1158224Y489851D02*
Y492568D01*
G01X1159374Y489374D02*
Y493045D01*
G01X1158224Y492568D02*
X1157225Y493567D01*
G01X1190650Y466472D02*
Y480351D01*
G01X1189874Y481202D02*
X1189500Y480828D01*
G01X1190650Y480351D02*
X1191024Y480725D01*
G01X1189874Y491313D02*
Y481202D01*
G01X1191024Y480725D02*
Y491790D01*
G01X1187978Y493209D02*
X1189874Y491313D01*
G01X1191024Y491790D02*
X1189874Y492940D01*
G01X1193820Y473500D02*
Y474500D01*
G01Y476500D02*
Y478023D01*
G01X1194970Y474489D02*
Y477546D01*
G01X1193820Y478023D02*
X1194897Y479100D01*
G01X1194970Y477546D02*
X1195374Y477950D01*
G01X1194897Y479100D02*
X1196268D01*
G01X1195374Y477950D02*
X1196745D01*
G01X1196268Y479100D02*
X1196768Y479600D01*
G01X1196745Y477950D02*
X1197918Y479123D01*
G01X1196768Y479600D02*
Y481250D01*
G01X1197918Y479123D02*
Y481727D01*
G01X1196768Y481250D02*
X1196268Y481750D01*
G01X1197918Y481727D02*
X1196745Y482900D01*
G01X1196268Y481750D02*
X1195097D01*
G01X1196745Y482900D02*
X1195574D01*
G01X1195097Y481750D02*
X1193774Y483073D01*
G01X1195574Y482900D02*
X1194924Y483550D01*
G01X1193774Y483073D02*
Y485401D01*
G01X1194924Y483550D02*
Y484924D01*
G01X1193774Y485401D02*
X1195174Y486801D01*
G01X1194924Y484924D02*
X1196324Y486324D01*
G01X1195174Y486801D02*
Y487600D01*
G01Y489600D02*
Y492426D01*
G01X1196324Y486324D02*
Y492920D01*
G01X1193820Y467500D02*
Y468500D01*
G01Y470500D02*
Y471500D01*
G01Y473500D02*
Y474500D01*
G01X1190650Y466472D02*
Y480351D01*
G01X1189874Y481202D02*
X1189500Y480828D01*
G01X1190650Y480351D02*
X1191024Y480725D01*
G01X1189874Y491313D02*
Y481202D01*
G01X1191024Y480725D02*
Y491790D01*
G01X1187978Y493209D02*
X1189874Y491313D01*
G01X1191024Y491790D02*
X1189874Y492940D01*
G01X1193820Y467500D02*
Y468500D01*
G01Y470500D02*
Y471500D01*
G01X1194970Y474489D02*
Y477546D01*
G01X1193820Y473500D02*
Y474500D01*
G01X1194970Y474489D02*
Y477546D01*
G01X1193820Y476500D02*
Y478023D01*
G01X1194970Y477546D02*
X1195374Y477950D01*
G01X1193820Y478023D02*
X1194897Y479100D01*
G01X1195374Y477950D02*
X1196745D01*
G01X1194897Y479100D02*
X1196268D01*
G01X1196745Y477950D02*
X1197918Y479123D01*
G01X1196268Y479100D02*
X1196768Y479600D01*
G01X1197918Y479123D02*
Y481727D01*
G01X1196768Y479600D02*
Y481250D01*
G01X1197918Y481727D02*
X1196745Y482900D01*
G01X1196768Y481250D02*
X1196268Y481750D01*
G01X1196745Y482900D02*
X1195574D01*
G01X1196268Y481750D02*
X1195097D01*
G01X1195574Y482900D02*
X1194924Y483550D01*
G01X1195097Y481750D02*
X1193774Y483073D01*
G01X1194924Y483550D02*
Y484924D01*
G01X1193774Y483073D02*
Y485401D01*
G01X1194924Y484924D02*
X1196324Y486324D01*
G01X1193774Y485401D02*
X1195174Y486801D01*
G01X1196324Y486324D02*
Y492920D01*
G01X1195174Y486801D02*
Y487600D01*
G01X1196324Y486324D02*
Y492920D01*
G01X1195174Y489600D02*
Y492426D01*
G01X1191024Y491790D02*
X1189874Y492940D01*
G01X1187978Y493209D02*
X1189874Y491313D01*
G01X1191024Y480725D02*
Y491790D01*
G01X1189874Y491313D02*
Y481202D01*
G01X1190650Y480351D02*
X1191024Y480725D01*
G01X1189874Y481202D02*
X1189500Y480828D01*
G01X1190650Y466472D02*
Y480351D01*
G01X1193820Y473500D02*
Y474500D01*
G01Y476500D02*
Y478023D01*
G01X1194970Y474489D02*
Y477546D01*
G01X1193820Y478023D02*
X1194897Y479100D01*
G01X1194970Y477546D02*
X1195374Y477950D01*
G01X1194897Y479100D02*
X1196268D01*
G01X1195374Y477950D02*
X1196745D01*
G01X1196268Y479100D02*
X1196768Y479600D01*
G01X1196745Y477950D02*
X1197918Y479123D01*
G01X1196768Y479600D02*
Y481250D01*
G01X1197918Y479123D02*
Y481727D01*
G01X1196768Y481250D02*
X1196268Y481750D01*
G01X1197918Y481727D02*
X1196745Y482900D01*
G01X1196268Y481750D02*
X1195097D01*
G01X1196745Y482900D02*
X1195574D01*
G01X1195097Y481750D02*
X1193774Y483073D01*
G01X1195574Y482900D02*
X1194924Y483550D01*
G01X1193774Y483073D02*
Y485401D01*
G01X1194924Y483550D02*
Y484924D01*
G01X1193774Y485401D02*
X1195174Y486801D01*
G01X1194924Y484924D02*
X1196324Y486324D01*
G01X1195174Y486801D02*
Y487600D01*
G01Y489600D02*
Y492426D01*
G01X1196324Y486324D02*
Y492920D01*
G01X1193820Y467500D02*
Y468500D01*
G01Y470500D02*
Y471500D01*
G01Y473500D02*
Y474500D01*
G54D15*
G01X1606973Y379149D02*
X1606103D01*
G01X1606968Y377349D02*
X1605955D01*
G01X1606968D02*
X1605955D01*
G01X1606973Y379149D02*
X1606103D01*
G01X1606973D02*
X1606103D01*
G01X1606968Y377349D02*
X1605955D01*
G01X1606968D02*
X1605955D01*
G01X1606973Y379149D02*
X1606103D01*
G01X1689991Y136381D02*
X1693377D01*
G01Y138181D02*
X1689991D01*
G01X1689181Y134425D02*
G02X1689991Y136381I810J810D01*
G01Y138181D02*
G03X1687908Y133152I0J-2946D01*
G01X1692930Y130676D02*
X1689181Y134425D01*
G01X1687908Y133152D02*
X1691657Y129403D01*
G01X1694622Y130676D02*
G02X1692930I-846J846D01*
G01X1691657Y129403D02*
G03X1695895I2119J2119D01*
G01X1697228Y133282D02*
X1694622Y130676D01*
G01X1695895Y129403D02*
X1698501Y132009D01*
G01X1701468Y129042D02*
G03X1697228Y133282I-2120J2120D01*
G01X1698501Y132009D02*
G02X1700195Y130315I847J-847D01*
G01X1698542Y126116D02*
X1701468Y129042D01*
G01X1700195Y130315D02*
X1697269Y127389D01*
G01X1689012Y126116D02*
G03X1698542I4765J4765D01*
G01X1697269Y127389D02*
G02X1690285I-3492J3492D01*
G01X1678800Y136329D02*
X1679250Y135879D01*
G01D02*
X1689012Y126116D01*
G01X1690285Y127389D02*
X1680073Y137602D01*
G01X1678050Y136638D02*
G02X1678800Y136328I1J-1060D01*
G01X1680073Y137602D02*
G03X1678050Y138438I-2021J-2025D01*
G01X1670957Y136638D02*
X1678050D01*
G01Y138438D02*
X1670489D01*
G01X1678050D02*
X1670489D01*
G01X1670957Y136638D02*
X1678050D01*
G01X1680073Y137602D02*
G03X1678050Y138438I-2021J-2025D01*
G01Y136638D02*
G02X1678800Y136328I1J-1060D01*
G01X1690285Y127389D02*
X1680073Y137602D01*
G01X1678800Y136329D02*
X1679250Y135879D01*
G01X1690285Y127389D02*
X1680073Y137602D01*
G01X1679250Y135879D02*
X1689012Y126116D01*
G01X1697269Y127389D02*
G02X1690285I-3492J3492D01*
G01X1689012Y126116D02*
G03X1698542I4765J4765D01*
G01X1700195Y130315D02*
X1697269Y127389D01*
G01X1698542Y126116D02*
X1701468Y129042D01*
G01X1698501Y132009D02*
G02X1700195Y130315I847J-847D01*
G01X1701468Y129042D02*
G03X1697228Y133282I-2120J2120D01*
G01X1695895Y129403D02*
X1698501Y132009D01*
G01X1697228Y133282D02*
X1694622Y130676D01*
G01X1691657Y129403D02*
G03X1695895I2119J2119D01*
G01X1694622Y130676D02*
G02X1692930I-846J846D01*
G01X1687908Y133152D02*
X1691657Y129403D01*
G01X1692930Y130676D02*
X1689181Y134425D01*
G01X1689991Y138181D02*
G03X1687908Y133152I0J-2946D01*
G01X1689181Y134425D02*
G02X1689991Y136381I810J810D01*
G01X1693377Y138181D02*
X1689991D01*
G01Y136381D02*
X1693377D01*
G01X1677121Y130839D02*
X1669717D01*
G01X1669282Y132639D02*
X1677026D01*
G01X1669282D02*
X1677026D01*
G01X1677121Y130839D02*
X1669717D01*
G01X1669915Y122690D02*
X1675690D01*
G01X1674828Y120890D02*
X1671052D01*
G01X1674828D02*
X1671052D01*
G01X1669915Y122690D02*
X1675690D01*
G01X1689991Y136381D02*
X1693377D01*
G01Y138181D02*
X1689991D01*
G01X1689181Y134425D02*
G02X1689991Y136381I810J810D01*
G01Y138181D02*
G03X1687908Y133152I0J-2946D01*
G01X1692930Y130676D02*
X1689181Y134425D01*
G01X1687908Y133152D02*
X1691657Y129403D01*
G01X1694622Y130676D02*
G02X1692930I-846J846D01*
G01X1691657Y129403D02*
G03X1695895I2119J2119D01*
G01X1697228Y133282D02*
X1694622Y130676D01*
G01X1695895Y129403D02*
X1698501Y132009D01*
G01X1701468Y129042D02*
G03X1697228Y133282I-2120J2120D01*
G01X1698501Y132009D02*
G02X1700195Y130315I847J-847D01*
G01X1698542Y126116D02*
X1701468Y129042D01*
G01X1700195Y130315D02*
X1697269Y127389D01*
G01X1689012Y126116D02*
G03X1698542I4765J4765D01*
G01X1697269Y127389D02*
G02X1690285I-3492J3492D01*
G01X1678800Y136329D02*
X1679250Y135879D01*
G01D02*
X1689012Y126116D01*
G01X1690285Y127389D02*
X1680073Y137602D01*
G01X1678050Y136638D02*
G02X1678800Y136328I1J-1060D01*
G01X1680073Y137602D02*
G03X1678050Y138438I-2021J-2025D01*
G01X1670957Y136638D02*
X1678050D01*
G01Y138438D02*
X1670489D01*
G01X1678050D02*
X1670489D01*
G01X1670957Y136638D02*
X1678050D01*
G01X1680073Y137602D02*
G03X1678050Y138438I-2021J-2025D01*
G01Y136638D02*
G02X1678800Y136328I1J-1060D01*
G01X1690285Y127389D02*
X1680073Y137602D01*
G01X1678800Y136329D02*
X1679250Y135879D01*
G01X1690285Y127389D02*
X1680073Y137602D01*
G01X1679250Y135879D02*
X1689012Y126116D01*
G01X1697269Y127389D02*
G02X1690285I-3492J3492D01*
G01X1689012Y126116D02*
G03X1698542I4765J4765D01*
G01X1700195Y130315D02*
X1697269Y127389D01*
G01X1698542Y126116D02*
X1701468Y129042D01*
G01X1698501Y132009D02*
G02X1700195Y130315I847J-847D01*
G01X1701468Y129042D02*
G03X1697228Y133282I-2120J2120D01*
G01X1695895Y129403D02*
X1698501Y132009D01*
G01X1697228Y133282D02*
X1694622Y130676D01*
G01X1691657Y129403D02*
G03X1695895I2119J2119D01*
G01X1694622Y130676D02*
G02X1692930I-846J846D01*
G01X1687908Y133152D02*
X1691657Y129403D01*
G01X1692930Y130676D02*
X1689181Y134425D01*
G01X1689991Y138181D02*
G03X1687908Y133152I0J-2946D01*
G01X1689181Y134425D02*
G02X1689991Y136381I810J810D01*
G01X1693377Y138181D02*
X1689991D01*
G01Y136381D02*
X1693377D01*
G01X1899065Y-17720D02*
X1897196D01*
G01X1899065D02*
X1897196D01*
G01X1897726Y148378D02*
X1896614Y147266D01*
G01D02*
Y143065D01*
G01X1897726Y148378D02*
X1896614Y147266D01*
G01D02*
Y143065D01*
G01X1892039Y152289D02*
Y147536D01*
G01X1890239Y152989D02*
Y147437D01*
G01Y152989D02*
Y147437D01*
G01X1892039Y152289D02*
Y147536D01*
G01X1897726Y148378D02*
X1896614Y147266D01*
G01D02*
Y143065D01*
G01X1897726Y148378D02*
X1896614Y147266D01*
G01D02*
Y143065D01*
G01X1897472Y-15920D02*
X1899096D01*
G01X1897472D02*
X1899096D01*
G01X1899526Y153423D02*
Y147632D01*
G01X1897726Y153423D02*
Y148378D01*
G01X1899526Y147632D02*
X1898414Y146520D01*
G01D02*
Y142518D01*
G01X1897726Y153423D02*
Y148378D01*
G01X1899526Y153423D02*
Y147632D01*
G01D02*
X1898414Y146520D01*
G01D02*
Y142518D01*
G01X1899526Y153423D02*
Y147632D01*
G01X1897726Y153423D02*
Y148378D01*
G01X1899526Y147632D02*
X1898414Y146520D01*
G01D02*
Y142518D01*
G01X1897726Y153423D02*
Y148378D01*
G01X1899526Y153423D02*
Y147632D01*
G01D02*
X1898414Y146520D01*
G01D02*
Y142518D01*
M02*
